# Lightning_PDPB_SI constraints.xls — Net Rule by Layer (si-constraints)
| Project Name: 15669-1 |  |  |  |  |  |  |  |  |  |  |  |  |  |  |  |  |  |
| Project Path: C:\Users\<user>\Desktop\OCP\PDPB\15669-1_20161114-0932.db |  |  |  |  |  |  |  |  |  |  |  |  |  |  |  |  |  |
| Net Name | Group Name | Type | Layer | T_W(X) | P-P | P-V | P-T | V-V | V-T | T_T(Y) | P-F | V-F | T-F | F-F | T_T(Z) | Ohm | Ref Layer |
| ATTN_LED_DR0_AND | 50OHM_Y12MIL | BUS | 1 | 6.75 | 5 | 10 | 5 | 14 | 6 | 15 | 12 | 12 | 12 | 12 |  | 50 Ohms-3 | TOP=L2:L3=L2/L4:L6=L5/L7:BOTTOM=L7 |
| ATTN_LED_DR0_AND | 50OHM_Y12MIL | BUS | 2 | 6 | 5 | 10 | 5 | 14 | 6 | 15 | 12 | 12 | 12 | 12 |  | 50 Ohms-3 | TOP=L2:L3=L2/L4:L6=L5/L7:BOTTOM=L7 |
| ATTN_LED_DR0_AND | 50OHM_Y12MIL | BUS | 3 | 6 | 5 | 10 | 5 | 14 | 6 | 15 | 12 | 12 | 12 | 12 |  | 50 Ohms-3 | TOP=L2:L3=L2/L4:L6=L5/L7:BOTTOM=L7 |
| ATTN_LED_DR0_AND | 50OHM_Y12MIL | BUS | 4 | 6 | 5 | 10 | 5 | 14 | 6 | 15 | 12 | 12 | 12 | 12 |  | 50 Ohms-3 | TOP=L2:L3=L2/L4:L6=L5/L7:BOTTOM=L7 |
| ATTN_LED_DR0_AND | 50OHM_Y12MIL | BUS | 5 | 6 | 5 | 10 | 5 | 14 | 6 | 15 | 12 | 12 | 12 | 12 |  | 50 Ohms-3 | TOP=L2:L3=L2/L4:L6=L5/L7:BOTTOM=L7 |
| ATTN_LED_DR0_AND | 50OHM_Y12MIL | BUS | 6 | 6 | 5 | 10 | 5 | 14 | 6 | 15 | 12 | 12 | 12 | 12 |  | 50 Ohms-3 | TOP=L2:L3=L2/L4:L6=L5/L7:BOTTOM=L7 |
| ATTN_LED_DR0_AND | 50OHM_Y12MIL | BUS | 7 | 6 | 5 | 10 | 5 | 14 | 6 | 15 | 12 | 12 | 12 | 12 |  | 50 Ohms-3 | TOP=L2:L3=L2/L4:L6=L5/L7:BOTTOM=L7 |
| ATTN_LED_DR0_AND | 50OHM_Y12MIL | BUS | 8 | 6.75 | 5 | 10 | 5 | 14 | 6 | 15 | 12 | 12 | 12 | 12 |  | 50 Ohms-3 | TOP=L2:L3=L2/L4:L6=L5/L7:BOTTOM=L7 |
| ATTN_LED_DR0_AND_R | 50OHM_Y12MIL | BUS | 1 | 6.75 | 5 | 10 | 5 | 14 | 6 | 15 | 12 | 12 | 12 | 12 |  | 50 Ohms-3 | TOP=L2:L3=L2/L4:L6=L5/L7:BOTTOM=L7 |
| ATTN_LED_DR0_AND_R | 50OHM_Y12MIL | BUS | 2 | 6 | 5 | 10 | 5 | 14 | 6 | 15 | 12 | 12 | 12 | 12 |  | 50 Ohms-3 | TOP=L2:L3=L2/L4:L6=L5/L7:BOTTOM=L7 |
| ATTN_LED_DR0_AND_R | 50OHM_Y12MIL | BUS | 3 | 6 | 5 | 10 | 5 | 14 | 6 | 15 | 12 | 12 | 12 | 12 |  | 50 Ohms-3 | TOP=L2:L3=L2/L4:L6=L5/L7:BOTTOM=L7 |
| ATTN_LED_DR0_AND_R | 50OHM_Y12MIL | BUS | 4 | 6 | 5 | 10 | 5 | 14 | 6 | 15 | 12 | 12 | 12 | 12 |  | 50 Ohms-3 | TOP=L2:L3=L2/L4:L6=L5/L7:BOTTOM=L7 |
| ATTN_LED_DR0_AND_R | 50OHM_Y12MIL | BUS | 5 | 6 | 5 | 10 | 5 | 14 | 6 | 15 | 12 | 12 | 12 | 12 |  | 50 Ohms-3 | TOP=L2:L3=L2/L4:L6=L5/L7:BOTTOM=L7 |
| ATTN_LED_DR0_AND_R | 50OHM_Y12MIL | BUS | 6 | 6 | 5 | 10 | 5 | 14 | 6 | 15 | 12 | 12 | 12 | 12 |  | 50 Ohms-3 | TOP=L2:L3=L2/L4:L6=L5/L7:BOTTOM=L7 |
| ATTN_LED_DR0_AND_R | 50OHM_Y12MIL | BUS | 7 | 6 | 5 | 10 | 5 | 14 | 6 | 15 | 12 | 12 | 12 | 12 |  | 50 Ohms-3 | TOP=L2:L3=L2/L4:L6=L5/L7:BOTTOM=L7 |
| ATTN_LED_DR0_AND_R | 50OHM_Y12MIL | BUS | 8 | 6.75 | 5 | 10 | 5 | 14 | 6 | 15 | 12 | 12 | 12 | 12 |  | 50 Ohms-3 | TOP=L2:L3=L2/L4:L6=L5/L7:BOTTOM=L7 |
| ATTN_LED_DR0_MOS_N | 50OHM_Y12MIL | BUS | 1 | 6.75 | 5 | 10 | 5 | 14 | 6 | 15 | 12 | 12 | 12 | 12 |  | 50 Ohms-3 | TOP=L2:L3=L2/L4:L6=L5/L7:BOTTOM=L7 |
| ATTN_LED_DR0_MOS_N | 50OHM_Y12MIL | BUS | 2 | 6 | 5 | 10 | 5 | 14 | 6 | 15 | 12 | 12 | 12 | 12 |  | 50 Ohms-3 | TOP=L2:L3=L2/L4:L6=L5/L7:BOTTOM=L7 |
| ATTN_LED_DR0_MOS_N | 50OHM_Y12MIL | BUS | 3 | 6 | 5 | 10 | 5 | 14 | 6 | 15 | 12 | 12 | 12 | 12 |  | 50 Ohms-3 | TOP=L2:L3=L2/L4:L6=L5/L7:BOTTOM=L7 |
| ATTN_LED_DR0_MOS_N | 50OHM_Y12MIL | BUS | 4 | 6 | 5 | 10 | 5 | 14 | 6 | 15 | 12 | 12 | 12 | 12 |  | 50 Ohms-3 | TOP=L2:L3=L2/L4:L6=L5/L7:BOTTOM=L7 |
| ATTN_LED_DR0_MOS_N | 50OHM_Y12MIL | BUS | 5 | 6 | 5 | 10 | 5 | 14 | 6 | 15 | 12 | 12 | 12 | 12 |  | 50 Ohms-3 | TOP=L2:L3=L2/L4:L6=L5/L7:BOTTOM=L7 |
| ATTN_LED_DR0_MOS_N | 50OHM_Y12MIL | BUS | 6 | 6 | 5 | 10 | 5 | 14 | 6 | 15 | 12 | 12 | 12 | 12 |  | 50 Ohms-3 | TOP=L2:L3=L2/L4:L6=L5/L7:BOTTOM=L7 |
| ATTN_LED_DR0_MOS_N | 50OHM_Y12MIL | BUS | 7 | 6 | 5 | 10 | 5 | 14 | 6 | 15 | 12 | 12 | 12 | 12 |  | 50 Ohms-3 | TOP=L2:L3=L2/L4:L6=L5/L7:BOTTOM=L7 |
| ATTN_LED_DR0_MOS_N | 50OHM_Y12MIL | BUS | 8 | 6.75 | 5 | 10 | 5 | 14 | 6 | 15 | 12 | 12 | 12 | 12 |  | 50 Ohms-3 | TOP=L2:L3=L2/L4:L6=L5/L7:BOTTOM=L7 |
| ATTN_LED_DR0_N | 50OHM_Y12MIL | BUS | 1 | 6.75 | 5 | 10 | 5 | 14 | 6 | 15 | 12 | 12 | 12 | 12 |  | 50 Ohms-3 | TOP=L2:L3=L2/L4:L6=L5/L7:BOTTOM=L7 |
| ATTN_LED_DR0_N | 50OHM_Y12MIL | BUS | 2 | 6 | 5 | 10 | 5 | 14 | 6 | 15 | 12 | 12 | 12 | 12 |  | 50 Ohms-3 | TOP=L2:L3=L2/L4:L6=L5/L7:BOTTOM=L7 |
| ATTN_LED_DR0_N | 50OHM_Y12MIL | BUS | 3 | 6 | 5 | 10 | 5 | 14 | 6 | 15 | 12 | 12 | 12 | 12 |  | 50 Ohms-3 | TOP=L2:L3=L2/L4:L6=L5/L7:BOTTOM=L7 |
| ATTN_LED_DR0_N | 50OHM_Y12MIL | BUS | 4 | 6 | 5 | 10 | 5 | 14 | 6 | 15 | 12 | 12 | 12 | 12 |  | 50 Ohms-3 | TOP=L2:L3=L2/L4:L6=L5/L7:BOTTOM=L7 |
| ATTN_LED_DR0_N | 50OHM_Y12MIL | BUS | 5 | 6 | 5 | 10 | 5 | 14 | 6 | 15 | 12 | 12 | 12 | 12 |  | 50 Ohms-3 | TOP=L2:L3=L2/L4:L6=L5/L7:BOTTOM=L7 |
| ATTN_LED_DR0_N | 50OHM_Y12MIL | BUS | 6 | 6 | 5 | 10 | 5 | 14 | 6 | 15 | 12 | 12 | 12 | 12 |  | 50 Ohms-3 | TOP=L2:L3=L2/L4:L6=L5/L7:BOTTOM=L7 |
| ATTN_LED_DR0_N | 50OHM_Y12MIL | BUS | 7 | 6 | 5 | 10 | 5 | 14 | 6 | 15 | 12 | 12 | 12 | 12 |  | 50 Ohms-3 | TOP=L2:L3=L2/L4:L6=L5/L7:BOTTOM=L7 |
| ATTN_LED_DR0_N | 50OHM_Y12MIL | BUS | 8 | 6.75 | 5 | 10 | 5 | 14 | 6 | 15 | 12 | 12 | 12 | 12 |  | 50 Ohms-3 | TOP=L2:L3=L2/L4:L6=L5/L7:BOTTOM=L7 |
| ATTN_LED_DR0_R | 50OHM_Y12MIL | BUS | 1 | 6.75 | 5 | 10 | 5 | 14 | 6 | 15 | 12 | 12 | 12 | 12 |  | 50 Ohms-3 | TOP=L2:L3=L2/L4:L6=L5/L7:BOTTOM=L7 |
| ATTN_LED_DR0_R | 50OHM_Y12MIL | BUS | 2 | 6 | 5 | 10 | 5 | 14 | 6 | 15 | 12 | 12 | 12 | 12 |  | 50 Ohms-3 | TOP=L2:L3=L2/L4:L6=L5/L7:BOTTOM=L7 |
| ATTN_LED_DR0_R | 50OHM_Y12MIL | BUS | 3 | 6 | 5 | 10 | 5 | 14 | 6 | 15 | 12 | 12 | 12 | 12 |  | 50 Ohms-3 | TOP=L2:L3=L2/L4:L6=L5/L7:BOTTOM=L7 |
| ATTN_LED_DR0_R | 50OHM_Y12MIL | BUS | 4 | 6 | 5 | 10 | 5 | 14 | 6 | 15 | 12 | 12 | 12 | 12 |  | 50 Ohms-3 | TOP=L2:L3=L2/L4:L6=L5/L7:BOTTOM=L7 |
| ATTN_LED_DR0_R | 50OHM_Y12MIL | BUS | 5 | 6 | 5 | 10 | 5 | 14 | 6 | 15 | 12 | 12 | 12 | 12 |  | 50 Ohms-3 | TOP=L2:L3=L2/L4:L6=L5/L7:BOTTOM=L7 |
| ATTN_LED_DR0_R | 50OHM_Y12MIL | BUS | 6 | 6 | 5 | 10 | 5 | 14 | 6 | 15 | 12 | 12 | 12 | 12 |  | 50 Ohms-3 | TOP=L2:L3=L2/L4:L6=L5/L7:BOTTOM=L7 |
| ATTN_LED_DR0_R | 50OHM_Y12MIL | BUS | 7 | 6 | 5 | 10 | 5 | 14 | 6 | 15 | 12 | 12 | 12 | 12 |  | 50 Ohms-3 | TOP=L2:L3=L2/L4:L6=L5/L7:BOTTOM=L7 |
| ATTN_LED_DR0_R | 50OHM_Y12MIL | BUS | 8 | 6.75 | 5 | 10 | 5 | 14 | 6 | 15 | 12 | 12 | 12 | 12 |  | 50 Ohms-3 | TOP=L2:L3=L2/L4:L6=L5/L7:BOTTOM=L7 |
| ATTN_LED_DR1_AND | 50OHM_Y12MIL | BUS | 1 | 6.75 | 5 | 10 | 5 | 14 | 6 | 15 | 12 | 12 | 12 | 12 |  | 50 Ohms-3 | TOP=L2:L3=L2/L4:L6=L5/L7:BOTTOM=L7 |
| ATTN_LED_DR1_AND | 50OHM_Y12MIL | BUS | 2 | 6 | 5 | 10 | 5 | 14 | 6 | 15 | 12 | 12 | 12 | 12 |  | 50 Ohms-3 | TOP=L2:L3=L2/L4:L6=L5/L7:BOTTOM=L7 |
| ATTN_LED_DR1_AND | 50OHM_Y12MIL | BUS | 3 | 6 | 5 | 10 | 5 | 14 | 6 | 15 | 12 | 12 | 12 | 12 |  | 50 Ohms-3 | TOP=L2:L3=L2/L4:L6=L5/L7:BOTTOM=L7 |
| ATTN_LED_DR1_AND | 50OHM_Y12MIL | BUS | 4 | 6 | 5 | 10 | 5 | 14 | 6 | 15 | 12 | 12 | 12 | 12 |  | 50 Ohms-3 | TOP=L2:L3=L2/L4:L6=L5/L7:BOTTOM=L7 |
| ATTN_LED_DR1_AND | 50OHM_Y12MIL | BUS | 5 | 6 | 5 | 10 | 5 | 14 | 6 | 15 | 12 | 12 | 12 | 12 |  | 50 Ohms-3 | TOP=L2:L3=L2/L4:L6=L5/L7:BOTTOM=L7 |
| ATTN_LED_DR1_AND | 50OHM_Y12MIL | BUS | 6 | 6 | 5 | 10 | 5 | 14 | 6 | 15 | 12 | 12 | 12 | 12 |  | 50 Ohms-3 | TOP=L2:L3=L2/L4:L6=L5/L7:BOTTOM=L7 |
| ATTN_LED_DR1_AND | 50OHM_Y12MIL | BUS | 7 | 6 | 5 | 10 | 5 | 14 | 6 | 15 | 12 | 12 | 12 | 12 |  | 50 Ohms-3 | TOP=L2:L3=L2/L4:L6=L5/L7:BOTTOM=L7 |
| ATTN_LED_DR1_AND | 50OHM_Y12MIL | BUS | 8 | 6.75 | 5 | 10 | 5 | 14 | 6 | 15 | 12 | 12 | 12 | 12 |  | 50 Ohms-3 | TOP=L2:L3=L2/L4:L6=L5/L7:BOTTOM=L7 |
| ATTN_LED_DR1_AND_R | 50OHM_Y12MIL | BUS | 1 | 6.75 | 5 | 10 | 5 | 14 | 6 | 15 | 12 | 12 | 12 | 12 |  | 50 Ohms-3 | TOP=L2:L3=L2/L4:L6=L5/L7:BOTTOM=L7 |
| ATTN_LED_DR1_AND_R | 50OHM_Y12MIL | BUS | 2 | 6 | 5 | 10 | 5 | 14 | 6 | 15 | 12 | 12 | 12 | 12 |  | 50 Ohms-3 | TOP=L2:L3=L2/L4:L6=L5/L7:BOTTOM=L7 |
| ATTN_LED_DR1_AND_R | 50OHM_Y12MIL | BUS | 3 | 6 | 5 | 10 | 5 | 14 | 6 | 15 | 12 | 12 | 12 | 12 |  | 50 Ohms-3 | TOP=L2:L3=L2/L4:L6=L5/L7:BOTTOM=L7 |
| ATTN_LED_DR1_AND_R | 50OHM_Y12MIL | BUS | 4 | 6 | 5 | 10 | 5 | 14 | 6 | 15 | 12 | 12 | 12 | 12 |  | 50 Ohms-3 | TOP=L2:L3=L2/L4:L6=L5/L7:BOTTOM=L7 |
| ATTN_LED_DR1_AND_R | 50OHM_Y12MIL | BUS | 5 | 6 | 5 | 10 | 5 | 14 | 6 | 15 | 12 | 12 | 12 | 12 |  | 50 Ohms-3 | TOP=L2:L3=L2/L4:L6=L5/L7:BOTTOM=L7 |
| ATTN_LED_DR1_AND_R | 50OHM_Y12MIL | BUS | 6 | 6 | 5 | 10 | 5 | 14 | 6 | 15 | 12 | 12 | 12 | 12 |  | 50 Ohms-3 | TOP=L2:L3=L2/L4:L6=L5/L7:BOTTOM=L7 |
| ATTN_LED_DR1_AND_R | 50OHM_Y12MIL | BUS | 7 | 6 | 5 | 10 | 5 | 14 | 6 | 15 | 12 | 12 | 12 | 12 |  | 50 Ohms-3 | TOP=L2:L3=L2/L4:L6=L5/L7:BOTTOM=L7 |
| ATTN_LED_DR1_AND_R | 50OHM_Y12MIL | BUS | 8 | 6.75 | 5 | 10 | 5 | 14 | 6 | 15 | 12 | 12 | 12 | 12 |  | 50 Ohms-3 | TOP=L2:L3=L2/L4:L6=L5/L7:BOTTOM=L7 |
| ATTN_LED_DR1_MOS_N | 50OHM_Y12MIL | BUS | 1 | 6.75 | 5 | 10 | 5 | 14 | 6 | 15 | 12 | 12 | 12 | 12 |  | 50 Ohms-3 | TOP=L2:L3=L2/L4:L6=L5/L7:BOTTOM=L7 |
| ATTN_LED_DR1_MOS_N | 50OHM_Y12MIL | BUS | 2 | 6 | 5 | 10 | 5 | 14 | 6 | 15 | 12 | 12 | 12 | 12 |  | 50 Ohms-3 | TOP=L2:L3=L2/L4:L6=L5/L7:BOTTOM=L7 |
| ATTN_LED_DR1_MOS_N | 50OHM_Y12MIL | BUS | 3 | 6 | 5 | 10 | 5 | 14 | 6 | 15 | 12 | 12 | 12 | 12 |  | 50 Ohms-3 | TOP=L2:L3=L2/L4:L6=L5/L7:BOTTOM=L7 |
| ATTN_LED_DR1_MOS_N | 50OHM_Y12MIL | BUS | 4 | 6 | 5 | 10 | 5 | 14 | 6 | 15 | 12 | 12 | 12 | 12 |  | 50 Ohms-3 | TOP=L2:L3=L2/L4:L6=L5/L7:BOTTOM=L7 |
| ATTN_LED_DR1_MOS_N | 50OHM_Y12MIL | BUS | 5 | 6 | 5 | 10 | 5 | 14 | 6 | 15 | 12 | 12 | 12 | 12 |  | 50 Ohms-3 | TOP=L2:L3=L2/L4:L6=L5/L7:BOTTOM=L7 |
| ATTN_LED_DR1_MOS_N | 50OHM_Y12MIL | BUS | 6 | 6 | 5 | 10 | 5 | 14 | 6 | 15 | 12 | 12 | 12 | 12 |  | 50 Ohms-3 | TOP=L2:L3=L2/L4:L6=L5/L7:BOTTOM=L7 |
| ATTN_LED_DR1_MOS_N | 50OHM_Y12MIL | BUS | 7 | 6 | 5 | 10 | 5 | 14 | 6 | 15 | 12 | 12 | 12 | 12 |  | 50 Ohms-3 | TOP=L2:L3=L2/L4:L6=L5/L7:BOTTOM=L7 |
| ATTN_LED_DR1_MOS_N | 50OHM_Y12MIL | BUS | 8 | 6.75 | 5 | 10 | 5 | 14 | 6 | 15 | 12 | 12 | 12 | 12 |  | 50 Ohms-3 | TOP=L2:L3=L2/L4:L6=L5/L7:BOTTOM=L7 |
| ATTN_LED_DR1_N | 50OHM_Y12MIL | BUS | 1 | 6.75 | 5 | 10 | 5 | 14 | 6 | 15 | 12 | 12 | 12 | 12 |  | 50 Ohms-3 | TOP=L2:L3=L2/L4:L6=L5/L7:BOTTOM=L7 |
| ATTN_LED_DR1_N | 50OHM_Y12MIL | BUS | 2 | 6 | 5 | 10 | 5 | 14 | 6 | 15 | 12 | 12 | 12 | 12 |  | 50 Ohms-3 | TOP=L2:L3=L2/L4:L6=L5/L7:BOTTOM=L7 |
| ATTN_LED_DR1_N | 50OHM_Y12MIL | BUS | 3 | 6 | 5 | 10 | 5 | 14 | 6 | 15 | 12 | 12 | 12 | 12 |  | 50 Ohms-3 | TOP=L2:L3=L2/L4:L6=L5/L7:BOTTOM=L7 |
| ATTN_LED_DR1_N | 50OHM_Y12MIL | BUS | 4 | 6 | 5 | 10 | 5 | 14 | 6 | 15 | 12 | 12 | 12 | 12 |  | 50 Ohms-3 | TOP=L2:L3=L2/L4:L6=L5/L7:BOTTOM=L7 |
| ATTN_LED_DR1_N | 50OHM_Y12MIL | BUS | 5 | 6 | 5 | 10 | 5 | 14 | 6 | 15 | 12 | 12 | 12 | 12 |  | 50 Ohms-3 | TOP=L2:L3=L2/L4:L6=L5/L7:BOTTOM=L7 |
| ATTN_LED_DR1_N | 50OHM_Y12MIL | BUS | 6 | 6 | 5 | 10 | 5 | 14 | 6 | 15 | 12 | 12 | 12 | 12 |  | 50 Ohms-3 | TOP=L2:L3=L2/L4:L6=L5/L7:BOTTOM=L7 |
| ATTN_LED_DR1_N | 50OHM_Y12MIL | BUS | 7 | 6 | 5 | 10 | 5 | 14 | 6 | 15 | 12 | 12 | 12 | 12 |  | 50 Ohms-3 | TOP=L2:L3=L2/L4:L6=L5/L7:BOTTOM=L7 |
| ATTN_LED_DR1_N | 50OHM_Y12MIL | BUS | 8 | 6.75 | 5 | 10 | 5 | 14 | 6 | 15 | 12 | 12 | 12 | 12 |  | 50 Ohms-3 | TOP=L2:L3=L2/L4:L6=L5/L7:BOTTOM=L7 |
| ATTN_LED_DR1_R | 50OHM_Y12MIL | BUS | 1 | 6.75 | 5 | 10 | 5 | 14 | 6 | 15 | 12 | 12 | 12 | 12 |  | 50 Ohms-3 | TOP=L2:L3=L2/L4:L6=L5/L7:BOTTOM=L7 |
| ATTN_LED_DR1_R | 50OHM_Y12MIL | BUS | 2 | 6 | 5 | 10 | 5 | 14 | 6 | 15 | 12 | 12 | 12 | 12 |  | 50 Ohms-3 | TOP=L2:L3=L2/L4:L6=L5/L7:BOTTOM=L7 |
| ATTN_LED_DR1_R | 50OHM_Y12MIL | BUS | 3 | 6 | 5 | 10 | 5 | 14 | 6 | 15 | 12 | 12 | 12 | 12 |  | 50 Ohms-3 | TOP=L2:L3=L2/L4:L6=L5/L7:BOTTOM=L7 |
| ATTN_LED_DR1_R | 50OHM_Y12MIL | BUS | 4 | 6 | 5 | 10 | 5 | 14 | 6 | 15 | 12 | 12 | 12 | 12 |  | 50 Ohms-3 | TOP=L2:L3=L2/L4:L6=L5/L7:BOTTOM=L7 |
| ATTN_LED_DR1_R | 50OHM_Y12MIL | BUS | 5 | 6 | 5 | 10 | 5 | 14 | 6 | 15 | 12 | 12 | 12 | 12 |  | 50 Ohms-3 | TOP=L2:L3=L2/L4:L6=L5/L7:BOTTOM=L7 |
| ATTN_LED_DR1_R | 50OHM_Y12MIL | BUS | 6 | 6 | 5 | 10 | 5 | 14 | 6 | 15 | 12 | 12 | 12 | 12 |  | 50 Ohms-3 | TOP=L2:L3=L2/L4:L6=L5/L7:BOTTOM=L7 |
| ATTN_LED_DR1_R | 50OHM_Y12MIL | BUS | 7 | 6 | 5 | 10 | 5 | 14 | 6 | 15 | 12 | 12 | 12 | 12 |  | 50 Ohms-3 | TOP=L2:L3=L2/L4:L6=L5/L7:BOTTOM=L7 |
| ATTN_LED_DR1_R | 50OHM_Y12MIL | BUS | 8 | 6.75 | 5 | 10 | 5 | 14 | 6 | 15 | 12 | 12 | 12 | 12 |  | 50 Ohms-3 | TOP=L2:L3=L2/L4:L6=L5/L7:BOTTOM=L7 |
| ATTN_LED_DR10_AND | 50OHM_Y12MIL | BUS | 1 | 6.75 | 5 | 10 | 5 | 14 | 6 | 15 | 12 | 12 | 12 | 12 |  | 50 Ohms-3 | TOP=L2:L3=L2/L4:L6=L5/L7:BOTTOM=L7 |
| ATTN_LED_DR10_AND | 50OHM_Y12MIL | BUS | 2 | 6 | 5 | 10 | 5 | 14 | 6 | 15 | 12 | 12 | 12 | 12 |  | 50 Ohms-3 | TOP=L2:L3=L2/L4:L6=L5/L7:BOTTOM=L7 |
| ATTN_LED_DR10_AND | 50OHM_Y12MIL | BUS | 3 | 6 | 5 | 10 | 5 | 14 | 6 | 15 | 12 | 12 | 12 | 12 |  | 50 Ohms-3 | TOP=L2:L3=L2/L4:L6=L5/L7:BOTTOM=L7 |
| ATTN_LED_DR10_AND | 50OHM_Y12MIL | BUS | 4 | 6 | 5 | 10 | 5 | 14 | 6 | 15 | 12 | 12 | 12 | 12 |  | 50 Ohms-3 | TOP=L2:L3=L2/L4:L6=L5/L7:BOTTOM=L7 |
| ATTN_LED_DR10_AND | 50OHM_Y12MIL | BUS | 5 | 6 | 5 | 10 | 5 | 14 | 6 | 15 | 12 | 12 | 12 | 12 |  | 50 Ohms-3 | TOP=L2:L3=L2/L4:L6=L5/L7:BOTTOM=L7 |
| ATTN_LED_DR10_AND | 50OHM_Y12MIL | BUS | 6 | 6 | 5 | 10 | 5 | 14 | 6 | 15 | 12 | 12 | 12 | 12 |  | 50 Ohms-3 | TOP=L2:L3=L2/L4:L6=L5/L7:BOTTOM=L7 |
| ATTN_LED_DR10_AND | 50OHM_Y12MIL | BUS | 7 | 6 | 5 | 10 | 5 | 14 | 6 | 15 | 12 | 12 | 12 | 12 |  | 50 Ohms-3 | TOP=L2:L3=L2/L4:L6=L5/L7:BOTTOM=L7 |
| ATTN_LED_DR10_AND | 50OHM_Y12MIL | BUS | 8 | 6.75 | 5 | 10 | 5 | 14 | 6 | 15 | 12 | 12 | 12 | 12 |  | 50 Ohms-3 | TOP=L2:L3=L2/L4:L6=L5/L7:BOTTOM=L7 |
| ATTN_LED_DR10_AND_R | 50OHM_Y12MIL | BUS | 1 | 6.75 | 5 | 10 | 5 | 14 | 6 | 15 | 12 | 12 | 12 | 12 |  | 50 Ohms-3 | TOP=L2:L3=L2/L4:L6=L5/L7:BOTTOM=L7 |
| ATTN_LED_DR10_AND_R | 50OHM_Y12MIL | BUS | 2 | 6 | 5 | 10 | 5 | 14 | 6 | 15 | 12 | 12 | 12 | 12 |  | 50 Ohms-3 | TOP=L2:L3=L2/L4:L6=L5/L7:BOTTOM=L7 |
| ATTN_LED_DR10_AND_R | 50OHM_Y12MIL | BUS | 3 | 6 | 5 | 10 | 5 | 14 | 6 | 15 | 12 | 12 | 12 | 12 |  | 50 Ohms-3 | TOP=L2:L3=L2/L4:L6=L5/L7:BOTTOM=L7 |
| ATTN_LED_DR10_AND_R | 50OHM_Y12MIL | BUS | 4 | 6 | 5 | 10 | 5 | 14 | 6 | 15 | 12 | 12 | 12 | 12 |  | 50 Ohms-3 | TOP=L2:L3=L2/L4:L6=L5/L7:BOTTOM=L7 |
| ATTN_LED_DR10_AND_R | 50OHM_Y12MIL | BUS | 5 | 6 | 5 | 10 | 5 | 14 | 6 | 15 | 12 | 12 | 12 | 12 |  | 50 Ohms-3 | TOP=L2:L3=L2/L4:L6=L5/L7:BOTTOM=L7 |
| ATTN_LED_DR10_AND_R | 50OHM_Y12MIL | BUS | 6 | 6 | 5 | 10 | 5 | 14 | 6 | 15 | 12 | 12 | 12 | 12 |  | 50 Ohms-3 | TOP=L2:L3=L2/L4:L6=L5/L7:BOTTOM=L7 |
| ATTN_LED_DR10_AND_R | 50OHM_Y12MIL | BUS | 7 | 6 | 5 | 10 | 5 | 14 | 6 | 15 | 12 | 12 | 12 | 12 |  | 50 Ohms-3 | TOP=L2:L3=L2/L4:L6=L5/L7:BOTTOM=L7 |
| ATTN_LED_DR10_AND_R | 50OHM_Y12MIL | BUS | 8 | 6.75 | 5 | 10 | 5 | 14 | 6 | 15 | 12 | 12 | 12 | 12 |  | 50 Ohms-3 | TOP=L2:L3=L2/L4:L6=L5/L7:BOTTOM=L7 |
| ATTN_LED_DR10_MOS_N | 50OHM_Y12MIL | BUS | 1 | 6.75 | 5 | 10 | 5 | 14 | 6 | 15 | 12 | 12 | 12 | 12 |  | 50 Ohms-3 | TOP=L2:L3=L2/L4:L6=L5/L7:BOTTOM=L7 |
| ATTN_LED_DR10_MOS_N | 50OHM_Y12MIL | BUS | 2 | 6 | 5 | 10 | 5 | 14 | 6 | 15 | 12 | 12 | 12 | 12 |  | 50 Ohms-3 | TOP=L2:L3=L2/L4:L6=L5/L7:BOTTOM=L7 |
| ATTN_LED_DR10_MOS_N | 50OHM_Y12MIL | BUS | 3 | 6 | 5 | 10 | 5 | 14 | 6 | 15 | 12 | 12 | 12 | 12 |  | 50 Ohms-3 | TOP=L2:L3=L2/L4:L6=L5/L7:BOTTOM=L7 |
| ATTN_LED_DR10_MOS_N | 50OHM_Y12MIL | BUS | 4 | 6 | 5 | 10 | 5 | 14 | 6 | 15 | 12 | 12 | 12 | 12 |  | 50 Ohms-3 | TOP=L2:L3=L2/L4:L6=L5/L7:BOTTOM=L7 |
| ATTN_LED_DR10_MOS_N | 50OHM_Y12MIL | BUS | 5 | 6 | 5 | 10 | 5 | 14 | 6 | 15 | 12 | 12 | 12 | 12 |  | 50 Ohms-3 | TOP=L2:L3=L2/L4:L6=L5/L7:BOTTOM=L7 |
| ATTN_LED_DR10_MOS_N | 50OHM_Y12MIL | BUS | 6 | 6 | 5 | 10 | 5 | 14 | 6 | 15 | 12 | 12 | 12 | 12 |  | 50 Ohms-3 | TOP=L2:L3=L2/L4:L6=L5/L7:BOTTOM=L7 |
| ATTN_LED_DR10_MOS_N | 50OHM_Y12MIL | BUS | 7 | 6 | 5 | 10 | 5 | 14 | 6 | 15 | 12 | 12 | 12 | 12 |  | 50 Ohms-3 | TOP=L2:L3=L2/L4:L6=L5/L7:BOTTOM=L7 |
| ATTN_LED_DR10_MOS_N | 50OHM_Y12MIL | BUS | 8 | 6.75 | 5 | 10 | 5 | 14 | 6 | 15 | 12 | 12 | 12 | 12 |  | 50 Ohms-3 | TOP=L2:L3=L2/L4:L6=L5/L7:BOTTOM=L7 |
| ATTN_LED_DR10_N | 50OHM_Y12MIL | BUS | 1 | 6.75 | 5 | 10 | 5 | 14 | 6 | 15 | 12 | 12 | 12 | 12 |  | 50 Ohms-3 | TOP=L2:L3=L2/L4:L6=L5/L7:BOTTOM=L7 |
| ATTN_LED_DR10_N | 50OHM_Y12MIL | BUS | 2 | 6 | 5 | 10 | 5 | 14 | 6 | 15 | 12 | 12 | 12 | 12 |  | 50 Ohms-3 | TOP=L2:L3=L2/L4:L6=L5/L7:BOTTOM=L7 |
| ATTN_LED_DR10_N | 50OHM_Y12MIL | BUS | 3 | 6 | 5 | 10 | 5 | 14 | 6 | 15 | 12 | 12 | 12 | 12 |  | 50 Ohms-3 | TOP=L2:L3=L2/L4:L6=L5/L7:BOTTOM=L7 |
| ATTN_LED_DR10_N | 50OHM_Y12MIL | BUS | 4 | 6 | 5 | 10 | 5 | 14 | 6 | 15 | 12 | 12 | 12 | 12 |  | 50 Ohms-3 | TOP=L2:L3=L2/L4:L6=L5/L7:BOTTOM=L7 |
| ATTN_LED_DR10_N | 50OHM_Y12MIL | BUS | 5 | 6 | 5 | 10 | 5 | 14 | 6 | 15 | 12 | 12 | 12 | 12 |  | 50 Ohms-3 | TOP=L2:L3=L2/L4:L6=L5/L7:BOTTOM=L7 |
| ATTN_LED_DR10_N | 50OHM_Y12MIL | BUS | 6 | 6 | 5 | 10 | 5 | 14 | 6 | 15 | 12 | 12 | 12 | 12 |  | 50 Ohms-3 | TOP=L2:L3=L2/L4:L6=L5/L7:BOTTOM=L7 |
| ATTN_LED_DR10_N | 50OHM_Y12MIL | BUS | 7 | 6 | 5 | 10 | 5 | 14 | 6 | 15 | 12 | 12 | 12 | 12 |  | 50 Ohms-3 | TOP=L2:L3=L2/L4:L6=L5/L7:BOTTOM=L7 |
| ATTN_LED_DR10_N | 50OHM_Y12MIL | BUS | 8 | 6.75 | 5 | 10 | 5 | 14 | 6 | 15 | 12 | 12 | 12 | 12 |  | 50 Ohms-3 | TOP=L2:L3=L2/L4:L6=L5/L7:BOTTOM=L7 |
| ATTN_LED_DR10_R | 50OHM_Y12MIL | BUS | 1 | 6.75 | 5 | 10 | 5 | 14 | 6 | 15 | 12 | 12 | 12 | 12 |  | 50 Ohms-3 | TOP=L2:L3=L2/L4:L6=L5/L7:BOTTOM=L7 |
| ATTN_LED_DR10_R | 50OHM_Y12MIL | BUS | 2 | 6 | 5 | 10 | 5 | 14 | 6 | 15 | 12 | 12 | 12 | 12 |  | 50 Ohms-3 | TOP=L2:L3=L2/L4:L6=L5/L7:BOTTOM=L7 |
| ATTN_LED_DR10_R | 50OHM_Y12MIL | BUS | 3 | 6 | 5 | 10 | 5 | 14 | 6 | 15 | 12 | 12 | 12 | 12 |  | 50 Ohms-3 | TOP=L2:L3=L2/L4:L6=L5/L7:BOTTOM=L7 |
| ATTN_LED_DR10_R | 50OHM_Y12MIL | BUS | 4 | 6 | 5 | 10 | 5 | 14 | 6 | 15 | 12 | 12 | 12 | 12 |  | 50 Ohms-3 | TOP=L2:L3=L2/L4:L6=L5/L7:BOTTOM=L7 |
| ATTN_LED_DR10_R | 50OHM_Y12MIL | BUS | 5 | 6 | 5 | 10 | 5 | 14 | 6 | 15 | 12 | 12 | 12 | 12 |  | 50 Ohms-3 | TOP=L2:L3=L2/L4:L6=L5/L7:BOTTOM=L7 |
| ATTN_LED_DR10_R | 50OHM_Y12MIL | BUS | 6 | 6 | 5 | 10 | 5 | 14 | 6 | 15 | 12 | 12 | 12 | 12 |  | 50 Ohms-3 | TOP=L2:L3=L2/L4:L6=L5/L7:BOTTOM=L7 |
| ATTN_LED_DR10_R | 50OHM_Y12MIL | BUS | 7 | 6 | 5 | 10 | 5 | 14 | 6 | 15 | 12 | 12 | 12 | 12 |  | 50 Ohms-3 | TOP=L2:L3=L2/L4:L6=L5/L7:BOTTOM=L7 |
| ATTN_LED_DR10_R | 50OHM_Y12MIL | BUS | 8 | 6.75 | 5 | 10 | 5 | 14 | 6 | 15 | 12 | 12 | 12 | 12 |  | 50 Ohms-3 | TOP=L2:L3=L2/L4:L6=L5/L7:BOTTOM=L7 |
| ATTN_LED_DR11_AND | 50OHM_Y12MIL | BUS | 1 | 6.75 | 5 | 10 | 5 | 14 | 6 | 15 | 12 | 12 | 12 | 12 |  | 50 Ohms-3 | TOP=L2:L3=L2/L4:L6=L5/L7:BOTTOM=L7 |
| ATTN_LED_DR11_AND | 50OHM_Y12MIL | BUS | 2 | 6 | 5 | 10 | 5 | 14 | 6 | 15 | 12 | 12 | 12 | 12 |  | 50 Ohms-3 | TOP=L2:L3=L2/L4:L6=L5/L7:BOTTOM=L7 |
| ATTN_LED_DR11_AND | 50OHM_Y12MIL | BUS | 3 | 6 | 5 | 10 | 5 | 14 | 6 | 15 | 12 | 12 | 12 | 12 |  | 50 Ohms-3 | TOP=L2:L3=L2/L4:L6=L5/L7:BOTTOM=L7 |
| ATTN_LED_DR11_AND | 50OHM_Y12MIL | BUS | 4 | 6 | 5 | 10 | 5 | 14 | 6 | 15 | 12 | 12 | 12 | 12 |  | 50 Ohms-3 | TOP=L2:L3=L2/L4:L6=L5/L7:BOTTOM=L7 |
| ATTN_LED_DR11_AND | 50OHM_Y12MIL | BUS | 5 | 6 | 5 | 10 | 5 | 14 | 6 | 15 | 12 | 12 | 12 | 12 |  | 50 Ohms-3 | TOP=L2:L3=L2/L4:L6=L5/L7:BOTTOM=L7 |
| ATTN_LED_DR11_AND | 50OHM_Y12MIL | BUS | 6 | 6 | 5 | 10 | 5 | 14 | 6 | 15 | 12 | 12 | 12 | 12 |  | 50 Ohms-3 | TOP=L2:L3=L2/L4:L6=L5/L7:BOTTOM=L7 |
| ATTN_LED_DR11_AND | 50OHM_Y12MIL | BUS | 7 | 6 | 5 | 10 | 5 | 14 | 6 | 15 | 12 | 12 | 12 | 12 |  | 50 Ohms-3 | TOP=L2:L3=L2/L4:L6=L5/L7:BOTTOM=L7 |
| ATTN_LED_DR11_AND | 50OHM_Y12MIL | BUS | 8 | 6.75 | 5 | 10 | 5 | 14 | 6 | 15 | 12 | 12 | 12 | 12 |  | 50 Ohms-3 | TOP=L2:L3=L2/L4:L6=L5/L7:BOTTOM=L7 |
| ATTN_LED_DR11_AND_R | 50OHM_Y12MIL | BUS | 1 | 6.75 | 5 | 10 | 5 | 14 | 6 | 15 | 12 | 12 | 12 | 12 |  | 50 Ohms-3 | TOP=L2:L3=L2/L4:L6=L5/L7:BOTTOM=L7 |
| ATTN_LED_DR11_AND_R | 50OHM_Y12MIL | BUS | 2 | 6 | 5 | 10 | 5 | 14 | 6 | 15 | 12 | 12 | 12 | 12 |  | 50 Ohms-3 | TOP=L2:L3=L2/L4:L6=L5/L7:BOTTOM=L7 |
| ATTN_LED_DR11_AND_R | 50OHM_Y12MIL | BUS | 3 | 6 | 5 | 10 | 5 | 14 | 6 | 15 | 12 | 12 | 12 | 12 |  | 50 Ohms-3 | TOP=L2:L3=L2/L4:L6=L5/L7:BOTTOM=L7 |
| ATTN_LED_DR11_AND_R | 50OHM_Y12MIL | BUS | 4 | 6 | 5 | 10 | 5 | 14 | 6 | 15 | 12 | 12 | 12 | 12 |  | 50 Ohms-3 | TOP=L2:L3=L2/L4:L6=L5/L7:BOTTOM=L7 |
| ATTN_LED_DR11_AND_R | 50OHM_Y12MIL | BUS | 5 | 6 | 5 | 10 | 5 | 14 | 6 | 15 | 12 | 12 | 12 | 12 |  | 50 Ohms-3 | TOP=L2:L3=L2/L4:L6=L5/L7:BOTTOM=L7 |
| ATTN_LED_DR11_AND_R | 50OHM_Y12MIL | BUS | 6 | 6 | 5 | 10 | 5 | 14 | 6 | 15 | 12 | 12 | 12 | 12 |  | 50 Ohms-3 | TOP=L2:L3=L2/L4:L6=L5/L7:BOTTOM=L7 |
| ATTN_LED_DR11_AND_R | 50OHM_Y12MIL | BUS | 7 | 6 | 5 | 10 | 5 | 14 | 6 | 15 | 12 | 12 | 12 | 12 |  | 50 Ohms-3 | TOP=L2:L3=L2/L4:L6=L5/L7:BOTTOM=L7 |
| ATTN_LED_DR11_AND_R | 50OHM_Y12MIL | BUS | 8 | 6.75 | 5 | 10 | 5 | 14 | 6 | 15 | 12 | 12 | 12 | 12 |  | 50 Ohms-3 | TOP=L2:L3=L2/L4:L6=L5/L7:BOTTOM=L7 |
| ATTN_LED_DR11_MOS_N | 50OHM_Y12MIL | BUS | 1 | 6.75 | 5 | 10 | 5 | 14 | 6 | 15 | 12 | 12 | 12 | 12 |  | 50 Ohms-3 | TOP=L2:L3=L2/L4:L6=L5/L7:BOTTOM=L7 |
| ATTN_LED_DR11_MOS_N | 50OHM_Y12MIL | BUS | 2 | 6 | 5 | 10 | 5 | 14 | 6 | 15 | 12 | 12 | 12 | 12 |  | 50 Ohms-3 | TOP=L2:L3=L2/L4:L6=L5/L7:BOTTOM=L7 |
| ATTN_LED_DR11_MOS_N | 50OHM_Y12MIL | BUS | 3 | 6 | 5 | 10 | 5 | 14 | 6 | 15 | 12 | 12 | 12 | 12 |  | 50 Ohms-3 | TOP=L2:L3=L2/L4:L6=L5/L7:BOTTOM=L7 |
| ATTN_LED_DR11_MOS_N | 50OHM_Y12MIL | BUS | 4 | 6 | 5 | 10 | 5 | 14 | 6 | 15 | 12 | 12 | 12 | 12 |  | 50 Ohms-3 | TOP=L2:L3=L2/L4:L6=L5/L7:BOTTOM=L7 |
| ATTN_LED_DR11_MOS_N | 50OHM_Y12MIL | BUS | 5 | 6 | 5 | 10 | 5 | 14 | 6 | 15 | 12 | 12 | 12 | 12 |  | 50 Ohms-3 | TOP=L2:L3=L2/L4:L6=L5/L7:BOTTOM=L7 |
| ATTN_LED_DR11_MOS_N | 50OHM_Y12MIL | BUS | 6 | 6 | 5 | 10 | 5 | 14 | 6 | 15 | 12 | 12 | 12 | 12 |  | 50 Ohms-3 | TOP=L2:L3=L2/L4:L6=L5/L7:BOTTOM=L7 |
| ATTN_LED_DR11_MOS_N | 50OHM_Y12MIL | BUS | 7 | 6 | 5 | 10 | 5 | 14 | 6 | 15 | 12 | 12 | 12 | 12 |  | 50 Ohms-3 | TOP=L2:L3=L2/L4:L6=L5/L7:BOTTOM=L7 |
| ATTN_LED_DR11_MOS_N | 50OHM_Y12MIL | BUS | 8 | 6.75 | 5 | 10 | 5 | 14 | 6 | 15 | 12 | 12 | 12 | 12 |  | 50 Ohms-3 | TOP=L2:L3=L2/L4:L6=L5/L7:BOTTOM=L7 |
| ATTN_LED_DR11_N | 50OHM_Y12MIL | BUS | 1 | 6.75 | 5 | 10 | 5 | 14 | 6 | 15 | 12 | 12 | 12 | 12 |  | 50 Ohms-3 | TOP=L2:L3=L2/L4:L6=L5/L7:BOTTOM=L7 |
| ATTN_LED_DR11_N | 50OHM_Y12MIL | BUS | 2 | 6 | 5 | 10 | 5 | 14 | 6 | 15 | 12 | 12 | 12 | 12 |  | 50 Ohms-3 | TOP=L2:L3=L2/L4:L6=L5/L7:BOTTOM=L7 |
| ATTN_LED_DR11_N | 50OHM_Y12MIL | BUS | 3 | 6 | 5 | 10 | 5 | 14 | 6 | 15 | 12 | 12 | 12 | 12 |  | 50 Ohms-3 | TOP=L2:L3=L2/L4:L6=L5/L7:BOTTOM=L7 |
| ATTN_LED_DR11_N | 50OHM_Y12MIL | BUS | 4 | 6 | 5 | 10 | 5 | 14 | 6 | 15 | 12 | 12 | 12 | 12 |  | 50 Ohms-3 | TOP=L2:L3=L2/L4:L6=L5/L7:BOTTOM=L7 |
| ATTN_LED_DR11_N | 50OHM_Y12MIL | BUS | 5 | 6 | 5 | 10 | 5 | 14 | 6 | 15 | 12 | 12 | 12 | 12 |  | 50 Ohms-3 | TOP=L2:L3=L2/L4:L6=L5/L7:BOTTOM=L7 |
| ATTN_LED_DR11_N | 50OHM_Y12MIL | BUS | 6 | 6 | 5 | 10 | 5 | 14 | 6 | 15 | 12 | 12 | 12 | 12 |  | 50 Ohms-3 | TOP=L2:L3=L2/L4:L6=L5/L7:BOTTOM=L7 |
| ATTN_LED_DR11_N | 50OHM_Y12MIL | BUS | 7 | 6 | 5 | 10 | 5 | 14 | 6 | 15 | 12 | 12 | 12 | 12 |  | 50 Ohms-3 | TOP=L2:L3=L2/L4:L6=L5/L7:BOTTOM=L7 |
| ATTN_LED_DR11_N | 50OHM_Y12MIL | BUS | 8 | 6.75 | 5 | 10 | 5 | 14 | 6 | 15 | 12 | 12 | 12 | 12 |  | 50 Ohms-3 | TOP=L2:L3=L2/L4:L6=L5/L7:BOTTOM=L7 |
| ATTN_LED_DR11_R | 50OHM_Y12MIL | BUS | 1 | 6.75 | 5 | 10 | 5 | 14 | 6 | 15 | 12 | 12 | 12 | 12 |  | 50 Ohms-3 | TOP=L2:L3=L2/L4:L6=L5/L7:BOTTOM=L7 |
| ATTN_LED_DR11_R | 50OHM_Y12MIL | BUS | 2 | 6 | 5 | 10 | 5 | 14 | 6 | 15 | 12 | 12 | 12 | 12 |  | 50 Ohms-3 | TOP=L2:L3=L2/L4:L6=L5/L7:BOTTOM=L7 |
| ATTN_LED_DR11_R | 50OHM_Y12MIL | BUS | 3 | 6 | 5 | 10 | 5 | 14 | 6 | 15 | 12 | 12 | 12 | 12 |  | 50 Ohms-3 | TOP=L2:L3=L2/L4:L6=L5/L7:BOTTOM=L7 |
| ATTN_LED_DR11_R | 50OHM_Y12MIL | BUS | 4 | 6 | 5 | 10 | 5 | 14 | 6 | 15 | 12 | 12 | 12 | 12 |  | 50 Ohms-3 | TOP=L2:L3=L2/L4:L6=L5/L7:BOTTOM=L7 |
| ATTN_LED_DR11_R | 50OHM_Y12MIL | BUS | 5 | 6 | 5 | 10 | 5 | 14 | 6 | 15 | 12 | 12 | 12 | 12 |  | 50 Ohms-3 | TOP=L2:L3=L2/L4:L6=L5/L7:BOTTOM=L7 |
| ATTN_LED_DR11_R | 50OHM_Y12MIL | BUS | 6 | 6 | 5 | 10 | 5 | 14 | 6 | 15 | 12 | 12 | 12 | 12 |  | 50 Ohms-3 | TOP=L2:L3=L2/L4:L6=L5/L7:BOTTOM=L7 |
| ATTN_LED_DR11_R | 50OHM_Y12MIL | BUS | 7 | 6 | 5 | 10 | 5 | 14 | 6 | 15 | 12 | 12 | 12 | 12 |  | 50 Ohms-3 | TOP=L2:L3=L2/L4:L6=L5/L7:BOTTOM=L7 |
| ATTN_LED_DR11_R | 50OHM_Y12MIL | BUS | 8 | 6.75 | 5 | 10 | 5 | 14 | 6 | 15 | 12 | 12 | 12 | 12 |  | 50 Ohms-3 | TOP=L2:L3=L2/L4:L6=L5/L7:BOTTOM=L7 |
| ATTN_LED_DR12_AND | 50OHM_Y12MIL | BUS | 1 | 6.75 | 5 | 10 | 5 | 14 | 6 | 15 | 12 | 12 | 12 | 12 |  | 50 Ohms-3 | TOP=L2:L3=L2/L4:L6=L5/L7:BOTTOM=L7 |
| ATTN_LED_DR12_AND | 50OHM_Y12MIL | BUS | 2 | 6 | 5 | 10 | 5 | 14 | 6 | 15 | 12 | 12 | 12 | 12 |  | 50 Ohms-3 | TOP=L2:L3=L2/L4:L6=L5/L7:BOTTOM=L7 |
| ATTN_LED_DR12_AND | 50OHM_Y12MIL | BUS | 3 | 6 | 5 | 10 | 5 | 14 | 6 | 15 | 12 | 12 | 12 | 12 |  | 50 Ohms-3 | TOP=L2:L3=L2/L4:L6=L5/L7:BOTTOM=L7 |
| ATTN_LED_DR12_AND | 50OHM_Y12MIL | BUS | 4 | 6 | 5 | 10 | 5 | 14 | 6 | 15 | 12 | 12 | 12 | 12 |  | 50 Ohms-3 | TOP=L2:L3=L2/L4:L6=L5/L7:BOTTOM=L7 |
| ATTN_LED_DR12_AND | 50OHM_Y12MIL | BUS | 5 | 6 | 5 | 10 | 5 | 14 | 6 | 15 | 12 | 12 | 12 | 12 |  | 50 Ohms-3 | TOP=L2:L3=L2/L4:L6=L5/L7:BOTTOM=L7 |
| ATTN_LED_DR12_AND | 50OHM_Y12MIL | BUS | 6 | 6 | 5 | 10 | 5 | 14 | 6 | 15 | 12 | 12 | 12 | 12 |  | 50 Ohms-3 | TOP=L2:L3=L2/L4:L6=L5/L7:BOTTOM=L7 |
| ATTN_LED_DR12_AND | 50OHM_Y12MIL | BUS | 7 | 6 | 5 | 10 | 5 | 14 | 6 | 15 | 12 | 12 | 12 | 12 |  | 50 Ohms-3 | TOP=L2:L3=L2/L4:L6=L5/L7:BOTTOM=L7 |
| ATTN_LED_DR12_AND | 50OHM_Y12MIL | BUS | 8 | 6.75 | 5 | 10 | 5 | 14 | 6 | 15 | 12 | 12 | 12 | 12 |  | 50 Ohms-3 | TOP=L2:L3=L2/L4:L6=L5/L7:BOTTOM=L7 |
| ATTN_LED_DR12_AND_R | 50OHM_Y12MIL | BUS | 1 | 6.75 | 5 | 10 | 5 | 14 | 6 | 15 | 12 | 12 | 12 | 12 |  | 50 Ohms-3 | TOP=L2:L3=L2/L4:L6=L5/L7:BOTTOM=L7 |
| ATTN_LED_DR12_AND_R | 50OHM_Y12MIL | BUS | 2 | 6 | 5 | 10 | 5 | 14 | 6 | 15 | 12 | 12 | 12 | 12 |  | 50 Ohms-3 | TOP=L2:L3=L2/L4:L6=L5/L7:BOTTOM=L7 |
| ATTN_LED_DR12_AND_R | 50OHM_Y12MIL | BUS | 3 | 6 | 5 | 10 | 5 | 14 | 6 | 15 | 12 | 12 | 12 | 12 |  | 50 Ohms-3 | TOP=L2:L3=L2/L4:L6=L5/L7:BOTTOM=L7 |
| ATTN_LED_DR12_AND_R | 50OHM_Y12MIL | BUS | 4 | 6 | 5 | 10 | 5 | 14 | 6 | 15 | 12 | 12 | 12 | 12 |  | 50 Ohms-3 | TOP=L2:L3=L2/L4:L6=L5/L7:BOTTOM=L7 |
| ATTN_LED_DR12_AND_R | 50OHM_Y12MIL | BUS | 5 | 6 | 5 | 10 | 5 | 14 | 6 | 15 | 12 | 12 | 12 | 12 |  | 50 Ohms-3 | TOP=L2:L3=L2/L4:L6=L5/L7:BOTTOM=L7 |
| ATTN_LED_DR12_AND_R | 50OHM_Y12MIL | BUS | 6 | 6 | 5 | 10 | 5 | 14 | 6 | 15 | 12 | 12 | 12 | 12 |  | 50 Ohms-3 | TOP=L2:L3=L2/L4:L6=L5/L7:BOTTOM=L7 |
| ATTN_LED_DR12_AND_R | 50OHM_Y12MIL | BUS | 7 | 6 | 5 | 10 | 5 | 14 | 6 | 15 | 12 | 12 | 12 | 12 |  | 50 Ohms-3 | TOP=L2:L3=L2/L4:L6=L5/L7:BOTTOM=L7 |
| ATTN_LED_DR12_AND_R | 50OHM_Y12MIL | BUS | 8 | 6.75 | 5 | 10 | 5 | 14 | 6 | 15 | 12 | 12 | 12 | 12 |  | 50 Ohms-3 | TOP=L2:L3=L2/L4:L6=L5/L7:BOTTOM=L7 |
| ATTN_LED_DR12_MOS_N | 50OHM_Y12MIL | BUS | 1 | 6.75 | 5 | 10 | 5 | 14 | 6 | 15 | 12 | 12 | 12 | 12 |  | 50 Ohms-3 | TOP=L2:L3=L2/L4:L6=L5/L7:BOTTOM=L7 |
| ATTN_LED_DR12_MOS_N | 50OHM_Y12MIL | BUS | 2 | 6 | 5 | 10 | 5 | 14 | 6 | 15 | 12 | 12 | 12 | 12 |  | 50 Ohms-3 | TOP=L2:L3=L2/L4:L6=L5/L7:BOTTOM=L7 |
| ATTN_LED_DR12_MOS_N | 50OHM_Y12MIL | BUS | 3 | 6 | 5 | 10 | 5 | 14 | 6 | 15 | 12 | 12 | 12 | 12 |  | 50 Ohms-3 | TOP=L2:L3=L2/L4:L6=L5/L7:BOTTOM=L7 |
| ATTN_LED_DR12_MOS_N | 50OHM_Y12MIL | BUS | 4 | 6 | 5 | 10 | 5 | 14 | 6 | 15 | 12 | 12 | 12 | 12 |  | 50 Ohms-3 | TOP=L2:L3=L2/L4:L6=L5/L7:BOTTOM=L7 |
| ATTN_LED_DR12_MOS_N | 50OHM_Y12MIL | BUS | 5 | 6 | 5 | 10 | 5 | 14 | 6 | 15 | 12 | 12 | 12 | 12 |  | 50 Ohms-3 | TOP=L2:L3=L2/L4:L6=L5/L7:BOTTOM=L7 |
| ATTN_LED_DR12_MOS_N | 50OHM_Y12MIL | BUS | 6 | 6 | 5 | 10 | 5 | 14 | 6 | 15 | 12 | 12 | 12 | 12 |  | 50 Ohms-3 | TOP=L2:L3=L2/L4:L6=L5/L7:BOTTOM=L7 |
| ATTN_LED_DR12_MOS_N | 50OHM_Y12MIL | BUS | 7 | 6 | 5 | 10 | 5 | 14 | 6 | 15 | 12 | 12 | 12 | 12 |  | 50 Ohms-3 | TOP=L2:L3=L2/L4:L6=L5/L7:BOTTOM=L7 |
| ATTN_LED_DR12_MOS_N | 50OHM_Y12MIL | BUS | 8 | 6.75 | 5 | 10 | 5 | 14 | 6 | 15 | 12 | 12 | 12 | 12 |  | 50 Ohms-3 | TOP=L2:L3=L2/L4:L6=L5/L7:BOTTOM=L7 |
| ATTN_LED_DR12_N | 50OHM_Y12MIL | BUS | 1 | 6.75 | 5 | 10 | 5 | 14 | 6 | 15 | 12 | 12 | 12 | 12 |  | 50 Ohms-3 | TOP=L2:L3=L2/L4:L6=L5/L7:BOTTOM=L7 |
| ATTN_LED_DR12_N | 50OHM_Y12MIL | BUS | 2 | 6 | 5 | 10 | 5 | 14 | 6 | 15 | 12 | 12 | 12 | 12 |  | 50 Ohms-3 | TOP=L2:L3=L2/L4:L6=L5/L7:BOTTOM=L7 |
| ATTN_LED_DR12_N | 50OHM_Y12MIL | BUS | 3 | 6 | 5 | 10 | 5 | 14 | 6 | 15 | 12 | 12 | 12 | 12 |  | 50 Ohms-3 | TOP=L2:L3=L2/L4:L6=L5/L7:BOTTOM=L7 |
| ATTN_LED_DR12_N | 50OHM_Y12MIL | BUS | 4 | 6 | 5 | 10 | 5 | 14 | 6 | 15 | 12 | 12 | 12 | 12 |  | 50 Ohms-3 | TOP=L2:L3=L2/L4:L6=L5/L7:BOTTOM=L7 |
| ATTN_LED_DR12_N | 50OHM_Y12MIL | BUS | 5 | 6 | 5 | 10 | 5 | 14 | 6 | 15 | 12 | 12 | 12 | 12 |  | 50 Ohms-3 | TOP=L2:L3=L2/L4:L6=L5/L7:BOTTOM=L7 |
| ATTN_LED_DR12_N | 50OHM_Y12MIL | BUS | 6 | 6 | 5 | 10 | 5 | 14 | 6 | 15 | 12 | 12 | 12 | 12 |  | 50 Ohms-3 | TOP=L2:L3=L2/L4:L6=L5/L7:BOTTOM=L7 |
| ATTN_LED_DR12_N | 50OHM_Y12MIL | BUS | 7 | 6 | 5 | 10 | 5 | 14 | 6 | 15 | 12 | 12 | 12 | 12 |  | 50 Ohms-3 | TOP=L2:L3=L2/L4:L6=L5/L7:BOTTOM=L7 |
| ATTN_LED_DR12_N | 50OHM_Y12MIL | BUS | 8 | 6.75 | 5 | 10 | 5 | 14 | 6 | 15 | 12 | 12 | 12 | 12 |  | 50 Ohms-3 | TOP=L2:L3=L2/L4:L6=L5/L7:BOTTOM=L7 |
| ATTN_LED_DR12_R | 50OHM_Y12MIL | BUS | 1 | 6.75 | 5 | 10 | 5 | 14 | 6 | 15 | 12 | 12 | 12 | 12 |  | 50 Ohms-3 | TOP=L2:L3=L2/L4:L6=L5/L7:BOTTOM=L7 |
| ATTN_LED_DR12_R | 50OHM_Y12MIL | BUS | 2 | 6 | 5 | 10 | 5 | 14 | 6 | 15 | 12 | 12 | 12 | 12 |  | 50 Ohms-3 | TOP=L2:L3=L2/L4:L6=L5/L7:BOTTOM=L7 |
| ATTN_LED_DR12_R | 50OHM_Y12MIL | BUS | 3 | 6 | 5 | 10 | 5 | 14 | 6 | 15 | 12 | 12 | 12 | 12 |  | 50 Ohms-3 | TOP=L2:L3=L2/L4:L6=L5/L7:BOTTOM=L7 |
| ATTN_LED_DR12_R | 50OHM_Y12MIL | BUS | 4 | 6 | 5 | 10 | 5 | 14 | 6 | 15 | 12 | 12 | 12 | 12 |  | 50 Ohms-3 | TOP=L2:L3=L2/L4:L6=L5/L7:BOTTOM=L7 |
| ATTN_LED_DR12_R | 50OHM_Y12MIL | BUS | 5 | 6 | 5 | 10 | 5 | 14 | 6 | 15 | 12 | 12 | 12 | 12 |  | 50 Ohms-3 | TOP=L2:L3=L2/L4:L6=L5/L7:BOTTOM=L7 |
| ATTN_LED_DR12_R | 50OHM_Y12MIL | BUS | 6 | 6 | 5 | 10 | 5 | 14 | 6 | 15 | 12 | 12 | 12 | 12 |  | 50 Ohms-3 | TOP=L2:L3=L2/L4:L6=L5/L7:BOTTOM=L7 |
| ATTN_LED_DR12_R | 50OHM_Y12MIL | BUS | 7 | 6 | 5 | 10 | 5 | 14 | 6 | 15 | 12 | 12 | 12 | 12 |  | 50 Ohms-3 | TOP=L2:L3=L2/L4:L6=L5/L7:BOTTOM=L7 |
| ATTN_LED_DR12_R | 50OHM_Y12MIL | BUS | 8 | 6.75 | 5 | 10 | 5 | 14 | 6 | 15 | 12 | 12 | 12 | 12 |  | 50 Ohms-3 | TOP=L2:L3=L2/L4:L6=L5/L7:BOTTOM=L7 |
| ATTN_LED_DR13_AND | 50OHM_Y12MIL | BUS | 1 | 6.75 | 5 | 10 | 5 | 14 | 6 | 15 | 12 | 12 | 12 | 12 |  | 50 Ohms-3 | TOP=L2:L3=L2/L4:L6=L5/L7:BOTTOM=L7 |
| ATTN_LED_DR13_AND | 50OHM_Y12MIL | BUS | 2 | 6 | 5 | 10 | 5 | 14 | 6 | 15 | 12 | 12 | 12 | 12 |  | 50 Ohms-3 | TOP=L2:L3=L2/L4:L6=L5/L7:BOTTOM=L7 |
| ATTN_LED_DR13_AND | 50OHM_Y12MIL | BUS | 3 | 6 | 5 | 10 | 5 | 14 | 6 | 15 | 12 | 12 | 12 | 12 |  | 50 Ohms-3 | TOP=L2:L3=L2/L4:L6=L5/L7:BOTTOM=L7 |
| ATTN_LED_DR13_AND | 50OHM_Y12MIL | BUS | 4 | 6 | 5 | 10 | 5 | 14 | 6 | 15 | 12 | 12 | 12 | 12 |  | 50 Ohms-3 | TOP=L2:L3=L2/L4:L6=L5/L7:BOTTOM=L7 |
| ATTN_LED_DR13_AND | 50OHM_Y12MIL | BUS | 5 | 6 | 5 | 10 | 5 | 14 | 6 | 15 | 12 | 12 | 12 | 12 |  | 50 Ohms-3 | TOP=L2:L3=L2/L4:L6=L5/L7:BOTTOM=L7 |
| ATTN_LED_DR13_AND | 50OHM_Y12MIL | BUS | 6 | 6 | 5 | 10 | 5 | 14 | 6 | 15 | 12 | 12 | 12 | 12 |  | 50 Ohms-3 | TOP=L2:L3=L2/L4:L6=L5/L7:BOTTOM=L7 |
| ATTN_LED_DR13_AND | 50OHM_Y12MIL | BUS | 7 | 6 | 5 | 10 | 5 | 14 | 6 | 15 | 12 | 12 | 12 | 12 |  | 50 Ohms-3 | TOP=L2:L3=L2/L4:L6=L5/L7:BOTTOM=L7 |
| ATTN_LED_DR13_AND | 50OHM_Y12MIL | BUS | 8 | 6.75 | 5 | 10 | 5 | 14 | 6 | 15 | 12 | 12 | 12 | 12 |  | 50 Ohms-3 | TOP=L2:L3=L2/L4:L6=L5/L7:BOTTOM=L7 |
| ATTN_LED_DR13_AND_R | 50OHM_Y12MIL | BUS | 1 | 6.75 | 5 | 10 | 5 | 14 | 6 | 15 | 12 | 12 | 12 | 12 |  | 50 Ohms-3 | TOP=L2:L3=L2/L4:L6=L5/L7:BOTTOM=L7 |
| ATTN_LED_DR13_AND_R | 50OHM_Y12MIL | BUS | 2 | 6 | 5 | 10 | 5 | 14 | 6 | 15 | 12 | 12 | 12 | 12 |  | 50 Ohms-3 | TOP=L2:L3=L2/L4:L6=L5/L7:BOTTOM=L7 |
| ATTN_LED_DR13_AND_R | 50OHM_Y12MIL | BUS | 3 | 6 | 5 | 10 | 5 | 14 | 6 | 15 | 12 | 12 | 12 | 12 |  | 50 Ohms-3 | TOP=L2:L3=L2/L4:L6=L5/L7:BOTTOM=L7 |
| ATTN_LED_DR13_AND_R | 50OHM_Y12MIL | BUS | 4 | 6 | 5 | 10 | 5 | 14 | 6 | 15 | 12 | 12 | 12 | 12 |  | 50 Ohms-3 | TOP=L2:L3=L2/L4:L6=L5/L7:BOTTOM=L7 |
| ATTN_LED_DR13_AND_R | 50OHM_Y12MIL | BUS | 5 | 6 | 5 | 10 | 5 | 14 | 6 | 15 | 12 | 12 | 12 | 12 |  | 50 Ohms-3 | TOP=L2:L3=L2/L4:L6=L5/L7:BOTTOM=L7 |
| ATTN_LED_DR13_AND_R | 50OHM_Y12MIL | BUS | 6 | 6 | 5 | 10 | 5 | 14 | 6 | 15 | 12 | 12 | 12 | 12 |  | 50 Ohms-3 | TOP=L2:L3=L2/L4:L6=L5/L7:BOTTOM=L7 |
| ATTN_LED_DR13_AND_R | 50OHM_Y12MIL | BUS | 7 | 6 | 5 | 10 | 5 | 14 | 6 | 15 | 12 | 12 | 12 | 12 |  | 50 Ohms-3 | TOP=L2:L3=L2/L4:L6=L5/L7:BOTTOM=L7 |
| ATTN_LED_DR13_AND_R | 50OHM_Y12MIL | BUS | 8 | 6.75 | 5 | 10 | 5 | 14 | 6 | 15 | 12 | 12 | 12 | 12 |  | 50 Ohms-3 | TOP=L2:L3=L2/L4:L6=L5/L7:BOTTOM=L7 |
| ATTN_LED_DR13_MOS_N | 50OHM_Y12MIL | BUS | 1 | 6.75 | 5 | 10 | 5 | 14 | 6 | 15 | 12 | 12 | 12 | 12 |  | 50 Ohms-3 | TOP=L2:L3=L2/L4:L6=L5/L7:BOTTOM=L7 |
| ATTN_LED_DR13_MOS_N | 50OHM_Y12MIL | BUS | 2 | 6 | 5 | 10 | 5 | 14 | 6 | 15 | 12 | 12 | 12 | 12 |  | 50 Ohms-3 | TOP=L2:L3=L2/L4:L6=L5/L7:BOTTOM=L7 |
| ATTN_LED_DR13_MOS_N | 50OHM_Y12MIL | BUS | 3 | 6 | 5 | 10 | 5 | 14 | 6 | 15 | 12 | 12 | 12 | 12 |  | 50 Ohms-3 | TOP=L2:L3=L2/L4:L6=L5/L7:BOTTOM=L7 |
| ATTN_LED_DR13_MOS_N | 50OHM_Y12MIL | BUS | 4 | 6 | 5 | 10 | 5 | 14 | 6 | 15 | 12 | 12 | 12 | 12 |  | 50 Ohms-3 | TOP=L2:L3=L2/L4:L6=L5/L7:BOTTOM=L7 |
| ATTN_LED_DR13_MOS_N | 50OHM_Y12MIL | BUS | 5 | 6 | 5 | 10 | 5 | 14 | 6 | 15 | 12 | 12 | 12 | 12 |  | 50 Ohms-3 | TOP=L2:L3=L2/L4:L6=L5/L7:BOTTOM=L7 |
| ATTN_LED_DR13_MOS_N | 50OHM_Y12MIL | BUS | 6 | 6 | 5 | 10 | 5 | 14 | 6 | 15 | 12 | 12 | 12 | 12 |  | 50 Ohms-3 | TOP=L2:L3=L2/L4:L6=L5/L7:BOTTOM=L7 |
| ATTN_LED_DR13_MOS_N | 50OHM_Y12MIL | BUS | 7 | 6 | 5 | 10 | 5 | 14 | 6 | 15 | 12 | 12 | 12 | 12 |  | 50 Ohms-3 | TOP=L2:L3=L2/L4:L6=L5/L7:BOTTOM=L7 |
| ATTN_LED_DR13_MOS_N | 50OHM_Y12MIL | BUS | 8 | 6.75 | 5 | 10 | 5 | 14 | 6 | 15 | 12 | 12 | 12 | 12 |  | 50 Ohms-3 | TOP=L2:L3=L2/L4:L6=L5/L7:BOTTOM=L7 |
| ATTN_LED_DR13_N | 50OHM_Y12MIL | BUS | 1 | 6.75 | 5 | 10 | 5 | 14 | 6 | 15 | 12 | 12 | 12 | 12 |  | 50 Ohms-3 | TOP=L2:L3=L2/L4:L6=L5/L7:BOTTOM=L7 |
| ATTN_LED_DR13_N | 50OHM_Y12MIL | BUS | 2 | 6 | 5 | 10 | 5 | 14 | 6 | 15 | 12 | 12 | 12 | 12 |  | 50 Ohms-3 | TOP=L2:L3=L2/L4:L6=L5/L7:BOTTOM=L7 |
| ATTN_LED_DR13_N | 50OHM_Y12MIL | BUS | 3 | 6 | 5 | 10 | 5 | 14 | 6 | 15 | 12 | 12 | 12 | 12 |  | 50 Ohms-3 | TOP=L2:L3=L2/L4:L6=L5/L7:BOTTOM=L7 |
| ATTN_LED_DR13_N | 50OHM_Y12MIL | BUS | 4 | 6 | 5 | 10 | 5 | 14 | 6 | 15 | 12 | 12 | 12 | 12 |  | 50 Ohms-3 | TOP=L2:L3=L2/L4:L6=L5/L7:BOTTOM=L7 |
| ATTN_LED_DR13_N | 50OHM_Y12MIL | BUS | 5 | 6 | 5 | 10 | 5 | 14 | 6 | 15 | 12 | 12 | 12 | 12 |  | 50 Ohms-3 | TOP=L2:L3=L2/L4:L6=L5/L7:BOTTOM=L7 |
| ATTN_LED_DR13_N | 50OHM_Y12MIL | BUS | 6 | 6 | 5 | 10 | 5 | 14 | 6 | 15 | 12 | 12 | 12 | 12 |  | 50 Ohms-3 | TOP=L2:L3=L2/L4:L6=L5/L7:BOTTOM=L7 |
| ATTN_LED_DR13_N | 50OHM_Y12MIL | BUS | 7 | 6 | 5 | 10 | 5 | 14 | 6 | 15 | 12 | 12 | 12 | 12 |  | 50 Ohms-3 | TOP=L2:L3=L2/L4:L6=L5/L7:BOTTOM=L7 |
| ATTN_LED_DR13_N | 50OHM_Y12MIL | BUS | 8 | 6.75 | 5 | 10 | 5 | 14 | 6 | 15 | 12 | 12 | 12 | 12 |  | 50 Ohms-3 | TOP=L2:L3=L2/L4:L6=L5/L7:BOTTOM=L7 |
| ATTN_LED_DR13_R | 50OHM_Y12MIL | BUS | 1 | 6.75 | 5 | 10 | 5 | 14 | 6 | 15 | 12 | 12 | 12 | 12 |  | 50 Ohms-3 | TOP=L2:L3=L2/L4:L6=L5/L7:BOTTOM=L7 |
| ATTN_LED_DR13_R | 50OHM_Y12MIL | BUS | 2 | 6 | 5 | 10 | 5 | 14 | 6 | 15 | 12 | 12 | 12 | 12 |  | 50 Ohms-3 | TOP=L2:L3=L2/L4:L6=L5/L7:BOTTOM=L7 |
| ATTN_LED_DR13_R | 50OHM_Y12MIL | BUS | 3 | 6 | 5 | 10 | 5 | 14 | 6 | 15 | 12 | 12 | 12 | 12 |  | 50 Ohms-3 | TOP=L2:L3=L2/L4:L6=L5/L7:BOTTOM=L7 |
| ATTN_LED_DR13_R | 50OHM_Y12MIL | BUS | 4 | 6 | 5 | 10 | 5 | 14 | 6 | 15 | 12 | 12 | 12 | 12 |  | 50 Ohms-3 | TOP=L2:L3=L2/L4:L6=L5/L7:BOTTOM=L7 |
| ATTN_LED_DR13_R | 50OHM_Y12MIL | BUS | 5 | 6 | 5 | 10 | 5 | 14 | 6 | 15 | 12 | 12 | 12 | 12 |  | 50 Ohms-3 | TOP=L2:L3=L2/L4:L6=L5/L7:BOTTOM=L7 |
| ATTN_LED_DR13_R | 50OHM_Y12MIL | BUS | 6 | 6 | 5 | 10 | 5 | 14 | 6 | 15 | 12 | 12 | 12 | 12 |  | 50 Ohms-3 | TOP=L2:L3=L2/L4:L6=L5/L7:BOTTOM=L7 |
| ATTN_LED_DR13_R | 50OHM_Y12MIL | BUS | 7 | 6 | 5 | 10 | 5 | 14 | 6 | 15 | 12 | 12 | 12 | 12 |  | 50 Ohms-3 | TOP=L2:L3=L2/L4:L6=L5/L7:BOTTOM=L7 |
| ATTN_LED_DR13_R | 50OHM_Y12MIL | BUS | 8 | 6.75 | 5 | 10 | 5 | 14 | 6 | 15 | 12 | 12 | 12 | 12 |  | 50 Ohms-3 | TOP=L2:L3=L2/L4:L6=L5/L7:BOTTOM=L7 |
| ATTN_LED_DR14_AND | 50OHM_Y12MIL | BUS | 1 | 6.75 | 5 | 10 | 5 | 14 | 6 | 15 | 12 | 12 | 12 | 12 |  | 50 Ohms-3 | TOP=L2:L3=L2/L4:L6=L5/L7:BOTTOM=L7 |
| ATTN_LED_DR14_AND | 50OHM_Y12MIL | BUS | 2 | 6 | 5 | 10 | 5 | 14 | 6 | 15 | 12 | 12 | 12 | 12 |  | 50 Ohms-3 | TOP=L2:L3=L2/L4:L6=L5/L7:BOTTOM=L7 |
| ATTN_LED_DR14_AND | 50OHM_Y12MIL | BUS | 3 | 6 | 5 | 10 | 5 | 14 | 6 | 15 | 12 | 12 | 12 | 12 |  | 50 Ohms-3 | TOP=L2:L3=L2/L4:L6=L5/L7:BOTTOM=L7 |
| ATTN_LED_DR14_AND | 50OHM_Y12MIL | BUS | 4 | 6 | 5 | 10 | 5 | 14 | 6 | 15 | 12 | 12 | 12 | 12 |  | 50 Ohms-3 | TOP=L2:L3=L2/L4:L6=L5/L7:BOTTOM=L7 |
| ATTN_LED_DR14_AND | 50OHM_Y12MIL | BUS | 5 | 6 | 5 | 10 | 5 | 14 | 6 | 15 | 12 | 12 | 12 | 12 |  | 50 Ohms-3 | TOP=L2:L3=L2/L4:L6=L5/L7:BOTTOM=L7 |
| ATTN_LED_DR14_AND | 50OHM_Y12MIL | BUS | 6 | 6 | 5 | 10 | 5 | 14 | 6 | 15 | 12 | 12 | 12 | 12 |  | 50 Ohms-3 | TOP=L2:L3=L2/L4:L6=L5/L7:BOTTOM=L7 |
| ATTN_LED_DR14_AND | 50OHM_Y12MIL | BUS | 7 | 6 | 5 | 10 | 5 | 14 | 6 | 15 | 12 | 12 | 12 | 12 |  | 50 Ohms-3 | TOP=L2:L3=L2/L4:L6=L5/L7:BOTTOM=L7 |
| ATTN_LED_DR14_AND | 50OHM_Y12MIL | BUS | 8 | 6.75 | 5 | 10 | 5 | 14 | 6 | 15 | 12 | 12 | 12 | 12 |  | 50 Ohms-3 | TOP=L2:L3=L2/L4:L6=L5/L7:BOTTOM=L7 |
| ATTN_LED_DR14_AND_R | 50OHM_Y12MIL | BUS | 1 | 6.75 | 5 | 10 | 5 | 14 | 6 | 15 | 12 | 12 | 12 | 12 |  | 50 Ohms-3 | TOP=L2:L3=L2/L4:L6=L5/L7:BOTTOM=L7 |
| ATTN_LED_DR14_AND_R | 50OHM_Y12MIL | BUS | 2 | 6 | 5 | 10 | 5 | 14 | 6 | 15 | 12 | 12 | 12 | 12 |  | 50 Ohms-3 | TOP=L2:L3=L2/L4:L6=L5/L7:BOTTOM=L7 |
| ATTN_LED_DR14_AND_R | 50OHM_Y12MIL | BUS | 3 | 6 | 5 | 10 | 5 | 14 | 6 | 15 | 12 | 12 | 12 | 12 |  | 50 Ohms-3 | TOP=L2:L3=L2/L4:L6=L5/L7:BOTTOM=L7 |
| ATTN_LED_DR14_AND_R | 50OHM_Y12MIL | BUS | 4 | 6 | 5 | 10 | 5 | 14 | 6 | 15 | 12 | 12 | 12 | 12 |  | 50 Ohms-3 | TOP=L2:L3=L2/L4:L6=L5/L7:BOTTOM=L7 |
| ATTN_LED_DR14_AND_R | 50OHM_Y12MIL | BUS | 5 | 6 | 5 | 10 | 5 | 14 | 6 | 15 | 12 | 12 | 12 | 12 |  | 50 Ohms-3 | TOP=L2:L3=L2/L4:L6=L5/L7:BOTTOM=L7 |
| ATTN_LED_DR14_AND_R | 50OHM_Y12MIL | BUS | 6 | 6 | 5 | 10 | 5 | 14 | 6 | 15 | 12 | 12 | 12 | 12 |  | 50 Ohms-3 | TOP=L2:L3=L2/L4:L6=L5/L7:BOTTOM=L7 |
| ATTN_LED_DR14_AND_R | 50OHM_Y12MIL | BUS | 7 | 6 | 5 | 10 | 5 | 14 | 6 | 15 | 12 | 12 | 12 | 12 |  | 50 Ohms-3 | TOP=L2:L3=L2/L4:L6=L5/L7:BOTTOM=L7 |
| ATTN_LED_DR14_AND_R | 50OHM_Y12MIL | BUS | 8 | 6.75 | 5 | 10 | 5 | 14 | 6 | 15 | 12 | 12 | 12 | 12 |  | 50 Ohms-3 | TOP=L2:L3=L2/L4:L6=L5/L7:BOTTOM=L7 |
| ATTN_LED_DR14_MOS_N | 50OHM_Y12MIL | BUS | 1 | 6.75 | 5 | 10 | 5 | 14 | 6 | 15 | 12 | 12 | 12 | 12 |  | 50 Ohms-3 | TOP=L2:L3=L2/L4:L6=L5/L7:BOTTOM=L7 |
| ATTN_LED_DR14_MOS_N | 50OHM_Y12MIL | BUS | 2 | 6 | 5 | 10 | 5 | 14 | 6 | 15 | 12 | 12 | 12 | 12 |  | 50 Ohms-3 | TOP=L2:L3=L2/L4:L6=L5/L7:BOTTOM=L7 |
| ATTN_LED_DR14_MOS_N | 50OHM_Y12MIL | BUS | 3 | 6 | 5 | 10 | 5 | 14 | 6 | 15 | 12 | 12 | 12 | 12 |  | 50 Ohms-3 | TOP=L2:L3=L2/L4:L6=L5/L7:BOTTOM=L7 |
| ATTN_LED_DR14_MOS_N | 50OHM_Y12MIL | BUS | 4 | 6 | 5 | 10 | 5 | 14 | 6 | 15 | 12 | 12 | 12 | 12 |  | 50 Ohms-3 | TOP=L2:L3=L2/L4:L6=L5/L7:BOTTOM=L7 |
| ATTN_LED_DR14_MOS_N | 50OHM_Y12MIL | BUS | 5 | 6 | 5 | 10 | 5 | 14 | 6 | 15 | 12 | 12 | 12 | 12 |  | 50 Ohms-3 | TOP=L2:L3=L2/L4:L6=L5/L7:BOTTOM=L7 |
| ATTN_LED_DR14_MOS_N | 50OHM_Y12MIL | BUS | 6 | 6 | 5 | 10 | 5 | 14 | 6 | 15 | 12 | 12 | 12 | 12 |  | 50 Ohms-3 | TOP=L2:L3=L2/L4:L6=L5/L7:BOTTOM=L7 |
| ATTN_LED_DR14_MOS_N | 50OHM_Y12MIL | BUS | 7 | 6 | 5 | 10 | 5 | 14 | 6 | 15 | 12 | 12 | 12 | 12 |  | 50 Ohms-3 | TOP=L2:L3=L2/L4:L6=L5/L7:BOTTOM=L7 |
| ATTN_LED_DR14_MOS_N | 50OHM_Y12MIL | BUS | 8 | 6.75 | 5 | 10 | 5 | 14 | 6 | 15 | 12 | 12 | 12 | 12 |  | 50 Ohms-3 | TOP=L2:L3=L2/L4:L6=L5/L7:BOTTOM=L7 |
| ATTN_LED_DR14_N | 50OHM_Y12MIL | BUS | 1 | 6.75 | 5 | 10 | 5 | 14 | 6 | 15 | 12 | 12 | 12 | 12 |  | 50 Ohms-3 | TOP=L2:L3=L2/L4:L6=L5/L7:BOTTOM=L7 |
| ATTN_LED_DR14_N | 50OHM_Y12MIL | BUS | 2 | 6 | 5 | 10 | 5 | 14 | 6 | 15 | 12 | 12 | 12 | 12 |  | 50 Ohms-3 | TOP=L2:L3=L2/L4:L6=L5/L7:BOTTOM=L7 |
| ATTN_LED_DR14_N | 50OHM_Y12MIL | BUS | 3 | 6 | 5 | 10 | 5 | 14 | 6 | 15 | 12 | 12 | 12 | 12 |  | 50 Ohms-3 | TOP=L2:L3=L2/L4:L6=L5/L7:BOTTOM=L7 |
| ATTN_LED_DR14_N | 50OHM_Y12MIL | BUS | 4 | 6 | 5 | 10 | 5 | 14 | 6 | 15 | 12 | 12 | 12 | 12 |  | 50 Ohms-3 | TOP=L2:L3=L2/L4:L6=L5/L7:BOTTOM=L7 |
| ATTN_LED_DR14_N | 50OHM_Y12MIL | BUS | 5 | 6 | 5 | 10 | 5 | 14 | 6 | 15 | 12 | 12 | 12 | 12 |  | 50 Ohms-3 | TOP=L2:L3=L2/L4:L6=L5/L7:BOTTOM=L7 |
| ATTN_LED_DR14_N | 50OHM_Y12MIL | BUS | 6 | 6 | 5 | 10 | 5 | 14 | 6 | 15 | 12 | 12 | 12 | 12 |  | 50 Ohms-3 | TOP=L2:L3=L2/L4:L6=L5/L7:BOTTOM=L7 |
| ATTN_LED_DR14_N | 50OHM_Y12MIL | BUS | 7 | 6 | 5 | 10 | 5 | 14 | 6 | 15 | 12 | 12 | 12 | 12 |  | 50 Ohms-3 | TOP=L2:L3=L2/L4:L6=L5/L7:BOTTOM=L7 |
| ATTN_LED_DR14_N | 50OHM_Y12MIL | BUS | 8 | 6.75 | 5 | 10 | 5 | 14 | 6 | 15 | 12 | 12 | 12 | 12 |  | 50 Ohms-3 | TOP=L2:L3=L2/L4:L6=L5/L7:BOTTOM=L7 |
| ATTN_LED_DR14_R | 50OHM_Y12MIL | BUS | 1 | 6.75 | 5 | 10 | 5 | 14 | 6 | 15 | 12 | 12 | 12 | 12 |  | 50 Ohms-3 | TOP=L2:L3=L2/L4:L6=L5/L7:BOTTOM=L7 |
| ATTN_LED_DR14_R | 50OHM_Y12MIL | BUS | 2 | 6 | 5 | 10 | 5 | 14 | 6 | 15 | 12 | 12 | 12 | 12 |  | 50 Ohms-3 | TOP=L2:L3=L2/L4:L6=L5/L7:BOTTOM=L7 |
| ATTN_LED_DR14_R | 50OHM_Y12MIL | BUS | 3 | 6 | 5 | 10 | 5 | 14 | 6 | 15 | 12 | 12 | 12 | 12 |  | 50 Ohms-3 | TOP=L2:L3=L2/L4:L6=L5/L7:BOTTOM=L7 |
| ATTN_LED_DR14_R | 50OHM_Y12MIL | BUS | 4 | 6 | 5 | 10 | 5 | 14 | 6 | 15 | 12 | 12 | 12 | 12 |  | 50 Ohms-3 | TOP=L2:L3=L2/L4:L6=L5/L7:BOTTOM=L7 |
| ATTN_LED_DR14_R | 50OHM_Y12MIL | BUS | 5 | 6 | 5 | 10 | 5 | 14 | 6 | 15 | 12 | 12 | 12 | 12 |  | 50 Ohms-3 | TOP=L2:L3=L2/L4:L6=L5/L7:BOTTOM=L7 |
| ATTN_LED_DR14_R | 50OHM_Y12MIL | BUS | 6 | 6 | 5 | 10 | 5 | 14 | 6 | 15 | 12 | 12 | 12 | 12 |  | 50 Ohms-3 | TOP=L2:L3=L2/L4:L6=L5/L7:BOTTOM=L7 |
| ATTN_LED_DR14_R | 50OHM_Y12MIL | BUS | 7 | 6 | 5 | 10 | 5 | 14 | 6 | 15 | 12 | 12 | 12 | 12 |  | 50 Ohms-3 | TOP=L2:L3=L2/L4:L6=L5/L7:BOTTOM=L7 |
| ATTN_LED_DR14_R | 50OHM_Y12MIL | BUS | 8 | 6.75 | 5 | 10 | 5 | 14 | 6 | 15 | 12 | 12 | 12 | 12 |  | 50 Ohms-3 | TOP=L2:L3=L2/L4:L6=L5/L7:BOTTOM=L7 |
| ATTN_LED_DR2_AND | 50OHM_Y12MIL | BUS | 1 | 6.75 | 5 | 10 | 5 | 14 | 6 | 15 | 12 | 12 | 12 | 12 |  | 50 Ohms-3 | TOP=L2:L3=L2/L4:L6=L5/L7:BOTTOM=L7 |
| ATTN_LED_DR2_AND | 50OHM_Y12MIL | BUS | 2 | 6 | 5 | 10 | 5 | 14 | 6 | 15 | 12 | 12 | 12 | 12 |  | 50 Ohms-3 | TOP=L2:L3=L2/L4:L6=L5/L7:BOTTOM=L7 |
| ATTN_LED_DR2_AND | 50OHM_Y12MIL | BUS | 3 | 6 | 5 | 10 | 5 | 14 | 6 | 15 | 12 | 12 | 12 | 12 |  | 50 Ohms-3 | TOP=L2:L3=L2/L4:L6=L5/L7:BOTTOM=L7 |
| ATTN_LED_DR2_AND | 50OHM_Y12MIL | BUS | 4 | 6 | 5 | 10 | 5 | 14 | 6 | 15 | 12 | 12 | 12 | 12 |  | 50 Ohms-3 | TOP=L2:L3=L2/L4:L6=L5/L7:BOTTOM=L7 |
| ATTN_LED_DR2_AND | 50OHM_Y12MIL | BUS | 5 | 6 | 5 | 10 | 5 | 14 | 6 | 15 | 12 | 12 | 12 | 12 |  | 50 Ohms-3 | TOP=L2:L3=L2/L4:L6=L5/L7:BOTTOM=L7 |
| ATTN_LED_DR2_AND | 50OHM_Y12MIL | BUS | 6 | 6 | 5 | 10 | 5 | 14 | 6 | 15 | 12 | 12 | 12 | 12 |  | 50 Ohms-3 | TOP=L2:L3=L2/L4:L6=L5/L7:BOTTOM=L7 |
| ATTN_LED_DR2_AND | 50OHM_Y12MIL | BUS | 7 | 6 | 5 | 10 | 5 | 14 | 6 | 15 | 12 | 12 | 12 | 12 |  | 50 Ohms-3 | TOP=L2:L3=L2/L4:L6=L5/L7:BOTTOM=L7 |
| ATTN_LED_DR2_AND | 50OHM_Y12MIL | BUS | 8 | 6.75 | 5 | 10 | 5 | 14 | 6 | 15 | 12 | 12 | 12 | 12 |  | 50 Ohms-3 | TOP=L2:L3=L2/L4:L6=L5/L7:BOTTOM=L7 |
| ATTN_LED_DR2_AND_R | 50OHM_Y12MIL | BUS | 1 | 6.75 | 5 | 10 | 5 | 14 | 6 | 15 | 12 | 12 | 12 | 12 |  | 50 Ohms-3 | TOP=L2:L3=L2/L4:L6=L5/L7:BOTTOM=L7 |
| ATTN_LED_DR2_AND_R | 50OHM_Y12MIL | BUS | 2 | 6 | 5 | 10 | 5 | 14 | 6 | 15 | 12 | 12 | 12 | 12 |  | 50 Ohms-3 | TOP=L2:L3=L2/L4:L6=L5/L7:BOTTOM=L7 |
| ATTN_LED_DR2_AND_R | 50OHM_Y12MIL | BUS | 3 | 6 | 5 | 10 | 5 | 14 | 6 | 15 | 12 | 12 | 12 | 12 |  | 50 Ohms-3 | TOP=L2:L3=L2/L4:L6=L5/L7:BOTTOM=L7 |
| ATTN_LED_DR2_AND_R | 50OHM_Y12MIL | BUS | 4 | 6 | 5 | 10 | 5 | 14 | 6 | 15 | 12 | 12 | 12 | 12 |  | 50 Ohms-3 | TOP=L2:L3=L2/L4:L6=L5/L7:BOTTOM=L7 |
| ATTN_LED_DR2_AND_R | 50OHM_Y12MIL | BUS | 5 | 6 | 5 | 10 | 5 | 14 | 6 | 15 | 12 | 12 | 12 | 12 |  | 50 Ohms-3 | TOP=L2:L3=L2/L4:L6=L5/L7:BOTTOM=L7 |
| ATTN_LED_DR2_AND_R | 50OHM_Y12MIL | BUS | 6 | 6 | 5 | 10 | 5 | 14 | 6 | 15 | 12 | 12 | 12 | 12 |  | 50 Ohms-3 | TOP=L2:L3=L2/L4:L6=L5/L7:BOTTOM=L7 |
| ATTN_LED_DR2_AND_R | 50OHM_Y12MIL | BUS | 7 | 6 | 5 | 10 | 5 | 14 | 6 | 15 | 12 | 12 | 12 | 12 |  | 50 Ohms-3 | TOP=L2:L3=L2/L4:L6=L5/L7:BOTTOM=L7 |
| ATTN_LED_DR2_AND_R | 50OHM_Y12MIL | BUS | 8 | 6.75 | 5 | 10 | 5 | 14 | 6 | 15 | 12 | 12 | 12 | 12 |  | 50 Ohms-3 | TOP=L2:L3=L2/L4:L6=L5/L7:BOTTOM=L7 |
| ATTN_LED_DR2_MOS_N | 50OHM_Y12MIL | BUS | 1 | 6.75 | 5 | 10 | 5 | 14 | 6 | 15 | 12 | 12 | 12 | 12 |  | 50 Ohms-3 | TOP=L2:L3=L2/L4:L6=L5/L7:BOTTOM=L7 |
| ATTN_LED_DR2_MOS_N | 50OHM_Y12MIL | BUS | 2 | 6 | 5 | 10 | 5 | 14 | 6 | 15 | 12 | 12 | 12 | 12 |  | 50 Ohms-3 | TOP=L2:L3=L2/L4:L6=L5/L7:BOTTOM=L7 |
| ATTN_LED_DR2_MOS_N | 50OHM_Y12MIL | BUS | 3 | 6 | 5 | 10 | 5 | 14 | 6 | 15 | 12 | 12 | 12 | 12 |  | 50 Ohms-3 | TOP=L2:L3=L2/L4:L6=L5/L7:BOTTOM=L7 |
| ATTN_LED_DR2_MOS_N | 50OHM_Y12MIL | BUS | 4 | 6 | 5 | 10 | 5 | 14 | 6 | 15 | 12 | 12 | 12 | 12 |  | 50 Ohms-3 | TOP=L2:L3=L2/L4:L6=L5/L7:BOTTOM=L7 |
| ATTN_LED_DR2_MOS_N | 50OHM_Y12MIL | BUS | 5 | 6 | 5 | 10 | 5 | 14 | 6 | 15 | 12 | 12 | 12 | 12 |  | 50 Ohms-3 | TOP=L2:L3=L2/L4:L6=L5/L7:BOTTOM=L7 |
| ATTN_LED_DR2_MOS_N | 50OHM_Y12MIL | BUS | 6 | 6 | 5 | 10 | 5 | 14 | 6 | 15 | 12 | 12 | 12 | 12 |  | 50 Ohms-3 | TOP=L2:L3=L2/L4:L6=L5/L7:BOTTOM=L7 |
| ATTN_LED_DR2_MOS_N | 50OHM_Y12MIL | BUS | 7 | 6 | 5 | 10 | 5 | 14 | 6 | 15 | 12 | 12 | 12 | 12 |  | 50 Ohms-3 | TOP=L2:L3=L2/L4:L6=L5/L7:BOTTOM=L7 |
| ATTN_LED_DR2_MOS_N | 50OHM_Y12MIL | BUS | 8 | 6.75 | 5 | 10 | 5 | 14 | 6 | 15 | 12 | 12 | 12 | 12 |  | 50 Ohms-3 | TOP=L2:L3=L2/L4:L6=L5/L7:BOTTOM=L7 |
| ATTN_LED_DR2_N | 50OHM_Y12MIL | BUS | 1 | 6.75 | 5 | 10 | 5 | 14 | 6 | 15 | 12 | 12 | 12 | 12 |  | 50 Ohms-3 | TOP=L2:L3=L2/L4:L6=L5/L7:BOTTOM=L7 |
| ATTN_LED_DR2_N | 50OHM_Y12MIL | BUS | 2 | 6 | 5 | 10 | 5 | 14 | 6 | 15 | 12 | 12 | 12 | 12 |  | 50 Ohms-3 | TOP=L2:L3=L2/L4:L6=L5/L7:BOTTOM=L7 |
| ATTN_LED_DR2_N | 50OHM_Y12MIL | BUS | 3 | 6 | 5 | 10 | 5 | 14 | 6 | 15 | 12 | 12 | 12 | 12 |  | 50 Ohms-3 | TOP=L2:L3=L2/L4:L6=L5/L7:BOTTOM=L7 |
| ATTN_LED_DR2_N | 50OHM_Y12MIL | BUS | 4 | 6 | 5 | 10 | 5 | 14 | 6 | 15 | 12 | 12 | 12 | 12 |  | 50 Ohms-3 | TOP=L2:L3=L2/L4:L6=L5/L7:BOTTOM=L7 |
| ATTN_LED_DR2_N | 50OHM_Y12MIL | BUS | 5 | 6 | 5 | 10 | 5 | 14 | 6 | 15 | 12 | 12 | 12 | 12 |  | 50 Ohms-3 | TOP=L2:L3=L2/L4:L6=L5/L7:BOTTOM=L7 |
| ATTN_LED_DR2_N | 50OHM_Y12MIL | BUS | 6 | 6 | 5 | 10 | 5 | 14 | 6 | 15 | 12 | 12 | 12 | 12 |  | 50 Ohms-3 | TOP=L2:L3=L2/L4:L6=L5/L7:BOTTOM=L7 |
| ATTN_LED_DR2_N | 50OHM_Y12MIL | BUS | 7 | 6 | 5 | 10 | 5 | 14 | 6 | 15 | 12 | 12 | 12 | 12 |  | 50 Ohms-3 | TOP=L2:L3=L2/L4:L6=L5/L7:BOTTOM=L7 |
| ATTN_LED_DR2_N | 50OHM_Y12MIL | BUS | 8 | 6.75 | 5 | 10 | 5 | 14 | 6 | 15 | 12 | 12 | 12 | 12 |  | 50 Ohms-3 | TOP=L2:L3=L2/L4:L6=L5/L7:BOTTOM=L7 |
| ATTN_LED_DR2_R | 50OHM_Y12MIL | BUS | 1 | 6.75 | 5 | 10 | 5 | 14 | 6 | 15 | 12 | 12 | 12 | 12 |  | 50 Ohms-3 | TOP=L2:L3=L2/L4:L6=L5/L7:BOTTOM=L7 |
| ATTN_LED_DR2_R | 50OHM_Y12MIL | BUS | 2 | 6 | 5 | 10 | 5 | 14 | 6 | 15 | 12 | 12 | 12 | 12 |  | 50 Ohms-3 | TOP=L2:L3=L2/L4:L6=L5/L7:BOTTOM=L7 |
| ATTN_LED_DR2_R | 50OHM_Y12MIL | BUS | 3 | 6 | 5 | 10 | 5 | 14 | 6 | 15 | 12 | 12 | 12 | 12 |  | 50 Ohms-3 | TOP=L2:L3=L2/L4:L6=L5/L7:BOTTOM=L7 |
| ATTN_LED_DR2_R | 50OHM_Y12MIL | BUS | 4 | 6 | 5 | 10 | 5 | 14 | 6 | 15 | 12 | 12 | 12 | 12 |  | 50 Ohms-3 | TOP=L2:L3=L2/L4:L6=L5/L7:BOTTOM=L7 |
| ATTN_LED_DR2_R | 50OHM_Y12MIL | BUS | 5 | 6 | 5 | 10 | 5 | 14 | 6 | 15 | 12 | 12 | 12 | 12 |  | 50 Ohms-3 | TOP=L2:L3=L2/L4:L6=L5/L7:BOTTOM=L7 |
| ATTN_LED_DR2_R | 50OHM_Y12MIL | BUS | 6 | 6 | 5 | 10 | 5 | 14 | 6 | 15 | 12 | 12 | 12 | 12 |  | 50 Ohms-3 | TOP=L2:L3=L2/L4:L6=L5/L7:BOTTOM=L7 |
| ATTN_LED_DR2_R | 50OHM_Y12MIL | BUS | 7 | 6 | 5 | 10 | 5 | 14 | 6 | 15 | 12 | 12 | 12 | 12 |  | 50 Ohms-3 | TOP=L2:L3=L2/L4:L6=L5/L7:BOTTOM=L7 |
| ATTN_LED_DR2_R | 50OHM_Y12MIL | BUS | 8 | 6.75 | 5 | 10 | 5 | 14 | 6 | 15 | 12 | 12 | 12 | 12 |  | 50 Ohms-3 | TOP=L2:L3=L2/L4:L6=L5/L7:BOTTOM=L7 |
| ATTN_LED_DR3_AND | 50OHM_Y12MIL | BUS | 1 | 6.75 | 5 | 10 | 5 | 14 | 6 | 15 | 12 | 12 | 12 | 12 |  | 50 Ohms-3 | TOP=L2:L3=L2/L4:L6=L5/L7:BOTTOM=L7 |
| ATTN_LED_DR3_AND | 50OHM_Y12MIL | BUS | 2 | 6 | 5 | 10 | 5 | 14 | 6 | 15 | 12 | 12 | 12 | 12 |  | 50 Ohms-3 | TOP=L2:L3=L2/L4:L6=L5/L7:BOTTOM=L7 |
| ATTN_LED_DR3_AND | 50OHM_Y12MIL | BUS | 3 | 6 | 5 | 10 | 5 | 14 | 6 | 15 | 12 | 12 | 12 | 12 |  | 50 Ohms-3 | TOP=L2:L3=L2/L4:L6=L5/L7:BOTTOM=L7 |
| ATTN_LED_DR3_AND | 50OHM_Y12MIL | BUS | 4 | 6 | 5 | 10 | 5 | 14 | 6 | 15 | 12 | 12 | 12 | 12 |  | 50 Ohms-3 | TOP=L2:L3=L2/L4:L6=L5/L7:BOTTOM=L7 |
| ATTN_LED_DR3_AND | 50OHM_Y12MIL | BUS | 5 | 6 | 5 | 10 | 5 | 14 | 6 | 15 | 12 | 12 | 12 | 12 |  | 50 Ohms-3 | TOP=L2:L3=L2/L4:L6=L5/L7:BOTTOM=L7 |
| ATTN_LED_DR3_AND | 50OHM_Y12MIL | BUS | 6 | 6 | 5 | 10 | 5 | 14 | 6 | 15 | 12 | 12 | 12 | 12 |  | 50 Ohms-3 | TOP=L2:L3=L2/L4:L6=L5/L7:BOTTOM=L7 |
| ATTN_LED_DR3_AND | 50OHM_Y12MIL | BUS | 7 | 6 | 5 | 10 | 5 | 14 | 6 | 15 | 12 | 12 | 12 | 12 |  | 50 Ohms-3 | TOP=L2:L3=L2/L4:L6=L5/L7:BOTTOM=L7 |
| ATTN_LED_DR3_AND | 50OHM_Y12MIL | BUS | 8 | 6.75 | 5 | 10 | 5 | 14 | 6 | 15 | 12 | 12 | 12 | 12 |  | 50 Ohms-3 | TOP=L2:L3=L2/L4:L6=L5/L7:BOTTOM=L7 |
| ATTN_LED_DR3_AND_R | 50OHM_Y12MIL | BUS | 1 | 6.75 | 5 | 10 | 5 | 14 | 6 | 15 | 12 | 12 | 12 | 12 |  | 50 Ohms-3 | TOP=L2:L3=L2/L4:L6=L5/L7:BOTTOM=L7 |
| ATTN_LED_DR3_AND_R | 50OHM_Y12MIL | BUS | 2 | 6 | 5 | 10 | 5 | 14 | 6 | 15 | 12 | 12 | 12 | 12 |  | 50 Ohms-3 | TOP=L2:L3=L2/L4:L6=L5/L7:BOTTOM=L7 |
| ATTN_LED_DR3_AND_R | 50OHM_Y12MIL | BUS | 3 | 6 | 5 | 10 | 5 | 14 | 6 | 15 | 12 | 12 | 12 | 12 |  | 50 Ohms-3 | TOP=L2:L3=L2/L4:L6=L5/L7:BOTTOM=L7 |
| ATTN_LED_DR3_AND_R | 50OHM_Y12MIL | BUS | 4 | 6 | 5 | 10 | 5 | 14 | 6 | 15 | 12 | 12 | 12 | 12 |  | 50 Ohms-3 | TOP=L2:L3=L2/L4:L6=L5/L7:BOTTOM=L7 |
| ATTN_LED_DR3_AND_R | 50OHM_Y12MIL | BUS | 5 | 6 | 5 | 10 | 5 | 14 | 6 | 15 | 12 | 12 | 12 | 12 |  | 50 Ohms-3 | TOP=L2:L3=L2/L4:L6=L5/L7:BOTTOM=L7 |
| ATTN_LED_DR3_AND_R | 50OHM_Y12MIL | BUS | 6 | 6 | 5 | 10 | 5 | 14 | 6 | 15 | 12 | 12 | 12 | 12 |  | 50 Ohms-3 | TOP=L2:L3=L2/L4:L6=L5/L7:BOTTOM=L7 |
| ATTN_LED_DR3_AND_R | 50OHM_Y12MIL | BUS | 7 | 6 | 5 | 10 | 5 | 14 | 6 | 15 | 12 | 12 | 12 | 12 |  | 50 Ohms-3 | TOP=L2:L3=L2/L4:L6=L5/L7:BOTTOM=L7 |
| ATTN_LED_DR3_AND_R | 50OHM_Y12MIL | BUS | 8 | 6.75 | 5 | 10 | 5 | 14 | 6 | 15 | 12 | 12 | 12 | 12 |  | 50 Ohms-3 | TOP=L2:L3=L2/L4:L6=L5/L7:BOTTOM=L7 |
| ATTN_LED_DR3_MOS_N | 50OHM_Y12MIL | BUS | 1 | 6.75 | 5 | 10 | 5 | 14 | 6 | 15 | 12 | 12 | 12 | 12 |  | 50 Ohms-3 | TOP=L2:L3=L2/L4:L6=L5/L7:BOTTOM=L7 |
| ATTN_LED_DR3_MOS_N | 50OHM_Y12MIL | BUS | 2 | 6 | 5 | 10 | 5 | 14 | 6 | 15 | 12 | 12 | 12 | 12 |  | 50 Ohms-3 | TOP=L2:L3=L2/L4:L6=L5/L7:BOTTOM=L7 |
| ATTN_LED_DR3_MOS_N | 50OHM_Y12MIL | BUS | 3 | 6 | 5 | 10 | 5 | 14 | 6 | 15 | 12 | 12 | 12 | 12 |  | 50 Ohms-3 | TOP=L2:L3=L2/L4:L6=L5/L7:BOTTOM=L7 |
| ATTN_LED_DR3_MOS_N | 50OHM_Y12MIL | BUS | 4 | 6 | 5 | 10 | 5 | 14 | 6 | 15 | 12 | 12 | 12 | 12 |  | 50 Ohms-3 | TOP=L2:L3=L2/L4:L6=L5/L7:BOTTOM=L7 |
| ATTN_LED_DR3_MOS_N | 50OHM_Y12MIL | BUS | 5 | 6 | 5 | 10 | 5 | 14 | 6 | 15 | 12 | 12 | 12 | 12 |  | 50 Ohms-3 | TOP=L2:L3=L2/L4:L6=L5/L7:BOTTOM=L7 |
| ATTN_LED_DR3_MOS_N | 50OHM_Y12MIL | BUS | 6 | 6 | 5 | 10 | 5 | 14 | 6 | 15 | 12 | 12 | 12 | 12 |  | 50 Ohms-3 | TOP=L2:L3=L2/L4:L6=L5/L7:BOTTOM=L7 |
| ATTN_LED_DR3_MOS_N | 50OHM_Y12MIL | BUS | 7 | 6 | 5 | 10 | 5 | 14 | 6 | 15 | 12 | 12 | 12 | 12 |  | 50 Ohms-3 | TOP=L2:L3=L2/L4:L6=L5/L7:BOTTOM=L7 |
| ATTN_LED_DR3_MOS_N | 50OHM_Y12MIL | BUS | 8 | 6.75 | 5 | 10 | 5 | 14 | 6 | 15 | 12 | 12 | 12 | 12 |  | 50 Ohms-3 | TOP=L2:L3=L2/L4:L6=L5/L7:BOTTOM=L7 |
| ATTN_LED_DR3_N | 50OHM_Y12MIL | BUS | 1 | 6.75 | 5 | 10 | 5 | 14 | 6 | 15 | 12 | 12 | 12 | 12 |  | 50 Ohms-3 | TOP=L2:L3=L2/L4:L6=L5/L7:BOTTOM=L7 |
| ATTN_LED_DR3_N | 50OHM_Y12MIL | BUS | 2 | 6 | 5 | 10 | 5 | 14 | 6 | 15 | 12 | 12 | 12 | 12 |  | 50 Ohms-3 | TOP=L2:L3=L2/L4:L6=L5/L7:BOTTOM=L7 |
| ATTN_LED_DR3_N | 50OHM_Y12MIL | BUS | 3 | 6 | 5 | 10 | 5 | 14 | 6 | 15 | 12 | 12 | 12 | 12 |  | 50 Ohms-3 | TOP=L2:L3=L2/L4:L6=L5/L7:BOTTOM=L7 |
| ATTN_LED_DR3_N | 50OHM_Y12MIL | BUS | 4 | 6 | 5 | 10 | 5 | 14 | 6 | 15 | 12 | 12 | 12 | 12 |  | 50 Ohms-3 | TOP=L2:L3=L2/L4:L6=L5/L7:BOTTOM=L7 |
| ATTN_LED_DR3_N | 50OHM_Y12MIL | BUS | 5 | 6 | 5 | 10 | 5 | 14 | 6 | 15 | 12 | 12 | 12 | 12 |  | 50 Ohms-3 | TOP=L2:L3=L2/L4:L6=L5/L7:BOTTOM=L7 |
| ATTN_LED_DR3_N | 50OHM_Y12MIL | BUS | 6 | 6 | 5 | 10 | 5 | 14 | 6 | 15 | 12 | 12 | 12 | 12 |  | 50 Ohms-3 | TOP=L2:L3=L2/L4:L6=L5/L7:BOTTOM=L7 |
| ATTN_LED_DR3_N | 50OHM_Y12MIL | BUS | 7 | 6 | 5 | 10 | 5 | 14 | 6 | 15 | 12 | 12 | 12 | 12 |  | 50 Ohms-3 | TOP=L2:L3=L2/L4:L6=L5/L7:BOTTOM=L7 |
| ATTN_LED_DR3_N | 50OHM_Y12MIL | BUS | 8 | 6.75 | 5 | 10 | 5 | 14 | 6 | 15 | 12 | 12 | 12 | 12 |  | 50 Ohms-3 | TOP=L2:L3=L2/L4:L6=L5/L7:BOTTOM=L7 |
| ATTN_LED_DR3_R | 50OHM_Y12MIL | BUS | 1 | 6.75 | 5 | 10 | 5 | 14 | 6 | 15 | 12 | 12 | 12 | 12 |  | 50 Ohms-3 | TOP=L2:L3=L2/L4:L6=L5/L7:BOTTOM=L7 |
| ATTN_LED_DR3_R | 50OHM_Y12MIL | BUS | 2 | 6 | 5 | 10 | 5 | 14 | 6 | 15 | 12 | 12 | 12 | 12 |  | 50 Ohms-3 | TOP=L2:L3=L2/L4:L6=L5/L7:BOTTOM=L7 |
| ATTN_LED_DR3_R | 50OHM_Y12MIL | BUS | 3 | 6 | 5 | 10 | 5 | 14 | 6 | 15 | 12 | 12 | 12 | 12 |  | 50 Ohms-3 | TOP=L2:L3=L2/L4:L6=L5/L7:BOTTOM=L7 |
| ATTN_LED_DR3_R | 50OHM_Y12MIL | BUS | 4 | 6 | 5 | 10 | 5 | 14 | 6 | 15 | 12 | 12 | 12 | 12 |  | 50 Ohms-3 | TOP=L2:L3=L2/L4:L6=L5/L7:BOTTOM=L7 |
| ATTN_LED_DR3_R | 50OHM_Y12MIL | BUS | 5 | 6 | 5 | 10 | 5 | 14 | 6 | 15 | 12 | 12 | 12 | 12 |  | 50 Ohms-3 | TOP=L2:L3=L2/L4:L6=L5/L7:BOTTOM=L7 |
| ATTN_LED_DR3_R | 50OHM_Y12MIL | BUS | 6 | 6 | 5 | 10 | 5 | 14 | 6 | 15 | 12 | 12 | 12 | 12 |  | 50 Ohms-3 | TOP=L2:L3=L2/L4:L6=L5/L7:BOTTOM=L7 |
| ATTN_LED_DR3_R | 50OHM_Y12MIL | BUS | 7 | 6 | 5 | 10 | 5 | 14 | 6 | 15 | 12 | 12 | 12 | 12 |  | 50 Ohms-3 | TOP=L2:L3=L2/L4:L6=L5/L7:BOTTOM=L7 |
| ATTN_LED_DR3_R | 50OHM_Y12MIL | BUS | 8 | 6.75 | 5 | 10 | 5 | 14 | 6 | 15 | 12 | 12 | 12 | 12 |  | 50 Ohms-3 | TOP=L2:L3=L2/L4:L6=L5/L7:BOTTOM=L7 |
| ATTN_LED_DR4_AND | 50OHM_Y12MIL | BUS | 1 | 6.75 | 5 | 10 | 5 | 14 | 6 | 15 | 12 | 12 | 12 | 12 |  | 50 Ohms-3 | TOP=L2:L3=L2/L4:L6=L5/L7:BOTTOM=L7 |
| ATTN_LED_DR4_AND | 50OHM_Y12MIL | BUS | 2 | 6 | 5 | 10 | 5 | 14 | 6 | 15 | 12 | 12 | 12 | 12 |  | 50 Ohms-3 | TOP=L2:L3=L2/L4:L6=L5/L7:BOTTOM=L7 |
| ATTN_LED_DR4_AND | 50OHM_Y12MIL | BUS | 3 | 6 | 5 | 10 | 5 | 14 | 6 | 15 | 12 | 12 | 12 | 12 |  | 50 Ohms-3 | TOP=L2:L3=L2/L4:L6=L5/L7:BOTTOM=L7 |
| ATTN_LED_DR4_AND | 50OHM_Y12MIL | BUS | 4 | 6 | 5 | 10 | 5 | 14 | 6 | 15 | 12 | 12 | 12 | 12 |  | 50 Ohms-3 | TOP=L2:L3=L2/L4:L6=L5/L7:BOTTOM=L7 |
| ATTN_LED_DR4_AND | 50OHM_Y12MIL | BUS | 5 | 6 | 5 | 10 | 5 | 14 | 6 | 15 | 12 | 12 | 12 | 12 |  | 50 Ohms-3 | TOP=L2:L3=L2/L4:L6=L5/L7:BOTTOM=L7 |
| ATTN_LED_DR4_AND | 50OHM_Y12MIL | BUS | 6 | 6 | 5 | 10 | 5 | 14 | 6 | 15 | 12 | 12 | 12 | 12 |  | 50 Ohms-3 | TOP=L2:L3=L2/L4:L6=L5/L7:BOTTOM=L7 |
| ATTN_LED_DR4_AND | 50OHM_Y12MIL | BUS | 7 | 6 | 5 | 10 | 5 | 14 | 6 | 15 | 12 | 12 | 12 | 12 |  | 50 Ohms-3 | TOP=L2:L3=L2/L4:L6=L5/L7:BOTTOM=L7 |
| ATTN_LED_DR4_AND | 50OHM_Y12MIL | BUS | 8 | 6.75 | 5 | 10 | 5 | 14 | 6 | 15 | 12 | 12 | 12 | 12 |  | 50 Ohms-3 | TOP=L2:L3=L2/L4:L6=L5/L7:BOTTOM=L7 |
| ATTN_LED_DR4_AND_R | 50OHM_Y12MIL | BUS | 1 | 6.75 | 5 | 10 | 5 | 14 | 6 | 15 | 12 | 12 | 12 | 12 |  | 50 Ohms-3 | TOP=L2:L3=L2/L4:L6=L5/L7:BOTTOM=L7 |
| ATTN_LED_DR4_AND_R | 50OHM_Y12MIL | BUS | 2 | 6 | 5 | 10 | 5 | 14 | 6 | 15 | 12 | 12 | 12 | 12 |  | 50 Ohms-3 | TOP=L2:L3=L2/L4:L6=L5/L7:BOTTOM=L7 |
| ATTN_LED_DR4_AND_R | 50OHM_Y12MIL | BUS | 3 | 6 | 5 | 10 | 5 | 14 | 6 | 15 | 12 | 12 | 12 | 12 |  | 50 Ohms-3 | TOP=L2:L3=L2/L4:L6=L5/L7:BOTTOM=L7 |
| ATTN_LED_DR4_AND_R | 50OHM_Y12MIL | BUS | 4 | 6 | 5 | 10 | 5 | 14 | 6 | 15 | 12 | 12 | 12 | 12 |  | 50 Ohms-3 | TOP=L2:L3=L2/L4:L6=L5/L7:BOTTOM=L7 |
| ATTN_LED_DR4_AND_R | 50OHM_Y12MIL | BUS | 5 | 6 | 5 | 10 | 5 | 14 | 6 | 15 | 12 | 12 | 12 | 12 |  | 50 Ohms-3 | TOP=L2:L3=L2/L4:L6=L5/L7:BOTTOM=L7 |
| ATTN_LED_DR4_AND_R | 50OHM_Y12MIL | BUS | 6 | 6 | 5 | 10 | 5 | 14 | 6 | 15 | 12 | 12 | 12 | 12 |  | 50 Ohms-3 | TOP=L2:L3=L2/L4:L6=L5/L7:BOTTOM=L7 |
| ATTN_LED_DR4_AND_R | 50OHM_Y12MIL | BUS | 7 | 6 | 5 | 10 | 5 | 14 | 6 | 15 | 12 | 12 | 12 | 12 |  | 50 Ohms-3 | TOP=L2:L3=L2/L4:L6=L5/L7:BOTTOM=L7 |
| ATTN_LED_DR4_AND_R | 50OHM_Y12MIL | BUS | 8 | 6.75 | 5 | 10 | 5 | 14 | 6 | 15 | 12 | 12 | 12 | 12 |  | 50 Ohms-3 | TOP=L2:L3=L2/L4:L6=L5/L7:BOTTOM=L7 |
| ATTN_LED_DR4_MOS_N | 50OHM_Y12MIL | BUS | 1 | 6.75 | 5 | 10 | 5 | 14 | 6 | 15 | 12 | 12 | 12 | 12 |  | 50 Ohms-3 | TOP=L2:L3=L2/L4:L6=L5/L7:BOTTOM=L7 |
| ATTN_LED_DR4_MOS_N | 50OHM_Y12MIL | BUS | 2 | 6 | 5 | 10 | 5 | 14 | 6 | 15 | 12 | 12 | 12 | 12 |  | 50 Ohms-3 | TOP=L2:L3=L2/L4:L6=L5/L7:BOTTOM=L7 |
| ATTN_LED_DR4_MOS_N | 50OHM_Y12MIL | BUS | 3 | 6 | 5 | 10 | 5 | 14 | 6 | 15 | 12 | 12 | 12 | 12 |  | 50 Ohms-3 | TOP=L2:L3=L2/L4:L6=L5/L7:BOTTOM=L7 |
| ATTN_LED_DR4_MOS_N | 50OHM_Y12MIL | BUS | 4 | 6 | 5 | 10 | 5 | 14 | 6 | 15 | 12 | 12 | 12 | 12 |  | 50 Ohms-3 | TOP=L2:L3=L2/L4:L6=L5/L7:BOTTOM=L7 |
| ATTN_LED_DR4_MOS_N | 50OHM_Y12MIL | BUS | 5 | 6 | 5 | 10 | 5 | 14 | 6 | 15 | 12 | 12 | 12 | 12 |  | 50 Ohms-3 | TOP=L2:L3=L2/L4:L6=L5/L7:BOTTOM=L7 |
| ATTN_LED_DR4_MOS_N | 50OHM_Y12MIL | BUS | 6 | 6 | 5 | 10 | 5 | 14 | 6 | 15 | 12 | 12 | 12 | 12 |  | 50 Ohms-3 | TOP=L2:L3=L2/L4:L6=L5/L7:BOTTOM=L7 |
| ATTN_LED_DR4_MOS_N | 50OHM_Y12MIL | BUS | 7 | 6 | 5 | 10 | 5 | 14 | 6 | 15 | 12 | 12 | 12 | 12 |  | 50 Ohms-3 | TOP=L2:L3=L2/L4:L6=L5/L7:BOTTOM=L7 |
| ATTN_LED_DR4_MOS_N | 50OHM_Y12MIL | BUS | 8 | 6.75 | 5 | 10 | 5 | 14 | 6 | 15 | 12 | 12 | 12 | 12 |  | 50 Ohms-3 | TOP=L2:L3=L2/L4:L6=L5/L7:BOTTOM=L7 |
| ATTN_LED_DR4_N | 50OHM_Y12MIL | BUS | 1 | 6.75 | 5 | 10 | 5 | 14 | 6 | 15 | 12 | 12 | 12 | 12 |  | 50 Ohms-3 | TOP=L2:L3=L2/L4:L6=L5/L7:BOTTOM=L7 |
| ATTN_LED_DR4_N | 50OHM_Y12MIL | BUS | 2 | 6 | 5 | 10 | 5 | 14 | 6 | 15 | 12 | 12 | 12 | 12 |  | 50 Ohms-3 | TOP=L2:L3=L2/L4:L6=L5/L7:BOTTOM=L7 |
| ATTN_LED_DR4_N | 50OHM_Y12MIL | BUS | 3 | 6 | 5 | 10 | 5 | 14 | 6 | 15 | 12 | 12 | 12 | 12 |  | 50 Ohms-3 | TOP=L2:L3=L2/L4:L6=L5/L7:BOTTOM=L7 |
| ATTN_LED_DR4_N | 50OHM_Y12MIL | BUS | 4 | 6 | 5 | 10 | 5 | 14 | 6 | 15 | 12 | 12 | 12 | 12 |  | 50 Ohms-3 | TOP=L2:L3=L2/L4:L6=L5/L7:BOTTOM=L7 |
| ATTN_LED_DR4_N | 50OHM_Y12MIL | BUS | 5 | 6 | 5 | 10 | 5 | 14 | 6 | 15 | 12 | 12 | 12 | 12 |  | 50 Ohms-3 | TOP=L2:L3=L2/L4:L6=L5/L7:BOTTOM=L7 |
| ATTN_LED_DR4_N | 50OHM_Y12MIL | BUS | 6 | 6 | 5 | 10 | 5 | 14 | 6 | 15 | 12 | 12 | 12 | 12 |  | 50 Ohms-3 | TOP=L2:L3=L2/L4:L6=L5/L7:BOTTOM=L7 |
| ATTN_LED_DR4_N | 50OHM_Y12MIL | BUS | 7 | 6 | 5 | 10 | 5 | 14 | 6 | 15 | 12 | 12 | 12 | 12 |  | 50 Ohms-3 | TOP=L2:L3=L2/L4:L6=L5/L7:BOTTOM=L7 |
| ATTN_LED_DR4_N | 50OHM_Y12MIL | BUS | 8 | 6.75 | 5 | 10 | 5 | 14 | 6 | 15 | 12 | 12 | 12 | 12 |  | 50 Ohms-3 | TOP=L2:L3=L2/L4:L6=L5/L7:BOTTOM=L7 |
| ATTN_LED_DR4_R | 50OHM_Y12MIL | BUS | 1 | 6.75 | 5 | 10 | 5 | 14 | 6 | 15 | 12 | 12 | 12 | 12 |  | 50 Ohms-3 | TOP=L2:L3=L2/L4:L6=L5/L7:BOTTOM=L7 |
| ATTN_LED_DR4_R | 50OHM_Y12MIL | BUS | 2 | 6 | 5 | 10 | 5 | 14 | 6 | 15 | 12 | 12 | 12 | 12 |  | 50 Ohms-3 | TOP=L2:L3=L2/L4:L6=L5/L7:BOTTOM=L7 |
| ATTN_LED_DR4_R | 50OHM_Y12MIL | BUS | 3 | 6 | 5 | 10 | 5 | 14 | 6 | 15 | 12 | 12 | 12 | 12 |  | 50 Ohms-3 | TOP=L2:L3=L2/L4:L6=L5/L7:BOTTOM=L7 |
| ATTN_LED_DR4_R | 50OHM_Y12MIL | BUS | 4 | 6 | 5 | 10 | 5 | 14 | 6 | 15 | 12 | 12 | 12 | 12 |  | 50 Ohms-3 | TOP=L2:L3=L2/L4:L6=L5/L7:BOTTOM=L7 |
| ATTN_LED_DR4_R | 50OHM_Y12MIL | BUS | 5 | 6 | 5 | 10 | 5 | 14 | 6 | 15 | 12 | 12 | 12 | 12 |  | 50 Ohms-3 | TOP=L2:L3=L2/L4:L6=L5/L7:BOTTOM=L7 |
| ATTN_LED_DR4_R | 50OHM_Y12MIL | BUS | 6 | 6 | 5 | 10 | 5 | 14 | 6 | 15 | 12 | 12 | 12 | 12 |  | 50 Ohms-3 | TOP=L2:L3=L2/L4:L6=L5/L7:BOTTOM=L7 |
| ATTN_LED_DR4_R | 50OHM_Y12MIL | BUS | 7 | 6 | 5 | 10 | 5 | 14 | 6 | 15 | 12 | 12 | 12 | 12 |  | 50 Ohms-3 | TOP=L2:L3=L2/L4:L6=L5/L7:BOTTOM=L7 |
| ATTN_LED_DR4_R | 50OHM_Y12MIL | BUS | 8 | 6.75 | 5 | 10 | 5 | 14 | 6 | 15 | 12 | 12 | 12 | 12 |  | 50 Ohms-3 | TOP=L2:L3=L2/L4:L6=L5/L7:BOTTOM=L7 |
| ATTN_LED_DR5_AND | 50OHM_Y12MIL | BUS | 1 | 6.75 | 5 | 10 | 5 | 14 | 6 | 15 | 12 | 12 | 12 | 12 |  | 50 Ohms-3 | TOP=L2:L3=L2/L4:L6=L5/L7:BOTTOM=L7 |
| ATTN_LED_DR5_AND | 50OHM_Y12MIL | BUS | 2 | 6 | 5 | 10 | 5 | 14 | 6 | 15 | 12 | 12 | 12 | 12 |  | 50 Ohms-3 | TOP=L2:L3=L2/L4:L6=L5/L7:BOTTOM=L7 |
| ATTN_LED_DR5_AND | 50OHM_Y12MIL | BUS | 3 | 6 | 5 | 10 | 5 | 14 | 6 | 15 | 12 | 12 | 12 | 12 |  | 50 Ohms-3 | TOP=L2:L3=L2/L4:L6=L5/L7:BOTTOM=L7 |
| ATTN_LED_DR5_AND | 50OHM_Y12MIL | BUS | 4 | 6 | 5 | 10 | 5 | 14 | 6 | 15 | 12 | 12 | 12 | 12 |  | 50 Ohms-3 | TOP=L2:L3=L2/L4:L6=L5/L7:BOTTOM=L7 |
| ATTN_LED_DR5_AND | 50OHM_Y12MIL | BUS | 5 | 6 | 5 | 10 | 5 | 14 | 6 | 15 | 12 | 12 | 12 | 12 |  | 50 Ohms-3 | TOP=L2:L3=L2/L4:L6=L5/L7:BOTTOM=L7 |
| ATTN_LED_DR5_AND | 50OHM_Y12MIL | BUS | 6 | 6 | 5 | 10 | 5 | 14 | 6 | 15 | 12 | 12 | 12 | 12 |  | 50 Ohms-3 | TOP=L2:L3=L2/L4:L6=L5/L7:BOTTOM=L7 |
| ATTN_LED_DR5_AND | 50OHM_Y12MIL | BUS | 7 | 6 | 5 | 10 | 5 | 14 | 6 | 15 | 12 | 12 | 12 | 12 |  | 50 Ohms-3 | TOP=L2:L3=L2/L4:L6=L5/L7:BOTTOM=L7 |
| ATTN_LED_DR5_AND | 50OHM_Y12MIL | BUS | 8 | 6.75 | 5 | 10 | 5 | 14 | 6 | 15 | 12 | 12 | 12 | 12 |  | 50 Ohms-3 | TOP=L2:L3=L2/L4:L6=L5/L7:BOTTOM=L7 |
| ATTN_LED_DR5_AND_R | 50OHM_Y12MIL | BUS | 1 | 6.75 | 5 | 10 | 5 | 14 | 6 | 15 | 12 | 12 | 12 | 12 |  | 50 Ohms-3 | TOP=L2:L3=L2/L4:L6=L5/L7:BOTTOM=L7 |
| ATTN_LED_DR5_AND_R | 50OHM_Y12MIL | BUS | 2 | 6 | 5 | 10 | 5 | 14 | 6 | 15 | 12 | 12 | 12 | 12 |  | 50 Ohms-3 | TOP=L2:L3=L2/L4:L6=L5/L7:BOTTOM=L7 |
| ATTN_LED_DR5_AND_R | 50OHM_Y12MIL | BUS | 3 | 6 | 5 | 10 | 5 | 14 | 6 | 15 | 12 | 12 | 12 | 12 |  | 50 Ohms-3 | TOP=L2:L3=L2/L4:L6=L5/L7:BOTTOM=L7 |
| ATTN_LED_DR5_AND_R | 50OHM_Y12MIL | BUS | 4 | 6 | 5 | 10 | 5 | 14 | 6 | 15 | 12 | 12 | 12 | 12 |  | 50 Ohms-3 | TOP=L2:L3=L2/L4:L6=L5/L7:BOTTOM=L7 |
| ATTN_LED_DR5_AND_R | 50OHM_Y12MIL | BUS | 5 | 6 | 5 | 10 | 5 | 14 | 6 | 15 | 12 | 12 | 12 | 12 |  | 50 Ohms-3 | TOP=L2:L3=L2/L4:L6=L5/L7:BOTTOM=L7 |
| ATTN_LED_DR5_AND_R | 50OHM_Y12MIL | BUS | 6 | 6 | 5 | 10 | 5 | 14 | 6 | 15 | 12 | 12 | 12 | 12 |  | 50 Ohms-3 | TOP=L2:L3=L2/L4:L6=L5/L7:BOTTOM=L7 |
| ATTN_LED_DR5_AND_R | 50OHM_Y12MIL | BUS | 7 | 6 | 5 | 10 | 5 | 14 | 6 | 15 | 12 | 12 | 12 | 12 |  | 50 Ohms-3 | TOP=L2:L3=L2/L4:L6=L5/L7:BOTTOM=L7 |
| ATTN_LED_DR5_AND_R | 50OHM_Y12MIL | BUS | 8 | 6.75 | 5 | 10 | 5 | 14 | 6 | 15 | 12 | 12 | 12 | 12 |  | 50 Ohms-3 | TOP=L2:L3=L2/L4:L6=L5/L7:BOTTOM=L7 |
| ATTN_LED_DR5_MOS_N | 50OHM_Y12MIL | BUS | 1 | 6.75 | 5 | 10 | 5 | 14 | 6 | 15 | 12 | 12 | 12 | 12 |  | 50 Ohms-3 | TOP=L2:L3=L2/L4:L6=L5/L7:BOTTOM=L7 |
| ATTN_LED_DR5_MOS_N | 50OHM_Y12MIL | BUS | 2 | 6 | 5 | 10 | 5 | 14 | 6 | 15 | 12 | 12 | 12 | 12 |  | 50 Ohms-3 | TOP=L2:L3=L2/L4:L6=L5/L7:BOTTOM=L7 |
| ATTN_LED_DR5_MOS_N | 50OHM_Y12MIL | BUS | 3 | 6 | 5 | 10 | 5 | 14 | 6 | 15 | 12 | 12 | 12 | 12 |  | 50 Ohms-3 | TOP=L2:L3=L2/L4:L6=L5/L7:BOTTOM=L7 |
| ATTN_LED_DR5_MOS_N | 50OHM_Y12MIL | BUS | 4 | 6 | 5 | 10 | 5 | 14 | 6 | 15 | 12 | 12 | 12 | 12 |  | 50 Ohms-3 | TOP=L2:L3=L2/L4:L6=L5/L7:BOTTOM=L7 |
| ATTN_LED_DR5_MOS_N | 50OHM_Y12MIL | BUS | 5 | 6 | 5 | 10 | 5 | 14 | 6 | 15 | 12 | 12 | 12 | 12 |  | 50 Ohms-3 | TOP=L2:L3=L2/L4:L6=L5/L7:BOTTOM=L7 |
| ATTN_LED_DR5_MOS_N | 50OHM_Y12MIL | BUS | 6 | 6 | 5 | 10 | 5 | 14 | 6 | 15 | 12 | 12 | 12 | 12 |  | 50 Ohms-3 | TOP=L2:L3=L2/L4:L6=L5/L7:BOTTOM=L7 |
| ATTN_LED_DR5_MOS_N | 50OHM_Y12MIL | BUS | 7 | 6 | 5 | 10 | 5 | 14 | 6 | 15 | 12 | 12 | 12 | 12 |  | 50 Ohms-3 | TOP=L2:L3=L2/L4:L6=L5/L7:BOTTOM=L7 |
| ATTN_LED_DR5_MOS_N | 50OHM_Y12MIL | BUS | 8 | 6.75 | 5 | 10 | 5 | 14 | 6 | 15 | 12 | 12 | 12 | 12 |  | 50 Ohms-3 | TOP=L2:L3=L2/L4:L6=L5/L7:BOTTOM=L7 |
| ATTN_LED_DR5_N | 50OHM_Y12MIL | BUS | 1 | 6.75 | 5 | 10 | 5 | 14 | 6 | 15 | 12 | 12 | 12 | 12 |  | 50 Ohms-3 | TOP=L2:L3=L2/L4:L6=L5/L7:BOTTOM=L7 |
| ATTN_LED_DR5_N | 50OHM_Y12MIL | BUS | 2 | 6 | 5 | 10 | 5 | 14 | 6 | 15 | 12 | 12 | 12 | 12 |  | 50 Ohms-3 | TOP=L2:L3=L2/L4:L6=L5/L7:BOTTOM=L7 |
| ATTN_LED_DR5_N | 50OHM_Y12MIL | BUS | 3 | 6 | 5 | 10 | 5 | 14 | 6 | 15 | 12 | 12 | 12 | 12 |  | 50 Ohms-3 | TOP=L2:L3=L2/L4:L6=L5/L7:BOTTOM=L7 |
| ATTN_LED_DR5_N | 50OHM_Y12MIL | BUS | 4 | 6 | 5 | 10 | 5 | 14 | 6 | 15 | 12 | 12 | 12 | 12 |  | 50 Ohms-3 | TOP=L2:L3=L2/L4:L6=L5/L7:BOTTOM=L7 |
| ATTN_LED_DR5_N | 50OHM_Y12MIL | BUS | 5 | 6 | 5 | 10 | 5 | 14 | 6 | 15 | 12 | 12 | 12 | 12 |  | 50 Ohms-3 | TOP=L2:L3=L2/L4:L6=L5/L7:BOTTOM=L7 |
| ATTN_LED_DR5_N | 50OHM_Y12MIL | BUS | 6 | 6 | 5 | 10 | 5 | 14 | 6 | 15 | 12 | 12 | 12 | 12 |  | 50 Ohms-3 | TOP=L2:L3=L2/L4:L6=L5/L7:BOTTOM=L7 |
| ATTN_LED_DR5_N | 50OHM_Y12MIL | BUS | 7 | 6 | 5 | 10 | 5 | 14 | 6 | 15 | 12 | 12 | 12 | 12 |  | 50 Ohms-3 | TOP=L2:L3=L2/L4:L6=L5/L7:BOTTOM=L7 |
| ATTN_LED_DR5_N | 50OHM_Y12MIL | BUS | 8 | 6.75 | 5 | 10 | 5 | 14 | 6 | 15 | 12 | 12 | 12 | 12 |  | 50 Ohms-3 | TOP=L2:L3=L2/L4:L6=L5/L7:BOTTOM=L7 |
| ATTN_LED_DR5_R | 50OHM_Y12MIL | BUS | 1 | 6.75 | 5 | 10 | 5 | 14 | 6 | 15 | 12 | 12 | 12 | 12 |  | 50 Ohms-3 | TOP=L2:L3=L2/L4:L6=L5/L7:BOTTOM=L7 |
| ATTN_LED_DR5_R | 50OHM_Y12MIL | BUS | 2 | 6 | 5 | 10 | 5 | 14 | 6 | 15 | 12 | 12 | 12 | 12 |  | 50 Ohms-3 | TOP=L2:L3=L2/L4:L6=L5/L7:BOTTOM=L7 |
| ATTN_LED_DR5_R | 50OHM_Y12MIL | BUS | 3 | 6 | 5 | 10 | 5 | 14 | 6 | 15 | 12 | 12 | 12 | 12 |  | 50 Ohms-3 | TOP=L2:L3=L2/L4:L6=L5/L7:BOTTOM=L7 |
| ATTN_LED_DR5_R | 50OHM_Y12MIL | BUS | 4 | 6 | 5 | 10 | 5 | 14 | 6 | 15 | 12 | 12 | 12 | 12 |  | 50 Ohms-3 | TOP=L2:L3=L2/L4:L6=L5/L7:BOTTOM=L7 |
| ATTN_LED_DR5_R | 50OHM_Y12MIL | BUS | 5 | 6 | 5 | 10 | 5 | 14 | 6 | 15 | 12 | 12 | 12 | 12 |  | 50 Ohms-3 | TOP=L2:L3=L2/L4:L6=L5/L7:BOTTOM=L7 |
| ATTN_LED_DR5_R | 50OHM_Y12MIL | BUS | 6 | 6 | 5 | 10 | 5 | 14 | 6 | 15 | 12 | 12 | 12 | 12 |  | 50 Ohms-3 | TOP=L2:L3=L2/L4:L6=L5/L7:BOTTOM=L7 |
| ATTN_LED_DR5_R | 50OHM_Y12MIL | BUS | 7 | 6 | 5 | 10 | 5 | 14 | 6 | 15 | 12 | 12 | 12 | 12 |  | 50 Ohms-3 | TOP=L2:L3=L2/L4:L6=L5/L7:BOTTOM=L7 |
| ATTN_LED_DR5_R | 50OHM_Y12MIL | BUS | 8 | 6.75 | 5 | 10 | 5 | 14 | 6 | 15 | 12 | 12 | 12 | 12 |  | 50 Ohms-3 | TOP=L2:L3=L2/L4:L6=L5/L7:BOTTOM=L7 |
| ATTN_LED_DR6_AND | 50OHM_Y12MIL | BUS | 1 | 6.75 | 5 | 10 | 5 | 14 | 6 | 15 | 12 | 12 | 12 | 12 |  | 50 Ohms-3 | TOP=L2:L3=L2/L4:L6=L5/L7:BOTTOM=L7 |
| ATTN_LED_DR6_AND | 50OHM_Y12MIL | BUS | 2 | 6 | 5 | 10 | 5 | 14 | 6 | 15 | 12 | 12 | 12 | 12 |  | 50 Ohms-3 | TOP=L2:L3=L2/L4:L6=L5/L7:BOTTOM=L7 |
| ATTN_LED_DR6_AND | 50OHM_Y12MIL | BUS | 3 | 6 | 5 | 10 | 5 | 14 | 6 | 15 | 12 | 12 | 12 | 12 |  | 50 Ohms-3 | TOP=L2:L3=L2/L4:L6=L5/L7:BOTTOM=L7 |
| ATTN_LED_DR6_AND | 50OHM_Y12MIL | BUS | 4 | 6 | 5 | 10 | 5 | 14 | 6 | 15 | 12 | 12 | 12 | 12 |  | 50 Ohms-3 | TOP=L2:L3=L2/L4:L6=L5/L7:BOTTOM=L7 |
| ATTN_LED_DR6_AND | 50OHM_Y12MIL | BUS | 5 | 6 | 5 | 10 | 5 | 14 | 6 | 15 | 12 | 12 | 12 | 12 |  | 50 Ohms-3 | TOP=L2:L3=L2/L4:L6=L5/L7:BOTTOM=L7 |
| ATTN_LED_DR6_AND | 50OHM_Y12MIL | BUS | 6 | 6 | 5 | 10 | 5 | 14 | 6 | 15 | 12 | 12 | 12 | 12 |  | 50 Ohms-3 | TOP=L2:L3=L2/L4:L6=L5/L7:BOTTOM=L7 |
| ATTN_LED_DR6_AND | 50OHM_Y12MIL | BUS | 7 | 6 | 5 | 10 | 5 | 14 | 6 | 15 | 12 | 12 | 12 | 12 |  | 50 Ohms-3 | TOP=L2:L3=L2/L4:L6=L5/L7:BOTTOM=L7 |
| ATTN_LED_DR6_AND | 50OHM_Y12MIL | BUS | 8 | 6.75 | 5 | 10 | 5 | 14 | 6 | 15 | 12 | 12 | 12 | 12 |  | 50 Ohms-3 | TOP=L2:L3=L2/L4:L6=L5/L7:BOTTOM=L7 |
| ATTN_LED_DR6_AND_R | 50OHM_Y12MIL | BUS | 1 | 6.75 | 5 | 10 | 5 | 14 | 6 | 15 | 12 | 12 | 12 | 12 |  | 50 Ohms-3 | TOP=L2:L3=L2/L4:L6=L5/L7:BOTTOM=L7 |
| ATTN_LED_DR6_AND_R | 50OHM_Y12MIL | BUS | 2 | 6 | 5 | 10 | 5 | 14 | 6 | 15 | 12 | 12 | 12 | 12 |  | 50 Ohms-3 | TOP=L2:L3=L2/L4:L6=L5/L7:BOTTOM=L7 |
| ATTN_LED_DR6_AND_R | 50OHM_Y12MIL | BUS | 3 | 6 | 5 | 10 | 5 | 14 | 6 | 15 | 12 | 12 | 12 | 12 |  | 50 Ohms-3 | TOP=L2:L3=L2/L4:L6=L5/L7:BOTTOM=L7 |
| ATTN_LED_DR6_AND_R | 50OHM_Y12MIL | BUS | 4 | 6 | 5 | 10 | 5 | 14 | 6 | 15 | 12 | 12 | 12 | 12 |  | 50 Ohms-3 | TOP=L2:L3=L2/L4:L6=L5/L7:BOTTOM=L7 |
| ATTN_LED_DR6_AND_R | 50OHM_Y12MIL | BUS | 5 | 6 | 5 | 10 | 5 | 14 | 6 | 15 | 12 | 12 | 12 | 12 |  | 50 Ohms-3 | TOP=L2:L3=L2/L4:L6=L5/L7:BOTTOM=L7 |
| ATTN_LED_DR6_AND_R | 50OHM_Y12MIL | BUS | 6 | 6 | 5 | 10 | 5 | 14 | 6 | 15 | 12 | 12 | 12 | 12 |  | 50 Ohms-3 | TOP=L2:L3=L2/L4:L6=L5/L7:BOTTOM=L7 |
| ATTN_LED_DR6_AND_R | 50OHM_Y12MIL | BUS | 7 | 6 | 5 | 10 | 5 | 14 | 6 | 15 | 12 | 12 | 12 | 12 |  | 50 Ohms-3 | TOP=L2:L3=L2/L4:L6=L5/L7:BOTTOM=L7 |
| ATTN_LED_DR6_AND_R | 50OHM_Y12MIL | BUS | 8 | 6.75 | 5 | 10 | 5 | 14 | 6 | 15 | 12 | 12 | 12 | 12 |  | 50 Ohms-3 | TOP=L2:L3=L2/L4:L6=L5/L7:BOTTOM=L7 |
| ATTN_LED_DR6_MOS_N | 50OHM_Y12MIL | BUS | 1 | 6.75 | 5 | 10 | 5 | 14 | 6 | 15 | 12 | 12 | 12 | 12 |  | 50 Ohms-3 | TOP=L2:L3=L2/L4:L6=L5/L7:BOTTOM=L7 |
| ATTN_LED_DR6_MOS_N | 50OHM_Y12MIL | BUS | 2 | 6 | 5 | 10 | 5 | 14 | 6 | 15 | 12 | 12 | 12 | 12 |  | 50 Ohms-3 | TOP=L2:L3=L2/L4:L6=L5/L7:BOTTOM=L7 |
| ATTN_LED_DR6_MOS_N | 50OHM_Y12MIL | BUS | 3 | 6 | 5 | 10 | 5 | 14 | 6 | 15 | 12 | 12 | 12 | 12 |  | 50 Ohms-3 | TOP=L2:L3=L2/L4:L6=L5/L7:BOTTOM=L7 |
| ATTN_LED_DR6_MOS_N | 50OHM_Y12MIL | BUS | 4 | 6 | 5 | 10 | 5 | 14 | 6 | 15 | 12 | 12 | 12 | 12 |  | 50 Ohms-3 | TOP=L2:L3=L2/L4:L6=L5/L7:BOTTOM=L7 |
| ATTN_LED_DR6_MOS_N | 50OHM_Y12MIL | BUS | 5 | 6 | 5 | 10 | 5 | 14 | 6 | 15 | 12 | 12 | 12 | 12 |  | 50 Ohms-3 | TOP=L2:L3=L2/L4:L6=L5/L7:BOTTOM=L7 |
| ATTN_LED_DR6_MOS_N | 50OHM_Y12MIL | BUS | 6 | 6 | 5 | 10 | 5 | 14 | 6 | 15 | 12 | 12 | 12 | 12 |  | 50 Ohms-3 | TOP=L2:L3=L2/L4:L6=L5/L7:BOTTOM=L7 |
| ATTN_LED_DR6_MOS_N | 50OHM_Y12MIL | BUS | 7 | 6 | 5 | 10 | 5 | 14 | 6 | 15 | 12 | 12 | 12 | 12 |  | 50 Ohms-3 | TOP=L2:L3=L2/L4:L6=L5/L7:BOTTOM=L7 |
| ATTN_LED_DR6_MOS_N | 50OHM_Y12MIL | BUS | 8 | 6.75 | 5 | 10 | 5 | 14 | 6 | 15 | 12 | 12 | 12 | 12 |  | 50 Ohms-3 | TOP=L2:L3=L2/L4:L6=L5/L7:BOTTOM=L7 |
| ATTN_LED_DR6_N | 50OHM_Y12MIL | BUS | 1 | 6.75 | 5 | 10 | 5 | 14 | 6 | 15 | 12 | 12 | 12 | 12 |  | 50 Ohms-3 | TOP=L2:L3=L2/L4:L6=L5/L7:BOTTOM=L7 |
| ATTN_LED_DR6_N | 50OHM_Y12MIL | BUS | 2 | 6 | 5 | 10 | 5 | 14 | 6 | 15 | 12 | 12 | 12 | 12 |  | 50 Ohms-3 | TOP=L2:L3=L2/L4:L6=L5/L7:BOTTOM=L7 |
| ATTN_LED_DR6_N | 50OHM_Y12MIL | BUS | 3 | 6 | 5 | 10 | 5 | 14 | 6 | 15 | 12 | 12 | 12 | 12 |  | 50 Ohms-3 | TOP=L2:L3=L2/L4:L6=L5/L7:BOTTOM=L7 |
| ATTN_LED_DR6_N | 50OHM_Y12MIL | BUS | 4 | 6 | 5 | 10 | 5 | 14 | 6 | 15 | 12 | 12 | 12 | 12 |  | 50 Ohms-3 | TOP=L2:L3=L2/L4:L6=L5/L7:BOTTOM=L7 |
| ATTN_LED_DR6_N | 50OHM_Y12MIL | BUS | 5 | 6 | 5 | 10 | 5 | 14 | 6 | 15 | 12 | 12 | 12 | 12 |  | 50 Ohms-3 | TOP=L2:L3=L2/L4:L6=L5/L7:BOTTOM=L7 |
| ATTN_LED_DR6_N | 50OHM_Y12MIL | BUS | 6 | 6 | 5 | 10 | 5 | 14 | 6 | 15 | 12 | 12 | 12 | 12 |  | 50 Ohms-3 | TOP=L2:L3=L2/L4:L6=L5/L7:BOTTOM=L7 |
| ATTN_LED_DR6_N | 50OHM_Y12MIL | BUS | 7 | 6 | 5 | 10 | 5 | 14 | 6 | 15 | 12 | 12 | 12 | 12 |  | 50 Ohms-3 | TOP=L2:L3=L2/L4:L6=L5/L7:BOTTOM=L7 |
| ATTN_LED_DR6_N | 50OHM_Y12MIL | BUS | 8 | 6.75 | 5 | 10 | 5 | 14 | 6 | 15 | 12 | 12 | 12 | 12 |  | 50 Ohms-3 | TOP=L2:L3=L2/L4:L6=L5/L7:BOTTOM=L7 |
| ATTN_LED_DR6_R | 50OHM_Y12MIL | BUS | 1 | 6.75 | 5 | 10 | 5 | 14 | 6 | 15 | 12 | 12 | 12 | 12 |  | 50 Ohms-3 | TOP=L2:L3=L2/L4:L6=L5/L7:BOTTOM=L7 |
| ATTN_LED_DR6_R | 50OHM_Y12MIL | BUS | 2 | 6 | 5 | 10 | 5 | 14 | 6 | 15 | 12 | 12 | 12 | 12 |  | 50 Ohms-3 | TOP=L2:L3=L2/L4:L6=L5/L7:BOTTOM=L7 |
| ATTN_LED_DR6_R | 50OHM_Y12MIL | BUS | 3 | 6 | 5 | 10 | 5 | 14 | 6 | 15 | 12 | 12 | 12 | 12 |  | 50 Ohms-3 | TOP=L2:L3=L2/L4:L6=L5/L7:BOTTOM=L7 |
| ATTN_LED_DR6_R | 50OHM_Y12MIL | BUS | 4 | 6 | 5 | 10 | 5 | 14 | 6 | 15 | 12 | 12 | 12 | 12 |  | 50 Ohms-3 | TOP=L2:L3=L2/L4:L6=L5/L7:BOTTOM=L7 |
| ATTN_LED_DR6_R | 50OHM_Y12MIL | BUS | 5 | 6 | 5 | 10 | 5 | 14 | 6 | 15 | 12 | 12 | 12 | 12 |  | 50 Ohms-3 | TOP=L2:L3=L2/L4:L6=L5/L7:BOTTOM=L7 |
| ATTN_LED_DR6_R | 50OHM_Y12MIL | BUS | 6 | 6 | 5 | 10 | 5 | 14 | 6 | 15 | 12 | 12 | 12 | 12 |  | 50 Ohms-3 | TOP=L2:L3=L2/L4:L6=L5/L7:BOTTOM=L7 |
| ATTN_LED_DR6_R | 50OHM_Y12MIL | BUS | 7 | 6 | 5 | 10 | 5 | 14 | 6 | 15 | 12 | 12 | 12 | 12 |  | 50 Ohms-3 | TOP=L2:L3=L2/L4:L6=L5/L7:BOTTOM=L7 |
| ATTN_LED_DR6_R | 50OHM_Y12MIL | BUS | 8 | 6.75 | 5 | 10 | 5 | 14 | 6 | 15 | 12 | 12 | 12 | 12 |  | 50 Ohms-3 | TOP=L2:L3=L2/L4:L6=L5/L7:BOTTOM=L7 |
| ATTN_LED_DR7_AND | 50OHM_Y12MIL | BUS | 1 | 6.75 | 5 | 10 | 5 | 14 | 6 | 15 | 12 | 12 | 12 | 12 |  | 50 Ohms-3 | TOP=L2:L3=L2/L4:L6=L5/L7:BOTTOM=L7 |
| ATTN_LED_DR7_AND | 50OHM_Y12MIL | BUS | 2 | 6 | 5 | 10 | 5 | 14 | 6 | 15 | 12 | 12 | 12 | 12 |  | 50 Ohms-3 | TOP=L2:L3=L2/L4:L6=L5/L7:BOTTOM=L7 |
| ATTN_LED_DR7_AND | 50OHM_Y12MIL | BUS | 3 | 6 | 5 | 10 | 5 | 14 | 6 | 15 | 12 | 12 | 12 | 12 |  | 50 Ohms-3 | TOP=L2:L3=L2/L4:L6=L5/L7:BOTTOM=L7 |
| ATTN_LED_DR7_AND | 50OHM_Y12MIL | BUS | 4 | 6 | 5 | 10 | 5 | 14 | 6 | 15 | 12 | 12 | 12 | 12 |  | 50 Ohms-3 | TOP=L2:L3=L2/L4:L6=L5/L7:BOTTOM=L7 |
| ATTN_LED_DR7_AND | 50OHM_Y12MIL | BUS | 5 | 6 | 5 | 10 | 5 | 14 | 6 | 15 | 12 | 12 | 12 | 12 |  | 50 Ohms-3 | TOP=L2:L3=L2/L4:L6=L5/L7:BOTTOM=L7 |
| ATTN_LED_DR7_AND | 50OHM_Y12MIL | BUS | 6 | 6 | 5 | 10 | 5 | 14 | 6 | 15 | 12 | 12 | 12 | 12 |  | 50 Ohms-3 | TOP=L2:L3=L2/L4:L6=L5/L7:BOTTOM=L7 |
| ATTN_LED_DR7_AND | 50OHM_Y12MIL | BUS | 7 | 6 | 5 | 10 | 5 | 14 | 6 | 15 | 12 | 12 | 12 | 12 |  | 50 Ohms-3 | TOP=L2:L3=L2/L4:L6=L5/L7:BOTTOM=L7 |
| ATTN_LED_DR7_AND | 50OHM_Y12MIL | BUS | 8 | 6.75 | 5 | 10 | 5 | 14 | 6 | 15 | 12 | 12 | 12 | 12 |  | 50 Ohms-3 | TOP=L2:L3=L2/L4:L6=L5/L7:BOTTOM=L7 |
| ATTN_LED_DR7_AND_R | 50OHM_Y12MIL | BUS | 1 | 6.75 | 5 | 10 | 5 | 14 | 6 | 15 | 12 | 12 | 12 | 12 |  | 50 Ohms-3 | TOP=L2:L3=L2/L4:L6=L5/L7:BOTTOM=L7 |
| ATTN_LED_DR7_AND_R | 50OHM_Y12MIL | BUS | 2 | 6 | 5 | 10 | 5 | 14 | 6 | 15 | 12 | 12 | 12 | 12 |  | 50 Ohms-3 | TOP=L2:L3=L2/L4:L6=L5/L7:BOTTOM=L7 |
| ATTN_LED_DR7_AND_R | 50OHM_Y12MIL | BUS | 3 | 6 | 5 | 10 | 5 | 14 | 6 | 15 | 12 | 12 | 12 | 12 |  | 50 Ohms-3 | TOP=L2:L3=L2/L4:L6=L5/L7:BOTTOM=L7 |
| ATTN_LED_DR7_AND_R | 50OHM_Y12MIL | BUS | 4 | 6 | 5 | 10 | 5 | 14 | 6 | 15 | 12 | 12 | 12 | 12 |  | 50 Ohms-3 | TOP=L2:L3=L2/L4:L6=L5/L7:BOTTOM=L7 |
| ATTN_LED_DR7_AND_R | 50OHM_Y12MIL | BUS | 5 | 6 | 5 | 10 | 5 | 14 | 6 | 15 | 12 | 12 | 12 | 12 |  | 50 Ohms-3 | TOP=L2:L3=L2/L4:L6=L5/L7:BOTTOM=L7 |
| ATTN_LED_DR7_AND_R | 50OHM_Y12MIL | BUS | 6 | 6 | 5 | 10 | 5 | 14 | 6 | 15 | 12 | 12 | 12 | 12 |  | 50 Ohms-3 | TOP=L2:L3=L2/L4:L6=L5/L7:BOTTOM=L7 |
| ATTN_LED_DR7_AND_R | 50OHM_Y12MIL | BUS | 7 | 6 | 5 | 10 | 5 | 14 | 6 | 15 | 12 | 12 | 12 | 12 |  | 50 Ohms-3 | TOP=L2:L3=L2/L4:L6=L5/L7:BOTTOM=L7 |
| ATTN_LED_DR7_AND_R | 50OHM_Y12MIL | BUS | 8 | 6.75 | 5 | 10 | 5 | 14 | 6 | 15 | 12 | 12 | 12 | 12 |  | 50 Ohms-3 | TOP=L2:L3=L2/L4:L6=L5/L7:BOTTOM=L7 |
| ATTN_LED_DR7_MOS_N | 50OHM_Y12MIL | BUS | 1 | 6.75 | 5 | 10 | 5 | 14 | 6 | 15 | 12 | 12 | 12 | 12 |  | 50 Ohms-3 | TOP=L2:L3=L2/L4:L6=L5/L7:BOTTOM=L7 |
| ATTN_LED_DR7_MOS_N | 50OHM_Y12MIL | BUS | 2 | 6 | 5 | 10 | 5 | 14 | 6 | 15 | 12 | 12 | 12 | 12 |  | 50 Ohms-3 | TOP=L2:L3=L2/L4:L6=L5/L7:BOTTOM=L7 |
| ATTN_LED_DR7_MOS_N | 50OHM_Y12MIL | BUS | 3 | 6 | 5 | 10 | 5 | 14 | 6 | 15 | 12 | 12 | 12 | 12 |  | 50 Ohms-3 | TOP=L2:L3=L2/L4:L6=L5/L7:BOTTOM=L7 |
| ATTN_LED_DR7_MOS_N | 50OHM_Y12MIL | BUS | 4 | 6 | 5 | 10 | 5 | 14 | 6 | 15 | 12 | 12 | 12 | 12 |  | 50 Ohms-3 | TOP=L2:L3=L2/L4:L6=L5/L7:BOTTOM=L7 |
| ATTN_LED_DR7_MOS_N | 50OHM_Y12MIL | BUS | 5 | 6 | 5 | 10 | 5 | 14 | 6 | 15 | 12 | 12 | 12 | 12 |  | 50 Ohms-3 | TOP=L2:L3=L2/L4:L6=L5/L7:BOTTOM=L7 |
| ATTN_LED_DR7_MOS_N | 50OHM_Y12MIL | BUS | 6 | 6 | 5 | 10 | 5 | 14 | 6 | 15 | 12 | 12 | 12 | 12 |  | 50 Ohms-3 | TOP=L2:L3=L2/L4:L6=L5/L7:BOTTOM=L7 |
| ATTN_LED_DR7_MOS_N | 50OHM_Y12MIL | BUS | 7 | 6 | 5 | 10 | 5 | 14 | 6 | 15 | 12 | 12 | 12 | 12 |  | 50 Ohms-3 | TOP=L2:L3=L2/L4:L6=L5/L7:BOTTOM=L7 |
| ATTN_LED_DR7_MOS_N | 50OHM_Y12MIL | BUS | 8 | 6.75 | 5 | 10 | 5 | 14 | 6 | 15 | 12 | 12 | 12 | 12 |  | 50 Ohms-3 | TOP=L2:L3=L2/L4:L6=L5/L7:BOTTOM=L7 |
| ATTN_LED_DR7_N | 50OHM_Y12MIL | BUS | 1 | 6.75 | 5 | 10 | 5 | 14 | 6 | 15 | 12 | 12 | 12 | 12 |  | 50 Ohms-3 | TOP=L2:L3=L2/L4:L6=L5/L7:BOTTOM=L7 |
| ATTN_LED_DR7_N | 50OHM_Y12MIL | BUS | 2 | 6 | 5 | 10 | 5 | 14 | 6 | 15 | 12 | 12 | 12 | 12 |  | 50 Ohms-3 | TOP=L2:L3=L2/L4:L6=L5/L7:BOTTOM=L7 |
| ATTN_LED_DR7_N | 50OHM_Y12MIL | BUS | 3 | 6 | 5 | 10 | 5 | 14 | 6 | 15 | 12 | 12 | 12 | 12 |  | 50 Ohms-3 | TOP=L2:L3=L2/L4:L6=L5/L7:BOTTOM=L7 |
| ATTN_LED_DR7_N | 50OHM_Y12MIL | BUS | 4 | 6 | 5 | 10 | 5 | 14 | 6 | 15 | 12 | 12 | 12 | 12 |  | 50 Ohms-3 | TOP=L2:L3=L2/L4:L6=L5/L7:BOTTOM=L7 |
| ATTN_LED_DR7_N | 50OHM_Y12MIL | BUS | 5 | 6 | 5 | 10 | 5 | 14 | 6 | 15 | 12 | 12 | 12 | 12 |  | 50 Ohms-3 | TOP=L2:L3=L2/L4:L6=L5/L7:BOTTOM=L7 |
| ATTN_LED_DR7_N | 50OHM_Y12MIL | BUS | 6 | 6 | 5 | 10 | 5 | 14 | 6 | 15 | 12 | 12 | 12 | 12 |  | 50 Ohms-3 | TOP=L2:L3=L2/L4:L6=L5/L7:BOTTOM=L7 |
| ATTN_LED_DR7_N | 50OHM_Y12MIL | BUS | 7 | 6 | 5 | 10 | 5 | 14 | 6 | 15 | 12 | 12 | 12 | 12 |  | 50 Ohms-3 | TOP=L2:L3=L2/L4:L6=L5/L7:BOTTOM=L7 |
| ATTN_LED_DR7_N | 50OHM_Y12MIL | BUS | 8 | 6.75 | 5 | 10 | 5 | 14 | 6 | 15 | 12 | 12 | 12 | 12 |  | 50 Ohms-3 | TOP=L2:L3=L2/L4:L6=L5/L7:BOTTOM=L7 |
| ATTN_LED_DR7_R | 50OHM_Y12MIL | BUS | 1 | 6.75 | 5 | 10 | 5 | 14 | 6 | 15 | 12 | 12 | 12 | 12 |  | 50 Ohms-3 | TOP=L2:L3=L2/L4:L6=L5/L7:BOTTOM=L7 |
| ATTN_LED_DR7_R | 50OHM_Y12MIL | BUS | 2 | 6 | 5 | 10 | 5 | 14 | 6 | 15 | 12 | 12 | 12 | 12 |  | 50 Ohms-3 | TOP=L2:L3=L2/L4:L6=L5/L7:BOTTOM=L7 |
| ATTN_LED_DR7_R | 50OHM_Y12MIL | BUS | 3 | 6 | 5 | 10 | 5 | 14 | 6 | 15 | 12 | 12 | 12 | 12 |  | 50 Ohms-3 | TOP=L2:L3=L2/L4:L6=L5/L7:BOTTOM=L7 |
| ATTN_LED_DR7_R | 50OHM_Y12MIL | BUS | 4 | 6 | 5 | 10 | 5 | 14 | 6 | 15 | 12 | 12 | 12 | 12 |  | 50 Ohms-3 | TOP=L2:L3=L2/L4:L6=L5/L7:BOTTOM=L7 |
| ATTN_LED_DR7_R | 50OHM_Y12MIL | BUS | 5 | 6 | 5 | 10 | 5 | 14 | 6 | 15 | 12 | 12 | 12 | 12 |  | 50 Ohms-3 | TOP=L2:L3=L2/L4:L6=L5/L7:BOTTOM=L7 |
| ATTN_LED_DR7_R | 50OHM_Y12MIL | BUS | 6 | 6 | 5 | 10 | 5 | 14 | 6 | 15 | 12 | 12 | 12 | 12 |  | 50 Ohms-3 | TOP=L2:L3=L2/L4:L6=L5/L7:BOTTOM=L7 |
| ATTN_LED_DR7_R | 50OHM_Y12MIL | BUS | 7 | 6 | 5 | 10 | 5 | 14 | 6 | 15 | 12 | 12 | 12 | 12 |  | 50 Ohms-3 | TOP=L2:L3=L2/L4:L6=L5/L7:BOTTOM=L7 |
| ATTN_LED_DR7_R | 50OHM_Y12MIL | BUS | 8 | 6.75 | 5 | 10 | 5 | 14 | 6 | 15 | 12 | 12 | 12 | 12 |  | 50 Ohms-3 | TOP=L2:L3=L2/L4:L6=L5/L7:BOTTOM=L7 |
| ATTN_LED_DR8_AND | 50OHM_Y12MIL | BUS | 1 | 6.75 | 5 | 10 | 5 | 14 | 6 | 15 | 12 | 12 | 12 | 12 |  | 50 Ohms-3 | TOP=L2:L3=L2/L4:L6=L5/L7:BOTTOM=L7 |
| ATTN_LED_DR8_AND | 50OHM_Y12MIL | BUS | 2 | 6 | 5 | 10 | 5 | 14 | 6 | 15 | 12 | 12 | 12 | 12 |  | 50 Ohms-3 | TOP=L2:L3=L2/L4:L6=L5/L7:BOTTOM=L7 |
| ATTN_LED_DR8_AND | 50OHM_Y12MIL | BUS | 3 | 6 | 5 | 10 | 5 | 14 | 6 | 15 | 12 | 12 | 12 | 12 |  | 50 Ohms-3 | TOP=L2:L3=L2/L4:L6=L5/L7:BOTTOM=L7 |
| ATTN_LED_DR8_AND | 50OHM_Y12MIL | BUS | 4 | 6 | 5 | 10 | 5 | 14 | 6 | 15 | 12 | 12 | 12 | 12 |  | 50 Ohms-3 | TOP=L2:L3=L2/L4:L6=L5/L7:BOTTOM=L7 |
| ATTN_LED_DR8_AND | 50OHM_Y12MIL | BUS | 5 | 6 | 5 | 10 | 5 | 14 | 6 | 15 | 12 | 12 | 12 | 12 |  | 50 Ohms-3 | TOP=L2:L3=L2/L4:L6=L5/L7:BOTTOM=L7 |
| ATTN_LED_DR8_AND | 50OHM_Y12MIL | BUS | 6 | 6 | 5 | 10 | 5 | 14 | 6 | 15 | 12 | 12 | 12 | 12 |  | 50 Ohms-3 | TOP=L2:L3=L2/L4:L6=L5/L7:BOTTOM=L7 |
| ATTN_LED_DR8_AND | 50OHM_Y12MIL | BUS | 7 | 6 | 5 | 10 | 5 | 14 | 6 | 15 | 12 | 12 | 12 | 12 |  | 50 Ohms-3 | TOP=L2:L3=L2/L4:L6=L5/L7:BOTTOM=L7 |
| ATTN_LED_DR8_AND | 50OHM_Y12MIL | BUS | 8 | 6.75 | 5 | 10 | 5 | 14 | 6 | 15 | 12 | 12 | 12 | 12 |  | 50 Ohms-3 | TOP=L2:L3=L2/L4:L6=L5/L7:BOTTOM=L7 |
| ATTN_LED_DR8_AND_R | 50OHM_Y12MIL | BUS | 1 | 6.75 | 5 | 10 | 5 | 14 | 6 | 15 | 12 | 12 | 12 | 12 |  | 50 Ohms-3 | TOP=L2:L3=L2/L4:L6=L5/L7:BOTTOM=L7 |
| ATTN_LED_DR8_AND_R | 50OHM_Y12MIL | BUS | 2 | 6 | 5 | 10 | 5 | 14 | 6 | 15 | 12 | 12 | 12 | 12 |  | 50 Ohms-3 | TOP=L2:L3=L2/L4:L6=L5/L7:BOTTOM=L7 |
| ATTN_LED_DR8_AND_R | 50OHM_Y12MIL | BUS | 3 | 6 | 5 | 10 | 5 | 14 | 6 | 15 | 12 | 12 | 12 | 12 |  | 50 Ohms-3 | TOP=L2:L3=L2/L4:L6=L5/L7:BOTTOM=L7 |
| ATTN_LED_DR8_AND_R | 50OHM_Y12MIL | BUS | 4 | 6 | 5 | 10 | 5 | 14 | 6 | 15 | 12 | 12 | 12 | 12 |  | 50 Ohms-3 | TOP=L2:L3=L2/L4:L6=L5/L7:BOTTOM=L7 |
| ATTN_LED_DR8_AND_R | 50OHM_Y12MIL | BUS | 5 | 6 | 5 | 10 | 5 | 14 | 6 | 15 | 12 | 12 | 12 | 12 |  | 50 Ohms-3 | TOP=L2:L3=L2/L4:L6=L5/L7:BOTTOM=L7 |
| ATTN_LED_DR8_AND_R | 50OHM_Y12MIL | BUS | 6 | 6 | 5 | 10 | 5 | 14 | 6 | 15 | 12 | 12 | 12 | 12 |  | 50 Ohms-3 | TOP=L2:L3=L2/L4:L6=L5/L7:BOTTOM=L7 |
| ATTN_LED_DR8_AND_R | 50OHM_Y12MIL | BUS | 7 | 6 | 5 | 10 | 5 | 14 | 6 | 15 | 12 | 12 | 12 | 12 |  | 50 Ohms-3 | TOP=L2:L3=L2/L4:L6=L5/L7:BOTTOM=L7 |
| ATTN_LED_DR8_AND_R | 50OHM_Y12MIL | BUS | 8 | 6.75 | 5 | 10 | 5 | 14 | 6 | 15 | 12 | 12 | 12 | 12 |  | 50 Ohms-3 | TOP=L2:L3=L2/L4:L6=L5/L7:BOTTOM=L7 |
| ATTN_LED_DR8_MOS_N | 50OHM_Y12MIL | BUS | 1 | 6.75 | 5 | 10 | 5 | 14 | 6 | 15 | 12 | 12 | 12 | 12 |  | 50 Ohms-3 | TOP=L2:L3=L2/L4:L6=L5/L7:BOTTOM=L7 |
| ATTN_LED_DR8_MOS_N | 50OHM_Y12MIL | BUS | 2 | 6 | 5 | 10 | 5 | 14 | 6 | 15 | 12 | 12 | 12 | 12 |  | 50 Ohms-3 | TOP=L2:L3=L2/L4:L6=L5/L7:BOTTOM=L7 |
| ATTN_LED_DR8_MOS_N | 50OHM_Y12MIL | BUS | 3 | 6 | 5 | 10 | 5 | 14 | 6 | 15 | 12 | 12 | 12 | 12 |  | 50 Ohms-3 | TOP=L2:L3=L2/L4:L6=L5/L7:BOTTOM=L7 |
| ATTN_LED_DR8_MOS_N | 50OHM_Y12MIL | BUS | 4 | 6 | 5 | 10 | 5 | 14 | 6 | 15 | 12 | 12 | 12 | 12 |  | 50 Ohms-3 | TOP=L2:L3=L2/L4:L6=L5/L7:BOTTOM=L7 |
| ATTN_LED_DR8_MOS_N | 50OHM_Y12MIL | BUS | 5 | 6 | 5 | 10 | 5 | 14 | 6 | 15 | 12 | 12 | 12 | 12 |  | 50 Ohms-3 | TOP=L2:L3=L2/L4:L6=L5/L7:BOTTOM=L7 |
| ATTN_LED_DR8_MOS_N | 50OHM_Y12MIL | BUS | 6 | 6 | 5 | 10 | 5 | 14 | 6 | 15 | 12 | 12 | 12 | 12 |  | 50 Ohms-3 | TOP=L2:L3=L2/L4:L6=L5/L7:BOTTOM=L7 |
| ATTN_LED_DR8_MOS_N | 50OHM_Y12MIL | BUS | 7 | 6 | 5 | 10 | 5 | 14 | 6 | 15 | 12 | 12 | 12 | 12 |  | 50 Ohms-3 | TOP=L2:L3=L2/L4:L6=L5/L7:BOTTOM=L7 |
| ATTN_LED_DR8_MOS_N | 50OHM_Y12MIL | BUS | 8 | 6.75 | 5 | 10 | 5 | 14 | 6 | 15 | 12 | 12 | 12 | 12 |  | 50 Ohms-3 | TOP=L2:L3=L2/L4:L6=L5/L7:BOTTOM=L7 |
| ATTN_LED_DR8_N | 50OHM_Y12MIL | BUS | 1 | 6.75 | 5 | 10 | 5 | 14 | 6 | 15 | 12 | 12 | 12 | 12 |  | 50 Ohms-3 | TOP=L2:L3=L2/L4:L6=L5/L7:BOTTOM=L7 |
| ATTN_LED_DR8_N | 50OHM_Y12MIL | BUS | 2 | 6 | 5 | 10 | 5 | 14 | 6 | 15 | 12 | 12 | 12 | 12 |  | 50 Ohms-3 | TOP=L2:L3=L2/L4:L6=L5/L7:BOTTOM=L7 |
| ATTN_LED_DR8_N | 50OHM_Y12MIL | BUS | 3 | 6 | 5 | 10 | 5 | 14 | 6 | 15 | 12 | 12 | 12 | 12 |  | 50 Ohms-3 | TOP=L2:L3=L2/L4:L6=L5/L7:BOTTOM=L7 |
| ATTN_LED_DR8_N | 50OHM_Y12MIL | BUS | 4 | 6 | 5 | 10 | 5 | 14 | 6 | 15 | 12 | 12 | 12 | 12 |  | 50 Ohms-3 | TOP=L2:L3=L2/L4:L6=L5/L7:BOTTOM=L7 |
| ATTN_LED_DR8_N | 50OHM_Y12MIL | BUS | 5 | 6 | 5 | 10 | 5 | 14 | 6 | 15 | 12 | 12 | 12 | 12 |  | 50 Ohms-3 | TOP=L2:L3=L2/L4:L6=L5/L7:BOTTOM=L7 |
| ATTN_LED_DR8_N | 50OHM_Y12MIL | BUS | 6 | 6 | 5 | 10 | 5 | 14 | 6 | 15 | 12 | 12 | 12 | 12 |  | 50 Ohms-3 | TOP=L2:L3=L2/L4:L6=L5/L7:BOTTOM=L7 |
| ATTN_LED_DR8_N | 50OHM_Y12MIL | BUS | 7 | 6 | 5 | 10 | 5 | 14 | 6 | 15 | 12 | 12 | 12 | 12 |  | 50 Ohms-3 | TOP=L2:L3=L2/L4:L6=L5/L7:BOTTOM=L7 |
| ATTN_LED_DR8_N | 50OHM_Y12MIL | BUS | 8 | 6.75 | 5 | 10 | 5 | 14 | 6 | 15 | 12 | 12 | 12 | 12 |  | 50 Ohms-3 | TOP=L2:L3=L2/L4:L6=L5/L7:BOTTOM=L7 |
| ATTN_LED_DR8_R | 50OHM_Y12MIL | BUS | 1 | 6.75 | 5 | 10 | 5 | 14 | 6 | 15 | 12 | 12 | 12 | 12 |  | 50 Ohms-3 | TOP=L2:L3=L2/L4:L6=L5/L7:BOTTOM=L7 |
| ATTN_LED_DR8_R | 50OHM_Y12MIL | BUS | 2 | 6 | 5 | 10 | 5 | 14 | 6 | 15 | 12 | 12 | 12 | 12 |  | 50 Ohms-3 | TOP=L2:L3=L2/L4:L6=L5/L7:BOTTOM=L7 |
| ATTN_LED_DR8_R | 50OHM_Y12MIL | BUS | 3 | 6 | 5 | 10 | 5 | 14 | 6 | 15 | 12 | 12 | 12 | 12 |  | 50 Ohms-3 | TOP=L2:L3=L2/L4:L6=L5/L7:BOTTOM=L7 |
| ATTN_LED_DR8_R | 50OHM_Y12MIL | BUS | 4 | 6 | 5 | 10 | 5 | 14 | 6 | 15 | 12 | 12 | 12 | 12 |  | 50 Ohms-3 | TOP=L2:L3=L2/L4:L6=L5/L7:BOTTOM=L7 |
| ATTN_LED_DR8_R | 50OHM_Y12MIL | BUS | 5 | 6 | 5 | 10 | 5 | 14 | 6 | 15 | 12 | 12 | 12 | 12 |  | 50 Ohms-3 | TOP=L2:L3=L2/L4:L6=L5/L7:BOTTOM=L7 |
| ATTN_LED_DR8_R | 50OHM_Y12MIL | BUS | 6 | 6 | 5 | 10 | 5 | 14 | 6 | 15 | 12 | 12 | 12 | 12 |  | 50 Ohms-3 | TOP=L2:L3=L2/L4:L6=L5/L7:BOTTOM=L7 |
| ATTN_LED_DR8_R | 50OHM_Y12MIL | BUS | 7 | 6 | 5 | 10 | 5 | 14 | 6 | 15 | 12 | 12 | 12 | 12 |  | 50 Ohms-3 | TOP=L2:L3=L2/L4:L6=L5/L7:BOTTOM=L7 |
| ATTN_LED_DR8_R | 50OHM_Y12MIL | BUS | 8 | 6.75 | 5 | 10 | 5 | 14 | 6 | 15 | 12 | 12 | 12 | 12 |  | 50 Ohms-3 | TOP=L2:L3=L2/L4:L6=L5/L7:BOTTOM=L7 |
| ATTN_LED_DR9_AND | 50OHM_Y12MIL | BUS | 1 | 6.75 | 5 | 10 | 5 | 14 | 6 | 15 | 12 | 12 | 12 | 12 |  | 50 Ohms-3 | TOP=L2:L3=L2/L4:L6=L5/L7:BOTTOM=L7 |
| ATTN_LED_DR9_AND | 50OHM_Y12MIL | BUS | 2 | 6 | 5 | 10 | 5 | 14 | 6 | 15 | 12 | 12 | 12 | 12 |  | 50 Ohms-3 | TOP=L2:L3=L2/L4:L6=L5/L7:BOTTOM=L7 |
| ATTN_LED_DR9_AND | 50OHM_Y12MIL | BUS | 3 | 6 | 5 | 10 | 5 | 14 | 6 | 15 | 12 | 12 | 12 | 12 |  | 50 Ohms-3 | TOP=L2:L3=L2/L4:L6=L5/L7:BOTTOM=L7 |
| ATTN_LED_DR9_AND | 50OHM_Y12MIL | BUS | 4 | 6 | 5 | 10 | 5 | 14 | 6 | 15 | 12 | 12 | 12 | 12 |  | 50 Ohms-3 | TOP=L2:L3=L2/L4:L6=L5/L7:BOTTOM=L7 |
| ATTN_LED_DR9_AND | 50OHM_Y12MIL | BUS | 5 | 6 | 5 | 10 | 5 | 14 | 6 | 15 | 12 | 12 | 12 | 12 |  | 50 Ohms-3 | TOP=L2:L3=L2/L4:L6=L5/L7:BOTTOM=L7 |
| ATTN_LED_DR9_AND | 50OHM_Y12MIL | BUS | 6 | 6 | 5 | 10 | 5 | 14 | 6 | 15 | 12 | 12 | 12 | 12 |  | 50 Ohms-3 | TOP=L2:L3=L2/L4:L6=L5/L7:BOTTOM=L7 |
| ATTN_LED_DR9_AND | 50OHM_Y12MIL | BUS | 7 | 6 | 5 | 10 | 5 | 14 | 6 | 15 | 12 | 12 | 12 | 12 |  | 50 Ohms-3 | TOP=L2:L3=L2/L4:L6=L5/L7:BOTTOM=L7 |
| ATTN_LED_DR9_AND | 50OHM_Y12MIL | BUS | 8 | 6.75 | 5 | 10 | 5 | 14 | 6 | 15 | 12 | 12 | 12 | 12 |  | 50 Ohms-3 | TOP=L2:L3=L2/L4:L6=L5/L7:BOTTOM=L7 |
| ATTN_LED_DR9_AND_R | 50OHM_Y12MIL | BUS | 1 | 6.75 | 5 | 10 | 5 | 14 | 6 | 15 | 12 | 12 | 12 | 12 |  | 50 Ohms-3 | TOP=L2:L3=L2/L4:L6=L5/L7:BOTTOM=L7 |
| ATTN_LED_DR9_AND_R | 50OHM_Y12MIL | BUS | 2 | 6 | 5 | 10 | 5 | 14 | 6 | 15 | 12 | 12 | 12 | 12 |  | 50 Ohms-3 | TOP=L2:L3=L2/L4:L6=L5/L7:BOTTOM=L7 |
| ATTN_LED_DR9_AND_R | 50OHM_Y12MIL | BUS | 3 | 6 | 5 | 10 | 5 | 14 | 6 | 15 | 12 | 12 | 12 | 12 |  | 50 Ohms-3 | TOP=L2:L3=L2/L4:L6=L5/L7:BOTTOM=L7 |
| ATTN_LED_DR9_AND_R | 50OHM_Y12MIL | BUS | 4 | 6 | 5 | 10 | 5 | 14 | 6 | 15 | 12 | 12 | 12 | 12 |  | 50 Ohms-3 | TOP=L2:L3=L2/L4:L6=L5/L7:BOTTOM=L7 |
| ATTN_LED_DR9_AND_R | 50OHM_Y12MIL | BUS | 5 | 6 | 5 | 10 | 5 | 14 | 6 | 15 | 12 | 12 | 12 | 12 |  | 50 Ohms-3 | TOP=L2:L3=L2/L4:L6=L5/L7:BOTTOM=L7 |
| ATTN_LED_DR9_AND_R | 50OHM_Y12MIL | BUS | 6 | 6 | 5 | 10 | 5 | 14 | 6 | 15 | 12 | 12 | 12 | 12 |  | 50 Ohms-3 | TOP=L2:L3=L2/L4:L6=L5/L7:BOTTOM=L7 |
| ATTN_LED_DR9_AND_R | 50OHM_Y12MIL | BUS | 7 | 6 | 5 | 10 | 5 | 14 | 6 | 15 | 12 | 12 | 12 | 12 |  | 50 Ohms-3 | TOP=L2:L3=L2/L4:L6=L5/L7:BOTTOM=L7 |
| ATTN_LED_DR9_AND_R | 50OHM_Y12MIL | BUS | 8 | 6.75 | 5 | 10 | 5 | 14 | 6 | 15 | 12 | 12 | 12 | 12 |  | 50 Ohms-3 | TOP=L2:L3=L2/L4:L6=L5/L7:BOTTOM=L7 |
| ATTN_LED_DR9_MOS_N | 50OHM_Y12MIL | BUS | 1 | 6.75 | 5 | 10 | 5 | 14 | 6 | 15 | 12 | 12 | 12 | 12 |  | 50 Ohms-3 | TOP=L2:L3=L2/L4:L6=L5/L7:BOTTOM=L7 |
| ATTN_LED_DR9_MOS_N | 50OHM_Y12MIL | BUS | 2 | 6 | 5 | 10 | 5 | 14 | 6 | 15 | 12 | 12 | 12 | 12 |  | 50 Ohms-3 | TOP=L2:L3=L2/L4:L6=L5/L7:BOTTOM=L7 |
| ATTN_LED_DR9_MOS_N | 50OHM_Y12MIL | BUS | 3 | 6 | 5 | 10 | 5 | 14 | 6 | 15 | 12 | 12 | 12 | 12 |  | 50 Ohms-3 | TOP=L2:L3=L2/L4:L6=L5/L7:BOTTOM=L7 |
| ATTN_LED_DR9_MOS_N | 50OHM_Y12MIL | BUS | 4 | 6 | 5 | 10 | 5 | 14 | 6 | 15 | 12 | 12 | 12 | 12 |  | 50 Ohms-3 | TOP=L2:L3=L2/L4:L6=L5/L7:BOTTOM=L7 |
| ATTN_LED_DR9_MOS_N | 50OHM_Y12MIL | BUS | 5 | 6 | 5 | 10 | 5 | 14 | 6 | 15 | 12 | 12 | 12 | 12 |  | 50 Ohms-3 | TOP=L2:L3=L2/L4:L6=L5/L7:BOTTOM=L7 |
| ATTN_LED_DR9_MOS_N | 50OHM_Y12MIL | BUS | 6 | 6 | 5 | 10 | 5 | 14 | 6 | 15 | 12 | 12 | 12 | 12 |  | 50 Ohms-3 | TOP=L2:L3=L2/L4:L6=L5/L7:BOTTOM=L7 |
| ATTN_LED_DR9_MOS_N | 50OHM_Y12MIL | BUS | 7 | 6 | 5 | 10 | 5 | 14 | 6 | 15 | 12 | 12 | 12 | 12 |  | 50 Ohms-3 | TOP=L2:L3=L2/L4:L6=L5/L7:BOTTOM=L7 |
| ATTN_LED_DR9_MOS_N | 50OHM_Y12MIL | BUS | 8 | 6.75 | 5 | 10 | 5 | 14 | 6 | 15 | 12 | 12 | 12 | 12 |  | 50 Ohms-3 | TOP=L2:L3=L2/L4:L6=L5/L7:BOTTOM=L7 |
| ATTN_LED_DR9_N | 50OHM_Y12MIL | BUS | 1 | 6.75 | 5 | 10 | 5 | 14 | 6 | 15 | 12 | 12 | 12 | 12 |  | 50 Ohms-3 | TOP=L2:L3=L2/L4:L6=L5/L7:BOTTOM=L7 |
| ATTN_LED_DR9_N | 50OHM_Y12MIL | BUS | 2 | 6 | 5 | 10 | 5 | 14 | 6 | 15 | 12 | 12 | 12 | 12 |  | 50 Ohms-3 | TOP=L2:L3=L2/L4:L6=L5/L7:BOTTOM=L7 |
| ATTN_LED_DR9_N | 50OHM_Y12MIL | BUS | 3 | 6 | 5 | 10 | 5 | 14 | 6 | 15 | 12 | 12 | 12 | 12 |  | 50 Ohms-3 | TOP=L2:L3=L2/L4:L6=L5/L7:BOTTOM=L7 |
| ATTN_LED_DR9_N | 50OHM_Y12MIL | BUS | 4 | 6 | 5 | 10 | 5 | 14 | 6 | 15 | 12 | 12 | 12 | 12 |  | 50 Ohms-3 | TOP=L2:L3=L2/L4:L6=L5/L7:BOTTOM=L7 |
| ATTN_LED_DR9_N | 50OHM_Y12MIL | BUS | 5 | 6 | 5 | 10 | 5 | 14 | 6 | 15 | 12 | 12 | 12 | 12 |  | 50 Ohms-3 | TOP=L2:L3=L2/L4:L6=L5/L7:BOTTOM=L7 |
| ATTN_LED_DR9_N | 50OHM_Y12MIL | BUS | 6 | 6 | 5 | 10 | 5 | 14 | 6 | 15 | 12 | 12 | 12 | 12 |  | 50 Ohms-3 | TOP=L2:L3=L2/L4:L6=L5/L7:BOTTOM=L7 |
| ATTN_LED_DR9_N | 50OHM_Y12MIL | BUS | 7 | 6 | 5 | 10 | 5 | 14 | 6 | 15 | 12 | 12 | 12 | 12 |  | 50 Ohms-3 | TOP=L2:L3=L2/L4:L6=L5/L7:BOTTOM=L7 |
| ATTN_LED_DR9_N | 50OHM_Y12MIL | BUS | 8 | 6.75 | 5 | 10 | 5 | 14 | 6 | 15 | 12 | 12 | 12 | 12 |  | 50 Ohms-3 | TOP=L2:L3=L2/L4:L6=L5/L7:BOTTOM=L7 |
| ATTN_LED_DR9_R | 50OHM_Y12MIL | BUS | 1 | 6.75 | 5 | 10 | 5 | 14 | 6 | 15 | 12 | 12 | 12 | 12 |  | 50 Ohms-3 | TOP=L2:L3=L2/L4:L6=L5/L7:BOTTOM=L7 |
| ATTN_LED_DR9_R | 50OHM_Y12MIL | BUS | 2 | 6 | 5 | 10 | 5 | 14 | 6 | 15 | 12 | 12 | 12 | 12 |  | 50 Ohms-3 | TOP=L2:L3=L2/L4:L6=L5/L7:BOTTOM=L7 |
| ATTN_LED_DR9_R | 50OHM_Y12MIL | BUS | 3 | 6 | 5 | 10 | 5 | 14 | 6 | 15 | 12 | 12 | 12 | 12 |  | 50 Ohms-3 | TOP=L2:L3=L2/L4:L6=L5/L7:BOTTOM=L7 |
| ATTN_LED_DR9_R | 50OHM_Y12MIL | BUS | 4 | 6 | 5 | 10 | 5 | 14 | 6 | 15 | 12 | 12 | 12 | 12 |  | 50 Ohms-3 | TOP=L2:L3=L2/L4:L6=L5/L7:BOTTOM=L7 |
| ATTN_LED_DR9_R | 50OHM_Y12MIL | BUS | 5 | 6 | 5 | 10 | 5 | 14 | 6 | 15 | 12 | 12 | 12 | 12 |  | 50 Ohms-3 | TOP=L2:L3=L2/L4:L6=L5/L7:BOTTOM=L7 |
| ATTN_LED_DR9_R | 50OHM_Y12MIL | BUS | 6 | 6 | 5 | 10 | 5 | 14 | 6 | 15 | 12 | 12 | 12 | 12 |  | 50 Ohms-3 | TOP=L2:L3=L2/L4:L6=L5/L7:BOTTOM=L7 |
| ATTN_LED_DR9_R | 50OHM_Y12MIL | BUS | 7 | 6 | 5 | 10 | 5 | 14 | 6 | 15 | 12 | 12 | 12 | 12 |  | 50 Ohms-3 | TOP=L2:L3=L2/L4:L6=L5/L7:BOTTOM=L7 |
| ATTN_LED_DR9_R | 50OHM_Y12MIL | BUS | 8 | 6.75 | 5 | 10 | 5 | 14 | 6 | 15 | 12 | 12 | 12 | 12 |  | 50 Ohms-3 | TOP=L2:L3=L2/L4:L6=L5/L7:BOTTOM=L7 |
| CLK_BUF_EU1_100M_133M# | 50OHM_Y12MIL | BUS | 1 | 6.75 | 5 | 10 | 5 | 14 | 6 | 15 | 12 | 12 | 12 | 12 |  | 50 Ohms-3 | TOP=L2:L3=L2/L4:L6=L5/L7:BOTTOM=L7 |
| CLK_BUF_EU1_100M_133M# | 50OHM_Y12MIL | BUS | 2 | 6 | 5 | 10 | 5 | 14 | 6 | 15 | 12 | 12 | 12 | 12 |  | 50 Ohms-3 | TOP=L2:L3=L2/L4:L6=L5/L7:BOTTOM=L7 |
| CLK_BUF_EU1_100M_133M# | 50OHM_Y12MIL | BUS | 3 | 6 | 5 | 10 | 5 | 14 | 6 | 15 | 12 | 12 | 12 | 12 |  | 50 Ohms-3 | TOP=L2:L3=L2/L4:L6=L5/L7:BOTTOM=L7 |
| CLK_BUF_EU1_100M_133M# | 50OHM_Y12MIL | BUS | 4 | 6 | 5 | 10 | 5 | 14 | 6 | 15 | 12 | 12 | 12 | 12 |  | 50 Ohms-3 | TOP=L2:L3=L2/L4:L6=L5/L7:BOTTOM=L7 |
| CLK_BUF_EU1_100M_133M# | 50OHM_Y12MIL | BUS | 5 | 6 | 5 | 10 | 5 | 14 | 6 | 15 | 12 | 12 | 12 | 12 |  | 50 Ohms-3 | TOP=L2:L3=L2/L4:L6=L5/L7:BOTTOM=L7 |
| CLK_BUF_EU1_100M_133M# | 50OHM_Y12MIL | BUS | 6 | 6 | 5 | 10 | 5 | 14 | 6 | 15 | 12 | 12 | 12 | 12 |  | 50 Ohms-3 | TOP=L2:L3=L2/L4:L6=L5/L7:BOTTOM=L7 |
| CLK_BUF_EU1_100M_133M# | 50OHM_Y12MIL | BUS | 7 | 6 | 5 | 10 | 5 | 14 | 6 | 15 | 12 | 12 | 12 | 12 |  | 50 Ohms-3 | TOP=L2:L3=L2/L4:L6=L5/L7:BOTTOM=L7 |
| CLK_BUF_EU1_100M_133M# | 50OHM_Y12MIL | BUS | 8 | 6.75 | 5 | 10 | 5 | 14 | 6 | 15 | 12 | 12 | 12 | 12 |  | 50 Ohms-3 | TOP=L2:L3=L2/L4:L6=L5/L7:BOTTOM=L7 |
| CLK_BUF_EU1_HIBW_BYPM_LOBW# | 50OHM_Y12MIL | BUS | 1 | 6.75 | 5 | 10 | 5 | 14 | 6 | 15 | 12 | 12 | 12 | 12 |  | 50 Ohms-3 | TOP=L2:L3=L2/L4:L6=L5/L7:BOTTOM=L7 |
| CLK_BUF_EU1_HIBW_BYPM_LOBW# | 50OHM_Y12MIL | BUS | 2 | 6 | 5 | 10 | 5 | 14 | 6 | 15 | 12 | 12 | 12 | 12 |  | 50 Ohms-3 | TOP=L2:L3=L2/L4:L6=L5/L7:BOTTOM=L7 |
| CLK_BUF_EU1_HIBW_BYPM_LOBW# | 50OHM_Y12MIL | BUS | 3 | 6 | 5 | 10 | 5 | 14 | 6 | 15 | 12 | 12 | 12 | 12 |  | 50 Ohms-3 | TOP=L2:L3=L2/L4:L6=L5/L7:BOTTOM=L7 |
| CLK_BUF_EU1_HIBW_BYPM_LOBW# | 50OHM_Y12MIL | BUS | 4 | 6 | 5 | 10 | 5 | 14 | 6 | 15 | 12 | 12 | 12 | 12 |  | 50 Ohms-3 | TOP=L2:L3=L2/L4:L6=L5/L7:BOTTOM=L7 |
| CLK_BUF_EU1_HIBW_BYPM_LOBW# | 50OHM_Y12MIL | BUS | 5 | 6 | 5 | 10 | 5 | 14 | 6 | 15 | 12 | 12 | 12 | 12 |  | 50 Ohms-3 | TOP=L2:L3=L2/L4:L6=L5/L7:BOTTOM=L7 |
| CLK_BUF_EU1_HIBW_BYPM_LOBW# | 50OHM_Y12MIL | BUS | 6 | 6 | 5 | 10 | 5 | 14 | 6 | 15 | 12 | 12 | 12 | 12 |  | 50 Ohms-3 | TOP=L2:L3=L2/L4:L6=L5/L7:BOTTOM=L7 |
| CLK_BUF_EU1_HIBW_BYPM_LOBW# | 50OHM_Y12MIL | BUS | 7 | 6 | 5 | 10 | 5 | 14 | 6 | 15 | 12 | 12 | 12 | 12 |  | 50 Ohms-3 | TOP=L2:L3=L2/L4:L6=L5/L7:BOTTOM=L7 |
| CLK_BUF_EU1_HIBW_BYPM_LOBW# | 50OHM_Y12MIL | BUS | 8 | 6.75 | 5 | 10 | 5 | 14 | 6 | 15 | 12 | 12 | 12 | 12 |  | 50 Ohms-3 | TOP=L2:L3=L2/L4:L6=L5/L7:BOTTOM=L7 |
| CLK_BUF_EU1_SMB_A0_TRI | 50OHM_Y12MIL | BUS | 1 | 6.75 | 5 | 10 | 5 | 14 | 6 | 15 | 12 | 12 | 12 | 12 |  | 50 Ohms-3 | TOP=L2:L3=L2/L4:L6=L5/L7:BOTTOM=L7 |
| CLK_BUF_EU1_SMB_A0_TRI | 50OHM_Y12MIL | BUS | 2 | 6 | 5 | 10 | 5 | 14 | 6 | 15 | 12 | 12 | 12 | 12 |  | 50 Ohms-3 | TOP=L2:L3=L2/L4:L6=L5/L7:BOTTOM=L7 |
| CLK_BUF_EU1_SMB_A0_TRI | 50OHM_Y12MIL | BUS | 3 | 6 | 5 | 10 | 5 | 14 | 6 | 15 | 12 | 12 | 12 | 12 |  | 50 Ohms-3 | TOP=L2:L3=L2/L4:L6=L5/L7:BOTTOM=L7 |
| CLK_BUF_EU1_SMB_A0_TRI | 50OHM_Y12MIL | BUS | 4 | 6 | 5 | 10 | 5 | 14 | 6 | 15 | 12 | 12 | 12 | 12 |  | 50 Ohms-3 | TOP=L2:L3=L2/L4:L6=L5/L7:BOTTOM=L7 |
| CLK_BUF_EU1_SMB_A0_TRI | 50OHM_Y12MIL | BUS | 5 | 6 | 5 | 10 | 5 | 14 | 6 | 15 | 12 | 12 | 12 | 12 |  | 50 Ohms-3 | TOP=L2:L3=L2/L4:L6=L5/L7:BOTTOM=L7 |
| CLK_BUF_EU1_SMB_A0_TRI | 50OHM_Y12MIL | BUS | 6 | 6 | 5 | 10 | 5 | 14 | 6 | 15 | 12 | 12 | 12 | 12 |  | 50 Ohms-3 | TOP=L2:L3=L2/L4:L6=L5/L7:BOTTOM=L7 |
| CLK_BUF_EU1_SMB_A0_TRI | 50OHM_Y12MIL | BUS | 7 | 6 | 5 | 10 | 5 | 14 | 6 | 15 | 12 | 12 | 12 | 12 |  | 50 Ohms-3 | TOP=L2:L3=L2/L4:L6=L5/L7:BOTTOM=L7 |
| CLK_BUF_EU1_SMB_A0_TRI | 50OHM_Y12MIL | BUS | 8 | 6.75 | 5 | 10 | 5 | 14 | 6 | 15 | 12 | 12 | 12 | 12 |  | 50 Ohms-3 | TOP=L2:L3=L2/L4:L6=L5/L7:BOTTOM=L7 |
| CLK_BUF_EU1_SMB_A1_TRI | 50OHM_Y12MIL | BUS | 1 | 6.75 | 5 | 10 | 5 | 14 | 6 | 15 | 12 | 12 | 12 | 12 |  | 50 Ohms-3 | TOP=L2:L3=L2/L4:L6=L5/L7:BOTTOM=L7 |
| CLK_BUF_EU1_SMB_A1_TRI | 50OHM_Y12MIL | BUS | 2 | 6 | 5 | 10 | 5 | 14 | 6 | 15 | 12 | 12 | 12 | 12 |  | 50 Ohms-3 | TOP=L2:L3=L2/L4:L6=L5/L7:BOTTOM=L7 |
| CLK_BUF_EU1_SMB_A1_TRI | 50OHM_Y12MIL | BUS | 3 | 6 | 5 | 10 | 5 | 14 | 6 | 15 | 12 | 12 | 12 | 12 |  | 50 Ohms-3 | TOP=L2:L3=L2/L4:L6=L5/L7:BOTTOM=L7 |
| CLK_BUF_EU1_SMB_A1_TRI | 50OHM_Y12MIL | BUS | 4 | 6 | 5 | 10 | 5 | 14 | 6 | 15 | 12 | 12 | 12 | 12 |  | 50 Ohms-3 | TOP=L2:L3=L2/L4:L6=L5/L7:BOTTOM=L7 |
| CLK_BUF_EU1_SMB_A1_TRI | 50OHM_Y12MIL | BUS | 5 | 6 | 5 | 10 | 5 | 14 | 6 | 15 | 12 | 12 | 12 | 12 |  | 50 Ohms-3 | TOP=L2:L3=L2/L4:L6=L5/L7:BOTTOM=L7 |
| CLK_BUF_EU1_SMB_A1_TRI | 50OHM_Y12MIL | BUS | 6 | 6 | 5 | 10 | 5 | 14 | 6 | 15 | 12 | 12 | 12 | 12 |  | 50 Ohms-3 | TOP=L2:L3=L2/L4:L6=L5/L7:BOTTOM=L7 |
| CLK_BUF_EU1_SMB_A1_TRI | 50OHM_Y12MIL | BUS | 7 | 6 | 5 | 10 | 5 | 14 | 6 | 15 | 12 | 12 | 12 | 12 |  | 50 Ohms-3 | TOP=L2:L3=L2/L4:L6=L5/L7:BOTTOM=L7 |
| CLK_BUF_EU1_SMB_A1_TRI | 50OHM_Y12MIL | BUS | 8 | 6.75 | 5 | 10 | 5 | 14 | 6 | 15 | 12 | 12 | 12 | 12 |  | 50 Ohms-3 | TOP=L2:L3=L2/L4:L6=L5/L7:BOTTOM=L7 |
| CLK_BUF_EU2_100M_133M# | 50OHM_Y12MIL | BUS | 1 | 6.75 | 5 | 10 | 5 | 14 | 6 | 15 | 12 | 12 | 12 | 12 |  | 50 Ohms-3 | TOP=L2:L3=L2/L4:L6=L5/L7:BOTTOM=L7 |
| CLK_BUF_EU2_100M_133M# | 50OHM_Y12MIL | BUS | 2 | 6 | 5 | 10 | 5 | 14 | 6 | 15 | 12 | 12 | 12 | 12 |  | 50 Ohms-3 | TOP=L2:L3=L2/L4:L6=L5/L7:BOTTOM=L7 |
| CLK_BUF_EU2_100M_133M# | 50OHM_Y12MIL | BUS | 3 | 6 | 5 | 10 | 5 | 14 | 6 | 15 | 12 | 12 | 12 | 12 |  | 50 Ohms-3 | TOP=L2:L3=L2/L4:L6=L5/L7:BOTTOM=L7 |
| CLK_BUF_EU2_100M_133M# | 50OHM_Y12MIL | BUS | 4 | 6 | 5 | 10 | 5 | 14 | 6 | 15 | 12 | 12 | 12 | 12 |  | 50 Ohms-3 | TOP=L2:L3=L2/L4:L6=L5/L7:BOTTOM=L7 |
| CLK_BUF_EU2_100M_133M# | 50OHM_Y12MIL | BUS | 5 | 6 | 5 | 10 | 5 | 14 | 6 | 15 | 12 | 12 | 12 | 12 |  | 50 Ohms-3 | TOP=L2:L3=L2/L4:L6=L5/L7:BOTTOM=L7 |
| CLK_BUF_EU2_100M_133M# | 50OHM_Y12MIL | BUS | 6 | 6 | 5 | 10 | 5 | 14 | 6 | 15 | 12 | 12 | 12 | 12 |  | 50 Ohms-3 | TOP=L2:L3=L2/L4:L6=L5/L7:BOTTOM=L7 |
| CLK_BUF_EU2_100M_133M# | 50OHM_Y12MIL | BUS | 7 | 6 | 5 | 10 | 5 | 14 | 6 | 15 | 12 | 12 | 12 | 12 |  | 50 Ohms-3 | TOP=L2:L3=L2/L4:L6=L5/L7:BOTTOM=L7 |
| CLK_BUF_EU2_100M_133M# | 50OHM_Y12MIL | BUS | 8 | 6.75 | 5 | 10 | 5 | 14 | 6 | 15 | 12 | 12 | 12 | 12 |  | 50 Ohms-3 | TOP=L2:L3=L2/L4:L6=L5/L7:BOTTOM=L7 |
| CLK_BUF_EU2_HIBW_BYPM_LOBW# | 50OHM_Y12MIL | BUS | 1 | 6.75 | 5 | 10 | 5 | 14 | 6 | 15 | 12 | 12 | 12 | 12 |  | 50 Ohms-3 | TOP=L2:L3=L2/L4:L6=L5/L7:BOTTOM=L7 |
| CLK_BUF_EU2_HIBW_BYPM_LOBW# | 50OHM_Y12MIL | BUS | 2 | 6 | 5 | 10 | 5 | 14 | 6 | 15 | 12 | 12 | 12 | 12 |  | 50 Ohms-3 | TOP=L2:L3=L2/L4:L6=L5/L7:BOTTOM=L7 |
| CLK_BUF_EU2_HIBW_BYPM_LOBW# | 50OHM_Y12MIL | BUS | 3 | 6 | 5 | 10 | 5 | 14 | 6 | 15 | 12 | 12 | 12 | 12 |  | 50 Ohms-3 | TOP=L2:L3=L2/L4:L6=L5/L7:BOTTOM=L7 |
| CLK_BUF_EU2_HIBW_BYPM_LOBW# | 50OHM_Y12MIL | BUS | 4 | 6 | 5 | 10 | 5 | 14 | 6 | 15 | 12 | 12 | 12 | 12 |  | 50 Ohms-3 | TOP=L2:L3=L2/L4:L6=L5/L7:BOTTOM=L7 |
| CLK_BUF_EU2_HIBW_BYPM_LOBW# | 50OHM_Y12MIL | BUS | 5 | 6 | 5 | 10 | 5 | 14 | 6 | 15 | 12 | 12 | 12 | 12 |  | 50 Ohms-3 | TOP=L2:L3=L2/L4:L6=L5/L7:BOTTOM=L7 |
| CLK_BUF_EU2_HIBW_BYPM_LOBW# | 50OHM_Y12MIL | BUS | 6 | 6 | 5 | 10 | 5 | 14 | 6 | 15 | 12 | 12 | 12 | 12 |  | 50 Ohms-3 | TOP=L2:L3=L2/L4:L6=L5/L7:BOTTOM=L7 |
| CLK_BUF_EU2_HIBW_BYPM_LOBW# | 50OHM_Y12MIL | BUS | 7 | 6 | 5 | 10 | 5 | 14 | 6 | 15 | 12 | 12 | 12 | 12 |  | 50 Ohms-3 | TOP=L2:L3=L2/L4:L6=L5/L7:BOTTOM=L7 |
| CLK_BUF_EU2_HIBW_BYPM_LOBW# | 50OHM_Y12MIL | BUS | 8 | 6.75 | 5 | 10 | 5 | 14 | 6 | 15 | 12 | 12 | 12 | 12 |  | 50 Ohms-3 | TOP=L2:L3=L2/L4:L6=L5/L7:BOTTOM=L7 |
| CLK_BUF_EU2_SMB_A0_TRI | 50OHM_Y12MIL | BUS | 1 | 6.75 | 5 | 10 | 5 | 14 | 6 | 15 | 12 | 12 | 12 | 12 |  | 50 Ohms-3 | TOP=L2:L3=L2/L4:L6=L5/L7:BOTTOM=L7 |
| CLK_BUF_EU2_SMB_A0_TRI | 50OHM_Y12MIL | BUS | 2 | 6 | 5 | 10 | 5 | 14 | 6 | 15 | 12 | 12 | 12 | 12 |  | 50 Ohms-3 | TOP=L2:L3=L2/L4:L6=L5/L7:BOTTOM=L7 |
| CLK_BUF_EU2_SMB_A0_TRI | 50OHM_Y12MIL | BUS | 3 | 6 | 5 | 10 | 5 | 14 | 6 | 15 | 12 | 12 | 12 | 12 |  | 50 Ohms-3 | TOP=L2:L3=L2/L4:L6=L5/L7:BOTTOM=L7 |
| CLK_BUF_EU2_SMB_A0_TRI | 50OHM_Y12MIL | BUS | 4 | 6 | 5 | 10 | 5 | 14 | 6 | 15 | 12 | 12 | 12 | 12 |  | 50 Ohms-3 | TOP=L2:L3=L2/L4:L6=L5/L7:BOTTOM=L7 |
| CLK_BUF_EU2_SMB_A0_TRI | 50OHM_Y12MIL | BUS | 5 | 6 | 5 | 10 | 5 | 14 | 6 | 15 | 12 | 12 | 12 | 12 |  | 50 Ohms-3 | TOP=L2:L3=L2/L4:L6=L5/L7:BOTTOM=L7 |
| CLK_BUF_EU2_SMB_A0_TRI | 50OHM_Y12MIL | BUS | 6 | 6 | 5 | 10 | 5 | 14 | 6 | 15 | 12 | 12 | 12 | 12 |  | 50 Ohms-3 | TOP=L2:L3=L2/L4:L6=L5/L7:BOTTOM=L7 |
| CLK_BUF_EU2_SMB_A0_TRI | 50OHM_Y12MIL | BUS | 7 | 6 | 5 | 10 | 5 | 14 | 6 | 15 | 12 | 12 | 12 | 12 |  | 50 Ohms-3 | TOP=L2:L3=L2/L4:L6=L5/L7:BOTTOM=L7 |
| CLK_BUF_EU2_SMB_A0_TRI | 50OHM_Y12MIL | BUS | 8 | 6.75 | 5 | 10 | 5 | 14 | 6 | 15 | 12 | 12 | 12 | 12 |  | 50 Ohms-3 | TOP=L2:L3=L2/L4:L6=L5/L7:BOTTOM=L7 |
| CLK_BUF_EU2_SMB_A1_TRI | 50OHM_Y12MIL | BUS | 1 | 6.75 | 5 | 10 | 5 | 14 | 6 | 15 | 12 | 12 | 12 | 12 |  | 50 Ohms-3 | TOP=L2:L3=L2/L4:L6=L5/L7:BOTTOM=L7 |
| CLK_BUF_EU2_SMB_A1_TRI | 50OHM_Y12MIL | BUS | 2 | 6 | 5 | 10 | 5 | 14 | 6 | 15 | 12 | 12 | 12 | 12 |  | 50 Ohms-3 | TOP=L2:L3=L2/L4:L6=L5/L7:BOTTOM=L7 |
| CLK_BUF_EU2_SMB_A1_TRI | 50OHM_Y12MIL | BUS | 3 | 6 | 5 | 10 | 5 | 14 | 6 | 15 | 12 | 12 | 12 | 12 |  | 50 Ohms-3 | TOP=L2:L3=L2/L4:L6=L5/L7:BOTTOM=L7 |
| CLK_BUF_EU2_SMB_A1_TRI | 50OHM_Y12MIL | BUS | 4 | 6 | 5 | 10 | 5 | 14 | 6 | 15 | 12 | 12 | 12 | 12 |  | 50 Ohms-3 | TOP=L2:L3=L2/L4:L6=L5/L7:BOTTOM=L7 |
| CLK_BUF_EU2_SMB_A1_TRI | 50OHM_Y12MIL | BUS | 5 | 6 | 5 | 10 | 5 | 14 | 6 | 15 | 12 | 12 | 12 | 12 |  | 50 Ohms-3 | TOP=L2:L3=L2/L4:L6=L5/L7:BOTTOM=L7 |
| CLK_BUF_EU2_SMB_A1_TRI | 50OHM_Y12MIL | BUS | 6 | 6 | 5 | 10 | 5 | 14 | 6 | 15 | 12 | 12 | 12 | 12 |  | 50 Ohms-3 | TOP=L2:L3=L2/L4:L6=L5/L7:BOTTOM=L7 |
| CLK_BUF_EU2_SMB_A1_TRI | 50OHM_Y12MIL | BUS | 7 | 6 | 5 | 10 | 5 | 14 | 6 | 15 | 12 | 12 | 12 | 12 |  | 50 Ohms-3 | TOP=L2:L3=L2/L4:L6=L5/L7:BOTTOM=L7 |
| CLK_BUF_EU2_SMB_A1_TRI | 50OHM_Y12MIL | BUS | 8 | 6.75 | 5 | 10 | 5 | 14 | 6 | 15 | 12 | 12 | 12 | 12 |  | 50 Ohms-3 | TOP=L2:L3=L2/L4:L6=L5/L7:BOTTOM=L7 |
| CLK_BUF_EU3_100M_133M# | 50OHM_Y12MIL | BUS | 1 | 6.75 | 5 | 10 | 5 | 14 | 6 | 15 | 12 | 12 | 12 | 12 |  | 50 Ohms-3 | TOP=L2:L3=L2/L4:L6=L5/L7:BOTTOM=L7 |
| CLK_BUF_EU3_100M_133M# | 50OHM_Y12MIL | BUS | 2 | 6 | 5 | 10 | 5 | 14 | 6 | 15 | 12 | 12 | 12 | 12 |  | 50 Ohms-3 | TOP=L2:L3=L2/L4:L6=L5/L7:BOTTOM=L7 |
| CLK_BUF_EU3_100M_133M# | 50OHM_Y12MIL | BUS | 3 | 6 | 5 | 10 | 5 | 14 | 6 | 15 | 12 | 12 | 12 | 12 |  | 50 Ohms-3 | TOP=L2:L3=L2/L4:L6=L5/L7:BOTTOM=L7 |
| CLK_BUF_EU3_100M_133M# | 50OHM_Y12MIL | BUS | 4 | 6 | 5 | 10 | 5 | 14 | 6 | 15 | 12 | 12 | 12 | 12 |  | 50 Ohms-3 | TOP=L2:L3=L2/L4:L6=L5/L7:BOTTOM=L7 |
| CLK_BUF_EU3_100M_133M# | 50OHM_Y12MIL | BUS | 5 | 6 | 5 | 10 | 5 | 14 | 6 | 15 | 12 | 12 | 12 | 12 |  | 50 Ohms-3 | TOP=L2:L3=L2/L4:L6=L5/L7:BOTTOM=L7 |
| CLK_BUF_EU3_100M_133M# | 50OHM_Y12MIL | BUS | 6 | 6 | 5 | 10 | 5 | 14 | 6 | 15 | 12 | 12 | 12 | 12 |  | 50 Ohms-3 | TOP=L2:L3=L2/L4:L6=L5/L7:BOTTOM=L7 |
| CLK_BUF_EU3_100M_133M# | 50OHM_Y12MIL | BUS | 7 | 6 | 5 | 10 | 5 | 14 | 6 | 15 | 12 | 12 | 12 | 12 |  | 50 Ohms-3 | TOP=L2:L3=L2/L4:L6=L5/L7:BOTTOM=L7 |
| CLK_BUF_EU3_100M_133M# | 50OHM_Y12MIL | BUS | 8 | 6.75 | 5 | 10 | 5 | 14 | 6 | 15 | 12 | 12 | 12 | 12 |  | 50 Ohms-3 | TOP=L2:L3=L2/L4:L6=L5/L7:BOTTOM=L7 |
| CLK_BUF_EU3_HIBW_BYPM_LOBW# | 50OHM_Y12MIL | BUS | 1 | 6.75 | 5 | 10 | 5 | 14 | 6 | 15 | 12 | 12 | 12 | 12 |  | 50 Ohms-3 | TOP=L2:L3=L2/L4:L6=L5/L7:BOTTOM=L7 |
| CLK_BUF_EU3_HIBW_BYPM_LOBW# | 50OHM_Y12MIL | BUS | 2 | 6 | 5 | 10 | 5 | 14 | 6 | 15 | 12 | 12 | 12 | 12 |  | 50 Ohms-3 | TOP=L2:L3=L2/L4:L6=L5/L7:BOTTOM=L7 |
| CLK_BUF_EU3_HIBW_BYPM_LOBW# | 50OHM_Y12MIL | BUS | 3 | 6 | 5 | 10 | 5 | 14 | 6 | 15 | 12 | 12 | 12 | 12 |  | 50 Ohms-3 | TOP=L2:L3=L2/L4:L6=L5/L7:BOTTOM=L7 |
| CLK_BUF_EU3_HIBW_BYPM_LOBW# | 50OHM_Y12MIL | BUS | 4 | 6 | 5 | 10 | 5 | 14 | 6 | 15 | 12 | 12 | 12 | 12 |  | 50 Ohms-3 | TOP=L2:L3=L2/L4:L6=L5/L7:BOTTOM=L7 |
| CLK_BUF_EU3_HIBW_BYPM_LOBW# | 50OHM_Y12MIL | BUS | 5 | 6 | 5 | 10 | 5 | 14 | 6 | 15 | 12 | 12 | 12 | 12 |  | 50 Ohms-3 | TOP=L2:L3=L2/L4:L6=L5/L7:BOTTOM=L7 |
| CLK_BUF_EU3_HIBW_BYPM_LOBW# | 50OHM_Y12MIL | BUS | 6 | 6 | 5 | 10 | 5 | 14 | 6 | 15 | 12 | 12 | 12 | 12 |  | 50 Ohms-3 | TOP=L2:L3=L2/L4:L6=L5/L7:BOTTOM=L7 |
| CLK_BUF_EU3_HIBW_BYPM_LOBW# | 50OHM_Y12MIL | BUS | 7 | 6 | 5 | 10 | 5 | 14 | 6 | 15 | 12 | 12 | 12 | 12 |  | 50 Ohms-3 | TOP=L2:L3=L2/L4:L6=L5/L7:BOTTOM=L7 |
| CLK_BUF_EU3_HIBW_BYPM_LOBW# | 50OHM_Y12MIL | BUS | 8 | 6.75 | 5 | 10 | 5 | 14 | 6 | 15 | 12 | 12 | 12 | 12 |  | 50 Ohms-3 | TOP=L2:L3=L2/L4:L6=L5/L7:BOTTOM=L7 |
| CLK_BUF_EU3_SMB_A0_TRI | 50OHM_Y12MIL | BUS | 1 | 6.75 | 5 | 10 | 5 | 14 | 6 | 15 | 12 | 12 | 12 | 12 |  | 50 Ohms-3 | TOP=L2:L3=L2/L4:L6=L5/L7:BOTTOM=L7 |
| CLK_BUF_EU3_SMB_A0_TRI | 50OHM_Y12MIL | BUS | 2 | 6 | 5 | 10 | 5 | 14 | 6 | 15 | 12 | 12 | 12 | 12 |  | 50 Ohms-3 | TOP=L2:L3=L2/L4:L6=L5/L7:BOTTOM=L7 |
| CLK_BUF_EU3_SMB_A0_TRI | 50OHM_Y12MIL | BUS | 3 | 6 | 5 | 10 | 5 | 14 | 6 | 15 | 12 | 12 | 12 | 12 |  | 50 Ohms-3 | TOP=L2:L3=L2/L4:L6=L5/L7:BOTTOM=L7 |
| CLK_BUF_EU3_SMB_A0_TRI | 50OHM_Y12MIL | BUS | 4 | 6 | 5 | 10 | 5 | 14 | 6 | 15 | 12 | 12 | 12 | 12 |  | 50 Ohms-3 | TOP=L2:L3=L2/L4:L6=L5/L7:BOTTOM=L7 |
| CLK_BUF_EU3_SMB_A0_TRI | 50OHM_Y12MIL | BUS | 5 | 6 | 5 | 10 | 5 | 14 | 6 | 15 | 12 | 12 | 12 | 12 |  | 50 Ohms-3 | TOP=L2:L3=L2/L4:L6=L5/L7:BOTTOM=L7 |
| CLK_BUF_EU3_SMB_A0_TRI | 50OHM_Y12MIL | BUS | 6 | 6 | 5 | 10 | 5 | 14 | 6 | 15 | 12 | 12 | 12 | 12 |  | 50 Ohms-3 | TOP=L2:L3=L2/L4:L6=L5/L7:BOTTOM=L7 |
| CLK_BUF_EU3_SMB_A0_TRI | 50OHM_Y12MIL | BUS | 7 | 6 | 5 | 10 | 5 | 14 | 6 | 15 | 12 | 12 | 12 | 12 |  | 50 Ohms-3 | TOP=L2:L3=L2/L4:L6=L5/L7:BOTTOM=L7 |
| CLK_BUF_EU3_SMB_A0_TRI | 50OHM_Y12MIL | BUS | 8 | 6.75 | 5 | 10 | 5 | 14 | 6 | 15 | 12 | 12 | 12 | 12 |  | 50 Ohms-3 | TOP=L2:L3=L2/L4:L6=L5/L7:BOTTOM=L7 |
| CLK_BUF_EU3_SMB_A1_TRI | 50OHM_Y12MIL | BUS | 1 | 6.75 | 5 | 10 | 5 | 14 | 6 | 15 | 12 | 12 | 12 | 12 |  | 50 Ohms-3 | TOP=L2:L3=L2/L4:L6=L5/L7:BOTTOM=L7 |
| CLK_BUF_EU3_SMB_A1_TRI | 50OHM_Y12MIL | BUS | 2 | 6 | 5 | 10 | 5 | 14 | 6 | 15 | 12 | 12 | 12 | 12 |  | 50 Ohms-3 | TOP=L2:L3=L2/L4:L6=L5/L7:BOTTOM=L7 |
| CLK_BUF_EU3_SMB_A1_TRI | 50OHM_Y12MIL | BUS | 3 | 6 | 5 | 10 | 5 | 14 | 6 | 15 | 12 | 12 | 12 | 12 |  | 50 Ohms-3 | TOP=L2:L3=L2/L4:L6=L5/L7:BOTTOM=L7 |
| CLK_BUF_EU3_SMB_A1_TRI | 50OHM_Y12MIL | BUS | 4 | 6 | 5 | 10 | 5 | 14 | 6 | 15 | 12 | 12 | 12 | 12 |  | 50 Ohms-3 | TOP=L2:L3=L2/L4:L6=L5/L7:BOTTOM=L7 |
| CLK_BUF_EU3_SMB_A1_TRI | 50OHM_Y12MIL | BUS | 5 | 6 | 5 | 10 | 5 | 14 | 6 | 15 | 12 | 12 | 12 | 12 |  | 50 Ohms-3 | TOP=L2:L3=L2/L4:L6=L5/L7:BOTTOM=L7 |
| CLK_BUF_EU3_SMB_A1_TRI | 50OHM_Y12MIL | BUS | 6 | 6 | 5 | 10 | 5 | 14 | 6 | 15 | 12 | 12 | 12 | 12 |  | 50 Ohms-3 | TOP=L2:L3=L2/L4:L6=L5/L7:BOTTOM=L7 |
| CLK_BUF_EU3_SMB_A1_TRI | 50OHM_Y12MIL | BUS | 7 | 6 | 5 | 10 | 5 | 14 | 6 | 15 | 12 | 12 | 12 | 12 |  | 50 Ohms-3 | TOP=L2:L3=L2/L4:L6=L5/L7:BOTTOM=L7 |
| CLK_BUF_EU3_SMB_A1_TRI | 50OHM_Y12MIL | BUS | 8 | 6.75 | 5 | 10 | 5 | 14 | 6 | 15 | 12 | 12 | 12 | 12 |  | 50 Ohms-3 | TOP=L2:L3=L2/L4:L6=L5/L7:BOTTOM=L7 |
| CLK_BUF_EU4_100M_133M# | 50OHM_Y12MIL | BUS | 1 | 6.75 | 5 | 10 | 5 | 14 | 6 | 15 | 12 | 12 | 12 | 12 |  | 50 Ohms-3 | TOP=L2:L3=L2/L4:L6=L5/L7:BOTTOM=L7 |
| CLK_BUF_EU4_100M_133M# | 50OHM_Y12MIL | BUS | 2 | 6 | 5 | 10 | 5 | 14 | 6 | 15 | 12 | 12 | 12 | 12 |  | 50 Ohms-3 | TOP=L2:L3=L2/L4:L6=L5/L7:BOTTOM=L7 |
| CLK_BUF_EU4_100M_133M# | 50OHM_Y12MIL | BUS | 3 | 6 | 5 | 10 | 5 | 14 | 6 | 15 | 12 | 12 | 12 | 12 |  | 50 Ohms-3 | TOP=L2:L3=L2/L4:L6=L5/L7:BOTTOM=L7 |
| CLK_BUF_EU4_100M_133M# | 50OHM_Y12MIL | BUS | 4 | 6 | 5 | 10 | 5 | 14 | 6 | 15 | 12 | 12 | 12 | 12 |  | 50 Ohms-3 | TOP=L2:L3=L2/L4:L6=L5/L7:BOTTOM=L7 |
| CLK_BUF_EU4_100M_133M# | 50OHM_Y12MIL | BUS | 5 | 6 | 5 | 10 | 5 | 14 | 6 | 15 | 12 | 12 | 12 | 12 |  | 50 Ohms-3 | TOP=L2:L3=L2/L4:L6=L5/L7:BOTTOM=L7 |
| CLK_BUF_EU4_100M_133M# | 50OHM_Y12MIL | BUS | 6 | 6 | 5 | 10 | 5 | 14 | 6 | 15 | 12 | 12 | 12 | 12 |  | 50 Ohms-3 | TOP=L2:L3=L2/L4:L6=L5/L7:BOTTOM=L7 |
| CLK_BUF_EU4_100M_133M# | 50OHM_Y12MIL | BUS | 7 | 6 | 5 | 10 | 5 | 14 | 6 | 15 | 12 | 12 | 12 | 12 |  | 50 Ohms-3 | TOP=L2:L3=L2/L4:L6=L5/L7:BOTTOM=L7 |
| CLK_BUF_EU4_100M_133M# | 50OHM_Y12MIL | BUS | 8 | 6.75 | 5 | 10 | 5 | 14 | 6 | 15 | 12 | 12 | 12 | 12 |  | 50 Ohms-3 | TOP=L2:L3=L2/L4:L6=L5/L7:BOTTOM=L7 |
| CLK_BUF_EU4_HIBW_BYPM_LOBW# | 50OHM_Y12MIL | BUS | 1 | 6.75 | 5 | 10 | 5 | 14 | 6 | 15 | 12 | 12 | 12 | 12 |  | 50 Ohms-3 | TOP=L2:L3=L2/L4:L6=L5/L7:BOTTOM=L7 |
| CLK_BUF_EU4_HIBW_BYPM_LOBW# | 50OHM_Y12MIL | BUS | 2 | 6 | 5 | 10 | 5 | 14 | 6 | 15 | 12 | 12 | 12 | 12 |  | 50 Ohms-3 | TOP=L2:L3=L2/L4:L6=L5/L7:BOTTOM=L7 |
| CLK_BUF_EU4_HIBW_BYPM_LOBW# | 50OHM_Y12MIL | BUS | 3 | 6 | 5 | 10 | 5 | 14 | 6 | 15 | 12 | 12 | 12 | 12 |  | 50 Ohms-3 | TOP=L2:L3=L2/L4:L6=L5/L7:BOTTOM=L7 |
| CLK_BUF_EU4_HIBW_BYPM_LOBW# | 50OHM_Y12MIL | BUS | 4 | 6 | 5 | 10 | 5 | 14 | 6 | 15 | 12 | 12 | 12 | 12 |  | 50 Ohms-3 | TOP=L2:L3=L2/L4:L6=L5/L7:BOTTOM=L7 |
| CLK_BUF_EU4_HIBW_BYPM_LOBW# | 50OHM_Y12MIL | BUS | 5 | 6 | 5 | 10 | 5 | 14 | 6 | 15 | 12 | 12 | 12 | 12 |  | 50 Ohms-3 | TOP=L2:L3=L2/L4:L6=L5/L7:BOTTOM=L7 |
| CLK_BUF_EU4_HIBW_BYPM_LOBW# | 50OHM_Y12MIL | BUS | 6 | 6 | 5 | 10 | 5 | 14 | 6 | 15 | 12 | 12 | 12 | 12 |  | 50 Ohms-3 | TOP=L2:L3=L2/L4:L6=L5/L7:BOTTOM=L7 |
| CLK_BUF_EU4_HIBW_BYPM_LOBW# | 50OHM_Y12MIL | BUS | 7 | 6 | 5 | 10 | 5 | 14 | 6 | 15 | 12 | 12 | 12 | 12 |  | 50 Ohms-3 | TOP=L2:L3=L2/L4:L6=L5/L7:BOTTOM=L7 |
| CLK_BUF_EU4_HIBW_BYPM_LOBW# | 50OHM_Y12MIL | BUS | 8 | 6.75 | 5 | 10 | 5 | 14 | 6 | 15 | 12 | 12 | 12 | 12 |  | 50 Ohms-3 | TOP=L2:L3=L2/L4:L6=L5/L7:BOTTOM=L7 |
| CLK_BUF_EU4_SMB_A0_TRI | 50OHM_Y12MIL | BUS | 1 | 6.75 | 5 | 10 | 5 | 14 | 6 | 15 | 12 | 12 | 12 | 12 |  | 50 Ohms-3 | TOP=L2:L3=L2/L4:L6=L5/L7:BOTTOM=L7 |
| CLK_BUF_EU4_SMB_A0_TRI | 50OHM_Y12MIL | BUS | 2 | 6 | 5 | 10 | 5 | 14 | 6 | 15 | 12 | 12 | 12 | 12 |  | 50 Ohms-3 | TOP=L2:L3=L2/L4:L6=L5/L7:BOTTOM=L7 |
| CLK_BUF_EU4_SMB_A0_TRI | 50OHM_Y12MIL | BUS | 3 | 6 | 5 | 10 | 5 | 14 | 6 | 15 | 12 | 12 | 12 | 12 |  | 50 Ohms-3 | TOP=L2:L3=L2/L4:L6=L5/L7:BOTTOM=L7 |
| CLK_BUF_EU4_SMB_A0_TRI | 50OHM_Y12MIL | BUS | 4 | 6 | 5 | 10 | 5 | 14 | 6 | 15 | 12 | 12 | 12 | 12 |  | 50 Ohms-3 | TOP=L2:L3=L2/L4:L6=L5/L7:BOTTOM=L7 |
| CLK_BUF_EU4_SMB_A0_TRI | 50OHM_Y12MIL | BUS | 5 | 6 | 5 | 10 | 5 | 14 | 6 | 15 | 12 | 12 | 12 | 12 |  | 50 Ohms-3 | TOP=L2:L3=L2/L4:L6=L5/L7:BOTTOM=L7 |
| CLK_BUF_EU4_SMB_A0_TRI | 50OHM_Y12MIL | BUS | 6 | 6 | 5 | 10 | 5 | 14 | 6 | 15 | 12 | 12 | 12 | 12 |  | 50 Ohms-3 | TOP=L2:L3=L2/L4:L6=L5/L7:BOTTOM=L7 |
| CLK_BUF_EU4_SMB_A0_TRI | 50OHM_Y12MIL | BUS | 7 | 6 | 5 | 10 | 5 | 14 | 6 | 15 | 12 | 12 | 12 | 12 |  | 50 Ohms-3 | TOP=L2:L3=L2/L4:L6=L5/L7:BOTTOM=L7 |
| CLK_BUF_EU4_SMB_A0_TRI | 50OHM_Y12MIL | BUS | 8 | 6.75 | 5 | 10 | 5 | 14 | 6 | 15 | 12 | 12 | 12 | 12 |  | 50 Ohms-3 | TOP=L2:L3=L2/L4:L6=L5/L7:BOTTOM=L7 |
| CLK_BUF_EU4_SMB_A1_TRI | 50OHM_Y12MIL | BUS | 1 | 6.75 | 5 | 10 | 5 | 14 | 6 | 15 | 12 | 12 | 12 | 12 |  | 50 Ohms-3 | TOP=L2:L3=L2/L4:L6=L5/L7:BOTTOM=L7 |
| CLK_BUF_EU4_SMB_A1_TRI | 50OHM_Y12MIL | BUS | 2 | 6 | 5 | 10 | 5 | 14 | 6 | 15 | 12 | 12 | 12 | 12 |  | 50 Ohms-3 | TOP=L2:L3=L2/L4:L6=L5/L7:BOTTOM=L7 |
| CLK_BUF_EU4_SMB_A1_TRI | 50OHM_Y12MIL | BUS | 3 | 6 | 5 | 10 | 5 | 14 | 6 | 15 | 12 | 12 | 12 | 12 |  | 50 Ohms-3 | TOP=L2:L3=L2/L4:L6=L5/L7:BOTTOM=L7 |
| CLK_BUF_EU4_SMB_A1_TRI | 50OHM_Y12MIL | BUS | 4 | 6 | 5 | 10 | 5 | 14 | 6 | 15 | 12 | 12 | 12 | 12 |  | 50 Ohms-3 | TOP=L2:L3=L2/L4:L6=L5/L7:BOTTOM=L7 |
| CLK_BUF_EU4_SMB_A1_TRI | 50OHM_Y12MIL | BUS | 5 | 6 | 5 | 10 | 5 | 14 | 6 | 15 | 12 | 12 | 12 | 12 |  | 50 Ohms-3 | TOP=L2:L3=L2/L4:L6=L5/L7:BOTTOM=L7 |
| CLK_BUF_EU4_SMB_A1_TRI | 50OHM_Y12MIL | BUS | 6 | 6 | 5 | 10 | 5 | 14 | 6 | 15 | 12 | 12 | 12 | 12 |  | 50 Ohms-3 | TOP=L2:L3=L2/L4:L6=L5/L7:BOTTOM=L7 |
| CLK_BUF_EU4_SMB_A1_TRI | 50OHM_Y12MIL | BUS | 7 | 6 | 5 | 10 | 5 | 14 | 6 | 15 | 12 | 12 | 12 | 12 |  | 50 Ohms-3 | TOP=L2:L3=L2/L4:L6=L5/L7:BOTTOM=L7 |
| CLK_BUF_EU4_SMB_A1_TRI | 50OHM_Y12MIL | BUS | 8 | 6.75 | 5 | 10 | 5 | 14 | 6 | 15 | 12 | 12 | 12 | 12 |  | 50 Ohms-3 | TOP=L2:L3=L2/L4:L6=L5/L7:BOTTOM=L7 |
| CLK_BUFFER_EU1_VOE_N | 50OHM_Y12MIL | BUS | 1 | 6.75 | 5 | 10 | 5 | 14 | 6 | 15 | 12 | 12 | 12 | 12 |  | 50 Ohms-3 | TOP=L2:L3=L2/L4:L6=L5/L7:BOTTOM=L7 |
| CLK_BUFFER_EU1_VOE_N | 50OHM_Y12MIL | BUS | 2 | 6 | 5 | 10 | 5 | 14 | 6 | 15 | 12 | 12 | 12 | 12 |  | 50 Ohms-3 | TOP=L2:L3=L2/L4:L6=L5/L7:BOTTOM=L7 |
| CLK_BUFFER_EU1_VOE_N | 50OHM_Y12MIL | BUS | 3 | 6 | 5 | 10 | 5 | 14 | 6 | 15 | 12 | 12 | 12 | 12 |  | 50 Ohms-3 | TOP=L2:L3=L2/L4:L6=L5/L7:BOTTOM=L7 |
| CLK_BUFFER_EU1_VOE_N | 50OHM_Y12MIL | BUS | 4 | 6 | 5 | 10 | 5 | 14 | 6 | 15 | 12 | 12 | 12 | 12 |  | 50 Ohms-3 | TOP=L2:L3=L2/L4:L6=L5/L7:BOTTOM=L7 |
| CLK_BUFFER_EU1_VOE_N | 50OHM_Y12MIL | BUS | 5 | 6 | 5 | 10 | 5 | 14 | 6 | 15 | 12 | 12 | 12 | 12 |  | 50 Ohms-3 | TOP=L2:L3=L2/L4:L6=L5/L7:BOTTOM=L7 |
| CLK_BUFFER_EU1_VOE_N | 50OHM_Y12MIL | BUS | 6 | 6 | 5 | 10 | 5 | 14 | 6 | 15 | 12 | 12 | 12 | 12 |  | 50 Ohms-3 | TOP=L2:L3=L2/L4:L6=L5/L7:BOTTOM=L7 |
| CLK_BUFFER_EU1_VOE_N | 50OHM_Y12MIL | BUS | 7 | 6 | 5 | 10 | 5 | 14 | 6 | 15 | 12 | 12 | 12 | 12 |  | 50 Ohms-3 | TOP=L2:L3=L2/L4:L6=L5/L7:BOTTOM=L7 |
| CLK_BUFFER_EU1_VOE_N | 50OHM_Y12MIL | BUS | 8 | 6.75 | 5 | 10 | 5 | 14 | 6 | 15 | 12 | 12 | 12 | 12 |  | 50 Ohms-3 | TOP=L2:L3=L2/L4:L6=L5/L7:BOTTOM=L7 |
| CLK_BUFFER_EU2_VOE_N | 50OHM_Y12MIL | BUS | 1 | 6.75 | 5 | 10 | 5 | 14 | 6 | 15 | 12 | 12 | 12 | 12 |  | 50 Ohms-3 | TOP=L2:L3=L2/L4:L6=L5/L7:BOTTOM=L7 |
| CLK_BUFFER_EU2_VOE_N | 50OHM_Y12MIL | BUS | 2 | 6 | 5 | 10 | 5 | 14 | 6 | 15 | 12 | 12 | 12 | 12 |  | 50 Ohms-3 | TOP=L2:L3=L2/L4:L6=L5/L7:BOTTOM=L7 |
| CLK_BUFFER_EU2_VOE_N | 50OHM_Y12MIL | BUS | 3 | 6 | 5 | 10 | 5 | 14 | 6 | 15 | 12 | 12 | 12 | 12 |  | 50 Ohms-3 | TOP=L2:L3=L2/L4:L6=L5/L7:BOTTOM=L7 |
| CLK_BUFFER_EU2_VOE_N | 50OHM_Y12MIL | BUS | 4 | 6 | 5 | 10 | 5 | 14 | 6 | 15 | 12 | 12 | 12 | 12 |  | 50 Ohms-3 | TOP=L2:L3=L2/L4:L6=L5/L7:BOTTOM=L7 |
| CLK_BUFFER_EU2_VOE_N | 50OHM_Y12MIL | BUS | 5 | 6 | 5 | 10 | 5 | 14 | 6 | 15 | 12 | 12 | 12 | 12 |  | 50 Ohms-3 | TOP=L2:L3=L2/L4:L6=L5/L7:BOTTOM=L7 |
| CLK_BUFFER_EU2_VOE_N | 50OHM_Y12MIL | BUS | 6 | 6 | 5 | 10 | 5 | 14 | 6 | 15 | 12 | 12 | 12 | 12 |  | 50 Ohms-3 | TOP=L2:L3=L2/L4:L6=L5/L7:BOTTOM=L7 |
| CLK_BUFFER_EU2_VOE_N | 50OHM_Y12MIL | BUS | 7 | 6 | 5 | 10 | 5 | 14 | 6 | 15 | 12 | 12 | 12 | 12 |  | 50 Ohms-3 | TOP=L2:L3=L2/L4:L6=L5/L7:BOTTOM=L7 |
| CLK_BUFFER_EU2_VOE_N | 50OHM_Y12MIL | BUS | 8 | 6.75 | 5 | 10 | 5 | 14 | 6 | 15 | 12 | 12 | 12 | 12 |  | 50 Ohms-3 | TOP=L2:L3=L2/L4:L6=L5/L7:BOTTOM=L7 |
| CLK_BUFFER_EU3_VOE_N | 50OHM_Y12MIL | BUS | 1 | 6.75 | 5 | 10 | 5 | 14 | 6 | 15 | 12 | 12 | 12 | 12 |  | 50 Ohms-3 | TOP=L2:L3=L2/L4:L6=L5/L7:BOTTOM=L7 |
| CLK_BUFFER_EU3_VOE_N | 50OHM_Y12MIL | BUS | 2 | 6 | 5 | 10 | 5 | 14 | 6 | 15 | 12 | 12 | 12 | 12 |  | 50 Ohms-3 | TOP=L2:L3=L2/L4:L6=L5/L7:BOTTOM=L7 |
| CLK_BUFFER_EU3_VOE_N | 50OHM_Y12MIL | BUS | 3 | 6 | 5 | 10 | 5 | 14 | 6 | 15 | 12 | 12 | 12 | 12 |  | 50 Ohms-3 | TOP=L2:L3=L2/L4:L6=L5/L7:BOTTOM=L7 |
| CLK_BUFFER_EU3_VOE_N | 50OHM_Y12MIL | BUS | 4 | 6 | 5 | 10 | 5 | 14 | 6 | 15 | 12 | 12 | 12 | 12 |  | 50 Ohms-3 | TOP=L2:L3=L2/L4:L6=L5/L7:BOTTOM=L7 |
| CLK_BUFFER_EU3_VOE_N | 50OHM_Y12MIL | BUS | 5 | 6 | 5 | 10 | 5 | 14 | 6 | 15 | 12 | 12 | 12 | 12 |  | 50 Ohms-3 | TOP=L2:L3=L2/L4:L6=L5/L7:BOTTOM=L7 |
| CLK_BUFFER_EU3_VOE_N | 50OHM_Y12MIL | BUS | 6 | 6 | 5 | 10 | 5 | 14 | 6 | 15 | 12 | 12 | 12 | 12 |  | 50 Ohms-3 | TOP=L2:L3=L2/L4:L6=L5/L7:BOTTOM=L7 |
| CLK_BUFFER_EU3_VOE_N | 50OHM_Y12MIL | BUS | 7 | 6 | 5 | 10 | 5 | 14 | 6 | 15 | 12 | 12 | 12 | 12 |  | 50 Ohms-3 | TOP=L2:L3=L2/L4:L6=L5/L7:BOTTOM=L7 |
| CLK_BUFFER_EU3_VOE_N | 50OHM_Y12MIL | BUS | 8 | 6.75 | 5 | 10 | 5 | 14 | 6 | 15 | 12 | 12 | 12 | 12 |  | 50 Ohms-3 | TOP=L2:L3=L2/L4:L6=L5/L7:BOTTOM=L7 |
| CLK_BUFFER_EU4_VOE_N | 50OHM_Y12MIL | BUS | 1 | 6.75 | 5 | 10 | 5 | 14 | 6 | 15 | 12 | 12 | 12 | 12 |  | 50 Ohms-3 | TOP=L2:L3=L2/L4:L6=L5/L7:BOTTOM=L7 |
| CLK_BUFFER_EU4_VOE_N | 50OHM_Y12MIL | BUS | 2 | 6 | 5 | 10 | 5 | 14 | 6 | 15 | 12 | 12 | 12 | 12 |  | 50 Ohms-3 | TOP=L2:L3=L2/L4:L6=L5/L7:BOTTOM=L7 |
| CLK_BUFFER_EU4_VOE_N | 50OHM_Y12MIL | BUS | 3 | 6 | 5 | 10 | 5 | 14 | 6 | 15 | 12 | 12 | 12 | 12 |  | 50 Ohms-3 | TOP=L2:L3=L2/L4:L6=L5/L7:BOTTOM=L7 |
| CLK_BUFFER_EU4_VOE_N | 50OHM_Y12MIL | BUS | 4 | 6 | 5 | 10 | 5 | 14 | 6 | 15 | 12 | 12 | 12 | 12 |  | 50 Ohms-3 | TOP=L2:L3=L2/L4:L6=L5/L7:BOTTOM=L7 |
| CLK_BUFFER_EU4_VOE_N | 50OHM_Y12MIL | BUS | 5 | 6 | 5 | 10 | 5 | 14 | 6 | 15 | 12 | 12 | 12 | 12 |  | 50 Ohms-3 | TOP=L2:L3=L2/L4:L6=L5/L7:BOTTOM=L7 |
| CLK_BUFFER_EU4_VOE_N | 50OHM_Y12MIL | BUS | 6 | 6 | 5 | 10 | 5 | 14 | 6 | 15 | 12 | 12 | 12 | 12 |  | 50 Ohms-3 | TOP=L2:L3=L2/L4:L6=L5/L7:BOTTOM=L7 |
| CLK_BUFFER_EU4_VOE_N | 50OHM_Y12MIL | BUS | 7 | 6 | 5 | 10 | 5 | 14 | 6 | 15 | 12 | 12 | 12 | 12 |  | 50 Ohms-3 | TOP=L2:L3=L2/L4:L6=L5/L7:BOTTOM=L7 |
| CLK_BUFFER_EU4_VOE_N | 50OHM_Y12MIL | BUS | 8 | 6.75 | 5 | 10 | 5 | 14 | 6 | 15 | 12 | 12 | 12 | 12 |  | 50 Ohms-3 | TOP=L2:L3=L2/L4:L6=L5/L7:BOTTOM=L7 |
| DPB_HW_REVISION | 50OHM_Y12MIL | BUS | 1 | 6.75 | 5 | 10 | 5 | 14 | 6 | 15 | 12 | 12 | 12 | 12 |  | 50 Ohms-3 | TOP=L2:L3=L2/L4:L6=L5/L7:BOTTOM=L7 |
| DPB_HW_REVISION | 50OHM_Y12MIL | BUS | 2 | 6 | 5 | 10 | 5 | 14 | 6 | 15 | 12 | 12 | 12 | 12 |  | 50 Ohms-3 | TOP=L2:L3=L2/L4:L6=L5/L7:BOTTOM=L7 |
| DPB_HW_REVISION | 50OHM_Y12MIL | BUS | 3 | 6 | 5 | 10 | 5 | 14 | 6 | 15 | 12 | 12 | 12 | 12 |  | 50 Ohms-3 | TOP=L2:L3=L2/L4:L6=L5/L7:BOTTOM=L7 |
| DPB_HW_REVISION | 50OHM_Y12MIL | BUS | 4 | 6 | 5 | 10 | 5 | 14 | 6 | 15 | 12 | 12 | 12 | 12 |  | 50 Ohms-3 | TOP=L2:L3=L2/L4:L6=L5/L7:BOTTOM=L7 |
| DPB_HW_REVISION | 50OHM_Y12MIL | BUS | 5 | 6 | 5 | 10 | 5 | 14 | 6 | 15 | 12 | 12 | 12 | 12 |  | 50 Ohms-3 | TOP=L2:L3=L2/L4:L6=L5/L7:BOTTOM=L7 |
| DPB_HW_REVISION | 50OHM_Y12MIL | BUS | 6 | 6 | 5 | 10 | 5 | 14 | 6 | 15 | 12 | 12 | 12 | 12 |  | 50 Ohms-3 | TOP=L2:L3=L2/L4:L6=L5/L7:BOTTOM=L7 |
| DPB_HW_REVISION | 50OHM_Y12MIL | BUS | 7 | 6 | 5 | 10 | 5 | 14 | 6 | 15 | 12 | 12 | 12 | 12 |  | 50 Ohms-3 | TOP=L2:L3=L2/L4:L6=L5/L7:BOTTOM=L7 |
| DPB_HW_REVISION | 50OHM_Y12MIL | BUS | 8 | 6.75 | 5 | 10 | 5 | 14 | 6 | 15 | 12 | 12 | 12 | 12 |  | 50 Ohms-3 | TOP=L2:L3=L2/L4:L6=L5/L7:BOTTOM=L7 |
| DRV_ACT_0 | 50OHM_Y12MIL | BUS | 1 | 6.75 | 5 | 10 | 5 | 14 | 6 | 15 | 12 | 12 | 12 | 12 |  | 50 Ohms-3 | TOP=L2:L3=L2/L4:L6=L5/L7:BOTTOM=L7 |
| DRV_ACT_0 | 50OHM_Y12MIL | BUS | 2 | 6 | 5 | 10 | 5 | 14 | 6 | 15 | 12 | 12 | 12 | 12 |  | 50 Ohms-3 | TOP=L2:L3=L2/L4:L6=L5/L7:BOTTOM=L7 |
| DRV_ACT_0 | 50OHM_Y12MIL | BUS | 3 | 6 | 5 | 10 | 5 | 14 | 6 | 15 | 12 | 12 | 12 | 12 |  | 50 Ohms-3 | TOP=L2:L3=L2/L4:L6=L5/L7:BOTTOM=L7 |
| DRV_ACT_0 | 50OHM_Y12MIL | BUS | 4 | 6 | 5 | 10 | 5 | 14 | 6 | 15 | 12 | 12 | 12 | 12 |  | 50 Ohms-3 | TOP=L2:L3=L2/L4:L6=L5/L7:BOTTOM=L7 |
| DRV_ACT_0 | 50OHM_Y12MIL | BUS | 5 | 6 | 5 | 10 | 5 | 14 | 6 | 15 | 12 | 12 | 12 | 12 |  | 50 Ohms-3 | TOP=L2:L3=L2/L4:L6=L5/L7:BOTTOM=L7 |
| DRV_ACT_0 | 50OHM_Y12MIL | BUS | 6 | 6 | 5 | 10 | 5 | 14 | 6 | 15 | 12 | 12 | 12 | 12 |  | 50 Ohms-3 | TOP=L2:L3=L2/L4:L6=L5/L7:BOTTOM=L7 |
| DRV_ACT_0 | 50OHM_Y12MIL | BUS | 7 | 6 | 5 | 10 | 5 | 14 | 6 | 15 | 12 | 12 | 12 | 12 |  | 50 Ohms-3 | TOP=L2:L3=L2/L4:L6=L5/L7:BOTTOM=L7 |
| DRV_ACT_0 | 50OHM_Y12MIL | BUS | 8 | 6.75 | 5 | 10 | 5 | 14 | 6 | 15 | 12 | 12 | 12 | 12 |  | 50 Ohms-3 | TOP=L2:L3=L2/L4:L6=L5/L7:BOTTOM=L7 |
| DRV_ACT_1 | 50OHM_Y12MIL | BUS | 1 | 6.75 | 5 | 10 | 5 | 14 | 6 | 15 | 12 | 12 | 12 | 12 |  | 50 Ohms-3 | TOP=L2:L3=L2/L4:L6=L5/L7:BOTTOM=L7 |
| DRV_ACT_1 | 50OHM_Y12MIL | BUS | 2 | 6 | 5 | 10 | 5 | 14 | 6 | 15 | 12 | 12 | 12 | 12 |  | 50 Ohms-3 | TOP=L2:L3=L2/L4:L6=L5/L7:BOTTOM=L7 |
| DRV_ACT_1 | 50OHM_Y12MIL | BUS | 3 | 6 | 5 | 10 | 5 | 14 | 6 | 15 | 12 | 12 | 12 | 12 |  | 50 Ohms-3 | TOP=L2:L3=L2/L4:L6=L5/L7:BOTTOM=L7 |
| DRV_ACT_1 | 50OHM_Y12MIL | BUS | 4 | 6 | 5 | 10 | 5 | 14 | 6 | 15 | 12 | 12 | 12 | 12 |  | 50 Ohms-3 | TOP=L2:L3=L2/L4:L6=L5/L7:BOTTOM=L7 |
| DRV_ACT_1 | 50OHM_Y12MIL | BUS | 5 | 6 | 5 | 10 | 5 | 14 | 6 | 15 | 12 | 12 | 12 | 12 |  | 50 Ohms-3 | TOP=L2:L3=L2/L4:L6=L5/L7:BOTTOM=L7 |
| DRV_ACT_1 | 50OHM_Y12MIL | BUS | 6 | 6 | 5 | 10 | 5 | 14 | 6 | 15 | 12 | 12 | 12 | 12 |  | 50 Ohms-3 | TOP=L2:L3=L2/L4:L6=L5/L7:BOTTOM=L7 |
| DRV_ACT_1 | 50OHM_Y12MIL | BUS | 7 | 6 | 5 | 10 | 5 | 14 | 6 | 15 | 12 | 12 | 12 | 12 |  | 50 Ohms-3 | TOP=L2:L3=L2/L4:L6=L5/L7:BOTTOM=L7 |
| DRV_ACT_1 | 50OHM_Y12MIL | BUS | 8 | 6.75 | 5 | 10 | 5 | 14 | 6 | 15 | 12 | 12 | 12 | 12 |  | 50 Ohms-3 | TOP=L2:L3=L2/L4:L6=L5/L7:BOTTOM=L7 |
| DRV_ACT_10 | 50OHM_Y12MIL | BUS | 1 | 6.75 | 5 | 10 | 5 | 14 | 6 | 15 | 12 | 12 | 12 | 12 |  | 50 Ohms-3 | TOP=L2:L3=L2/L4:L6=L5/L7:BOTTOM=L7 |
| DRV_ACT_10 | 50OHM_Y12MIL | BUS | 2 | 6 | 5 | 10 | 5 | 14 | 6 | 15 | 12 | 12 | 12 | 12 |  | 50 Ohms-3 | TOP=L2:L3=L2/L4:L6=L5/L7:BOTTOM=L7 |
| DRV_ACT_10 | 50OHM_Y12MIL | BUS | 3 | 6 | 5 | 10 | 5 | 14 | 6 | 15 | 12 | 12 | 12 | 12 |  | 50 Ohms-3 | TOP=L2:L3=L2/L4:L6=L5/L7:BOTTOM=L7 |
| DRV_ACT_10 | 50OHM_Y12MIL | BUS | 4 | 6 | 5 | 10 | 5 | 14 | 6 | 15 | 12 | 12 | 12 | 12 |  | 50 Ohms-3 | TOP=L2:L3=L2/L4:L6=L5/L7:BOTTOM=L7 |
| DRV_ACT_10 | 50OHM_Y12MIL | BUS | 5 | 6 | 5 | 10 | 5 | 14 | 6 | 15 | 12 | 12 | 12 | 12 |  | 50 Ohms-3 | TOP=L2:L3=L2/L4:L6=L5/L7:BOTTOM=L7 |
| DRV_ACT_10 | 50OHM_Y12MIL | BUS | 6 | 6 | 5 | 10 | 5 | 14 | 6 | 15 | 12 | 12 | 12 | 12 |  | 50 Ohms-3 | TOP=L2:L3=L2/L4:L6=L5/L7:BOTTOM=L7 |
| DRV_ACT_10 | 50OHM_Y12MIL | BUS | 7 | 6 | 5 | 10 | 5 | 14 | 6 | 15 | 12 | 12 | 12 | 12 |  | 50 Ohms-3 | TOP=L2:L3=L2/L4:L6=L5/L7:BOTTOM=L7 |
| DRV_ACT_10 | 50OHM_Y12MIL | BUS | 8 | 6.75 | 5 | 10 | 5 | 14 | 6 | 15 | 12 | 12 | 12 | 12 |  | 50 Ohms-3 | TOP=L2:L3=L2/L4:L6=L5/L7:BOTTOM=L7 |
| DRV_ACT_11 | 50OHM_Y12MIL | BUS | 1 | 6.75 | 5 | 10 | 5 | 14 | 6 | 15 | 12 | 12 | 12 | 12 |  | 50 Ohms-3 | TOP=L2:L3=L2/L4:L6=L5/L7:BOTTOM=L7 |
| DRV_ACT_11 | 50OHM_Y12MIL | BUS | 2 | 6 | 5 | 10 | 5 | 14 | 6 | 15 | 12 | 12 | 12 | 12 |  | 50 Ohms-3 | TOP=L2:L3=L2/L4:L6=L5/L7:BOTTOM=L7 |
| DRV_ACT_11 | 50OHM_Y12MIL | BUS | 3 | 6 | 5 | 10 | 5 | 14 | 6 | 15 | 12 | 12 | 12 | 12 |  | 50 Ohms-3 | TOP=L2:L3=L2/L4:L6=L5/L7:BOTTOM=L7 |
| DRV_ACT_11 | 50OHM_Y12MIL | BUS | 4 | 6 | 5 | 10 | 5 | 14 | 6 | 15 | 12 | 12 | 12 | 12 |  | 50 Ohms-3 | TOP=L2:L3=L2/L4:L6=L5/L7:BOTTOM=L7 |
| DRV_ACT_11 | 50OHM_Y12MIL | BUS | 5 | 6 | 5 | 10 | 5 | 14 | 6 | 15 | 12 | 12 | 12 | 12 |  | 50 Ohms-3 | TOP=L2:L3=L2/L4:L6=L5/L7:BOTTOM=L7 |
| DRV_ACT_11 | 50OHM_Y12MIL | BUS | 6 | 6 | 5 | 10 | 5 | 14 | 6 | 15 | 12 | 12 | 12 | 12 |  | 50 Ohms-3 | TOP=L2:L3=L2/L4:L6=L5/L7:BOTTOM=L7 |
| DRV_ACT_11 | 50OHM_Y12MIL | BUS | 7 | 6 | 5 | 10 | 5 | 14 | 6 | 15 | 12 | 12 | 12 | 12 |  | 50 Ohms-3 | TOP=L2:L3=L2/L4:L6=L5/L7:BOTTOM=L7 |
| DRV_ACT_11 | 50OHM_Y12MIL | BUS | 8 | 6.75 | 5 | 10 | 5 | 14 | 6 | 15 | 12 | 12 | 12 | 12 |  | 50 Ohms-3 | TOP=L2:L3=L2/L4:L6=L5/L7:BOTTOM=L7 |
| DRV_ACT_12 | 50OHM_Y12MIL | BUS | 1 | 6.75 | 5 | 10 | 5 | 14 | 6 | 15 | 12 | 12 | 12 | 12 |  | 50 Ohms-3 | TOP=L2:L3=L2/L4:L6=L5/L7:BOTTOM=L7 |
| DRV_ACT_12 | 50OHM_Y12MIL | BUS | 2 | 6 | 5 | 10 | 5 | 14 | 6 | 15 | 12 | 12 | 12 | 12 |  | 50 Ohms-3 | TOP=L2:L3=L2/L4:L6=L5/L7:BOTTOM=L7 |
| DRV_ACT_12 | 50OHM_Y12MIL | BUS | 3 | 6 | 5 | 10 | 5 | 14 | 6 | 15 | 12 | 12 | 12 | 12 |  | 50 Ohms-3 | TOP=L2:L3=L2/L4:L6=L5/L7:BOTTOM=L7 |
| DRV_ACT_12 | 50OHM_Y12MIL | BUS | 4 | 6 | 5 | 10 | 5 | 14 | 6 | 15 | 12 | 12 | 12 | 12 |  | 50 Ohms-3 | TOP=L2:L3=L2/L4:L6=L5/L7:BOTTOM=L7 |
| DRV_ACT_12 | 50OHM_Y12MIL | BUS | 5 | 6 | 5 | 10 | 5 | 14 | 6 | 15 | 12 | 12 | 12 | 12 |  | 50 Ohms-3 | TOP=L2:L3=L2/L4:L6=L5/L7:BOTTOM=L7 |
| DRV_ACT_12 | 50OHM_Y12MIL | BUS | 6 | 6 | 5 | 10 | 5 | 14 | 6 | 15 | 12 | 12 | 12 | 12 |  | 50 Ohms-3 | TOP=L2:L3=L2/L4:L6=L5/L7:BOTTOM=L7 |
| DRV_ACT_12 | 50OHM_Y12MIL | BUS | 7 | 6 | 5 | 10 | 5 | 14 | 6 | 15 | 12 | 12 | 12 | 12 |  | 50 Ohms-3 | TOP=L2:L3=L2/L4:L6=L5/L7:BOTTOM=L7 |
| DRV_ACT_12 | 50OHM_Y12MIL | BUS | 8 | 6.75 | 5 | 10 | 5 | 14 | 6 | 15 | 12 | 12 | 12 | 12 |  | 50 Ohms-3 | TOP=L2:L3=L2/L4:L6=L5/L7:BOTTOM=L7 |
| DRV_ACT_13 | 50OHM_Y12MIL | BUS | 1 | 6.75 | 5 | 10 | 5 | 14 | 6 | 15 | 12 | 12 | 12 | 12 |  | 50 Ohms-3 | TOP=L2:L3=L2/L4:L6=L5/L7:BOTTOM=L7 |
| DRV_ACT_13 | 50OHM_Y12MIL | BUS | 2 | 6 | 5 | 10 | 5 | 14 | 6 | 15 | 12 | 12 | 12 | 12 |  | 50 Ohms-3 | TOP=L2:L3=L2/L4:L6=L5/L7:BOTTOM=L7 |
| DRV_ACT_13 | 50OHM_Y12MIL | BUS | 3 | 6 | 5 | 10 | 5 | 14 | 6 | 15 | 12 | 12 | 12 | 12 |  | 50 Ohms-3 | TOP=L2:L3=L2/L4:L6=L5/L7:BOTTOM=L7 |
| DRV_ACT_13 | 50OHM_Y12MIL | BUS | 4 | 6 | 5 | 10 | 5 | 14 | 6 | 15 | 12 | 12 | 12 | 12 |  | 50 Ohms-3 | TOP=L2:L3=L2/L4:L6=L5/L7:BOTTOM=L7 |
| DRV_ACT_13 | 50OHM_Y12MIL | BUS | 5 | 6 | 5 | 10 | 5 | 14 | 6 | 15 | 12 | 12 | 12 | 12 |  | 50 Ohms-3 | TOP=L2:L3=L2/L4:L6=L5/L7:BOTTOM=L7 |
| DRV_ACT_13 | 50OHM_Y12MIL | BUS | 6 | 6 | 5 | 10 | 5 | 14 | 6 | 15 | 12 | 12 | 12 | 12 |  | 50 Ohms-3 | TOP=L2:L3=L2/L4:L6=L5/L7:BOTTOM=L7 |
| DRV_ACT_13 | 50OHM_Y12MIL | BUS | 7 | 6 | 5 | 10 | 5 | 14 | 6 | 15 | 12 | 12 | 12 | 12 |  | 50 Ohms-3 | TOP=L2:L3=L2/L4:L6=L5/L7:BOTTOM=L7 |
| DRV_ACT_13 | 50OHM_Y12MIL | BUS | 8 | 6.75 | 5 | 10 | 5 | 14 | 6 | 15 | 12 | 12 | 12 | 12 |  | 50 Ohms-3 | TOP=L2:L3=L2/L4:L6=L5/L7:BOTTOM=L7 |
| DRV_ACT_14 | 50OHM_Y12MIL | BUS | 1 | 6.75 | 5 | 10 | 5 | 14 | 6 | 15 | 12 | 12 | 12 | 12 |  | 50 Ohms-3 | TOP=L2:L3=L2/L4:L6=L5/L7:BOTTOM=L7 |
| DRV_ACT_14 | 50OHM_Y12MIL | BUS | 2 | 6 | 5 | 10 | 5 | 14 | 6 | 15 | 12 | 12 | 12 | 12 |  | 50 Ohms-3 | TOP=L2:L3=L2/L4:L6=L5/L7:BOTTOM=L7 |
| DRV_ACT_14 | 50OHM_Y12MIL | BUS | 3 | 6 | 5 | 10 | 5 | 14 | 6 | 15 | 12 | 12 | 12 | 12 |  | 50 Ohms-3 | TOP=L2:L3=L2/L4:L6=L5/L7:BOTTOM=L7 |
| DRV_ACT_14 | 50OHM_Y12MIL | BUS | 4 | 6 | 5 | 10 | 5 | 14 | 6 | 15 | 12 | 12 | 12 | 12 |  | 50 Ohms-3 | TOP=L2:L3=L2/L4:L6=L5/L7:BOTTOM=L7 |
| DRV_ACT_14 | 50OHM_Y12MIL | BUS | 5 | 6 | 5 | 10 | 5 | 14 | 6 | 15 | 12 | 12 | 12 | 12 |  | 50 Ohms-3 | TOP=L2:L3=L2/L4:L6=L5/L7:BOTTOM=L7 |
| DRV_ACT_14 | 50OHM_Y12MIL | BUS | 6 | 6 | 5 | 10 | 5 | 14 | 6 | 15 | 12 | 12 | 12 | 12 |  | 50 Ohms-3 | TOP=L2:L3=L2/L4:L6=L5/L7:BOTTOM=L7 |
| DRV_ACT_14 | 50OHM_Y12MIL | BUS | 7 | 6 | 5 | 10 | 5 | 14 | 6 | 15 | 12 | 12 | 12 | 12 |  | 50 Ohms-3 | TOP=L2:L3=L2/L4:L6=L5/L7:BOTTOM=L7 |
| DRV_ACT_14 | 50OHM_Y12MIL | BUS | 8 | 6.75 | 5 | 10 | 5 | 14 | 6 | 15 | 12 | 12 | 12 | 12 |  | 50 Ohms-3 | TOP=L2:L3=L2/L4:L6=L5/L7:BOTTOM=L7 |
| DRV_ACT_2 | 50OHM_Y12MIL | BUS | 1 | 6.75 | 5 | 10 | 5 | 14 | 6 | 15 | 12 | 12 | 12 | 12 |  | 50 Ohms-3 | TOP=L2:L3=L2/L4:L6=L5/L7:BOTTOM=L7 |
| DRV_ACT_2 | 50OHM_Y12MIL | BUS | 2 | 6 | 5 | 10 | 5 | 14 | 6 | 15 | 12 | 12 | 12 | 12 |  | 50 Ohms-3 | TOP=L2:L3=L2/L4:L6=L5/L7:BOTTOM=L7 |
| DRV_ACT_2 | 50OHM_Y12MIL | BUS | 3 | 6 | 5 | 10 | 5 | 14 | 6 | 15 | 12 | 12 | 12 | 12 |  | 50 Ohms-3 | TOP=L2:L3=L2/L4:L6=L5/L7:BOTTOM=L7 |
| DRV_ACT_2 | 50OHM_Y12MIL | BUS | 4 | 6 | 5 | 10 | 5 | 14 | 6 | 15 | 12 | 12 | 12 | 12 |  | 50 Ohms-3 | TOP=L2:L3=L2/L4:L6=L5/L7:BOTTOM=L7 |
| DRV_ACT_2 | 50OHM_Y12MIL | BUS | 5 | 6 | 5 | 10 | 5 | 14 | 6 | 15 | 12 | 12 | 12 | 12 |  | 50 Ohms-3 | TOP=L2:L3=L2/L4:L6=L5/L7:BOTTOM=L7 |
| DRV_ACT_2 | 50OHM_Y12MIL | BUS | 6 | 6 | 5 | 10 | 5 | 14 | 6 | 15 | 12 | 12 | 12 | 12 |  | 50 Ohms-3 | TOP=L2:L3=L2/L4:L6=L5/L7:BOTTOM=L7 |
| DRV_ACT_2 | 50OHM_Y12MIL | BUS | 7 | 6 | 5 | 10 | 5 | 14 | 6 | 15 | 12 | 12 | 12 | 12 |  | 50 Ohms-3 | TOP=L2:L3=L2/L4:L6=L5/L7:BOTTOM=L7 |
| DRV_ACT_2 | 50OHM_Y12MIL | BUS | 8 | 6.75 | 5 | 10 | 5 | 14 | 6 | 15 | 12 | 12 | 12 | 12 |  | 50 Ohms-3 | TOP=L2:L3=L2/L4:L6=L5/L7:BOTTOM=L7 |
| DRV_ACT_3 | 50OHM_Y12MIL | BUS | 1 | 6.75 | 5 | 10 | 5 | 14 | 6 | 15 | 12 | 12 | 12 | 12 |  | 50 Ohms-3 | TOP=L2:L3=L2/L4:L6=L5/L7:BOTTOM=L7 |
| DRV_ACT_3 | 50OHM_Y12MIL | BUS | 2 | 6 | 5 | 10 | 5 | 14 | 6 | 15 | 12 | 12 | 12 | 12 |  | 50 Ohms-3 | TOP=L2:L3=L2/L4:L6=L5/L7:BOTTOM=L7 |
| DRV_ACT_3 | 50OHM_Y12MIL | BUS | 3 | 6 | 5 | 10 | 5 | 14 | 6 | 15 | 12 | 12 | 12 | 12 |  | 50 Ohms-3 | TOP=L2:L3=L2/L4:L6=L5/L7:BOTTOM=L7 |
| DRV_ACT_3 | 50OHM_Y12MIL | BUS | 4 | 6 | 5 | 10 | 5 | 14 | 6 | 15 | 12 | 12 | 12 | 12 |  | 50 Ohms-3 | TOP=L2:L3=L2/L4:L6=L5/L7:BOTTOM=L7 |
| DRV_ACT_3 | 50OHM_Y12MIL | BUS | 5 | 6 | 5 | 10 | 5 | 14 | 6 | 15 | 12 | 12 | 12 | 12 |  | 50 Ohms-3 | TOP=L2:L3=L2/L4:L6=L5/L7:BOTTOM=L7 |
| DRV_ACT_3 | 50OHM_Y12MIL | BUS | 6 | 6 | 5 | 10 | 5 | 14 | 6 | 15 | 12 | 12 | 12 | 12 |  | 50 Ohms-3 | TOP=L2:L3=L2/L4:L6=L5/L7:BOTTOM=L7 |
| DRV_ACT_3 | 50OHM_Y12MIL | BUS | 7 | 6 | 5 | 10 | 5 | 14 | 6 | 15 | 12 | 12 | 12 | 12 |  | 50 Ohms-3 | TOP=L2:L3=L2/L4:L6=L5/L7:BOTTOM=L7 |
| DRV_ACT_3 | 50OHM_Y12MIL | BUS | 8 | 6.75 | 5 | 10 | 5 | 14 | 6 | 15 | 12 | 12 | 12 | 12 |  | 50 Ohms-3 | TOP=L2:L3=L2/L4:L6=L5/L7:BOTTOM=L7 |
| DRV_ACT_4 | 50OHM_Y12MIL | BUS | 1 | 6.75 | 5 | 10 | 5 | 14 | 6 | 15 | 12 | 12 | 12 | 12 |  | 50 Ohms-3 | TOP=L2:L3=L2/L4:L6=L5/L7:BOTTOM=L7 |
| DRV_ACT_4 | 50OHM_Y12MIL | BUS | 2 | 6 | 5 | 10 | 5 | 14 | 6 | 15 | 12 | 12 | 12 | 12 |  | 50 Ohms-3 | TOP=L2:L3=L2/L4:L6=L5/L7:BOTTOM=L7 |
| DRV_ACT_4 | 50OHM_Y12MIL | BUS | 3 | 6 | 5 | 10 | 5 | 14 | 6 | 15 | 12 | 12 | 12 | 12 |  | 50 Ohms-3 | TOP=L2:L3=L2/L4:L6=L5/L7:BOTTOM=L7 |
| DRV_ACT_4 | 50OHM_Y12MIL | BUS | 4 | 6 | 5 | 10 | 5 | 14 | 6 | 15 | 12 | 12 | 12 | 12 |  | 50 Ohms-3 | TOP=L2:L3=L2/L4:L6=L5/L7:BOTTOM=L7 |
| DRV_ACT_4 | 50OHM_Y12MIL | BUS | 5 | 6 | 5 | 10 | 5 | 14 | 6 | 15 | 12 | 12 | 12 | 12 |  | 50 Ohms-3 | TOP=L2:L3=L2/L4:L6=L5/L7:BOTTOM=L7 |
| DRV_ACT_4 | 50OHM_Y12MIL | BUS | 6 | 6 | 5 | 10 | 5 | 14 | 6 | 15 | 12 | 12 | 12 | 12 |  | 50 Ohms-3 | TOP=L2:L3=L2/L4:L6=L5/L7:BOTTOM=L7 |
| DRV_ACT_4 | 50OHM_Y12MIL | BUS | 7 | 6 | 5 | 10 | 5 | 14 | 6 | 15 | 12 | 12 | 12 | 12 |  | 50 Ohms-3 | TOP=L2:L3=L2/L4:L6=L5/L7:BOTTOM=L7 |
| DRV_ACT_4 | 50OHM_Y12MIL | BUS | 8 | 6.75 | 5 | 10 | 5 | 14 | 6 | 15 | 12 | 12 | 12 | 12 |  | 50 Ohms-3 | TOP=L2:L3=L2/L4:L6=L5/L7:BOTTOM=L7 |
| DRV_ACT_5 | 50OHM_Y12MIL | BUS | 1 | 6.75 | 5 | 10 | 5 | 14 | 6 | 15 | 12 | 12 | 12 | 12 |  | 50 Ohms-3 | TOP=L2:L3=L2/L4:L6=L5/L7:BOTTOM=L7 |
| DRV_ACT_5 | 50OHM_Y12MIL | BUS | 2 | 6 | 5 | 10 | 5 | 14 | 6 | 15 | 12 | 12 | 12 | 12 |  | 50 Ohms-3 | TOP=L2:L3=L2/L4:L6=L5/L7:BOTTOM=L7 |
| DRV_ACT_5 | 50OHM_Y12MIL | BUS | 3 | 6 | 5 | 10 | 5 | 14 | 6 | 15 | 12 | 12 | 12 | 12 |  | 50 Ohms-3 | TOP=L2:L3=L2/L4:L6=L5/L7:BOTTOM=L7 |
| DRV_ACT_5 | 50OHM_Y12MIL | BUS | 4 | 6 | 5 | 10 | 5 | 14 | 6 | 15 | 12 | 12 | 12 | 12 |  | 50 Ohms-3 | TOP=L2:L3=L2/L4:L6=L5/L7:BOTTOM=L7 |
| DRV_ACT_5 | 50OHM_Y12MIL | BUS | 5 | 6 | 5 | 10 | 5 | 14 | 6 | 15 | 12 | 12 | 12 | 12 |  | 50 Ohms-3 | TOP=L2:L3=L2/L4:L6=L5/L7:BOTTOM=L7 |
| DRV_ACT_5 | 50OHM_Y12MIL | BUS | 6 | 6 | 5 | 10 | 5 | 14 | 6 | 15 | 12 | 12 | 12 | 12 |  | 50 Ohms-3 | TOP=L2:L3=L2/L4:L6=L5/L7:BOTTOM=L7 |
| DRV_ACT_5 | 50OHM_Y12MIL | BUS | 7 | 6 | 5 | 10 | 5 | 14 | 6 | 15 | 12 | 12 | 12 | 12 |  | 50 Ohms-3 | TOP=L2:L3=L2/L4:L6=L5/L7:BOTTOM=L7 |
| DRV_ACT_5 | 50OHM_Y12MIL | BUS | 8 | 6.75 | 5 | 10 | 5 | 14 | 6 | 15 | 12 | 12 | 12 | 12 |  | 50 Ohms-3 | TOP=L2:L3=L2/L4:L6=L5/L7:BOTTOM=L7 |
| DRV_ACT_6 | 50OHM_Y12MIL | BUS | 1 | 6.75 | 5 | 10 | 5 | 14 | 6 | 15 | 12 | 12 | 12 | 12 |  | 50 Ohms-3 | TOP=L2:L3=L2/L4:L6=L5/L7:BOTTOM=L7 |
| DRV_ACT_6 | 50OHM_Y12MIL | BUS | 2 | 6 | 5 | 10 | 5 | 14 | 6 | 15 | 12 | 12 | 12 | 12 |  | 50 Ohms-3 | TOP=L2:L3=L2/L4:L6=L5/L7:BOTTOM=L7 |
| DRV_ACT_6 | 50OHM_Y12MIL | BUS | 3 | 6 | 5 | 10 | 5 | 14 | 6 | 15 | 12 | 12 | 12 | 12 |  | 50 Ohms-3 | TOP=L2:L3=L2/L4:L6=L5/L7:BOTTOM=L7 |
| DRV_ACT_6 | 50OHM_Y12MIL | BUS | 4 | 6 | 5 | 10 | 5 | 14 | 6 | 15 | 12 | 12 | 12 | 12 |  | 50 Ohms-3 | TOP=L2:L3=L2/L4:L6=L5/L7:BOTTOM=L7 |
| DRV_ACT_6 | 50OHM_Y12MIL | BUS | 5 | 6 | 5 | 10 | 5 | 14 | 6 | 15 | 12 | 12 | 12 | 12 |  | 50 Ohms-3 | TOP=L2:L3=L2/L4:L6=L5/L7:BOTTOM=L7 |
| DRV_ACT_6 | 50OHM_Y12MIL | BUS | 6 | 6 | 5 | 10 | 5 | 14 | 6 | 15 | 12 | 12 | 12 | 12 |  | 50 Ohms-3 | TOP=L2:L3=L2/L4:L6=L5/L7:BOTTOM=L7 |
| DRV_ACT_6 | 50OHM_Y12MIL | BUS | 7 | 6 | 5 | 10 | 5 | 14 | 6 | 15 | 12 | 12 | 12 | 12 |  | 50 Ohms-3 | TOP=L2:L3=L2/L4:L6=L5/L7:BOTTOM=L7 |
| DRV_ACT_6 | 50OHM_Y12MIL | BUS | 8 | 6.75 | 5 | 10 | 5 | 14 | 6 | 15 | 12 | 12 | 12 | 12 |  | 50 Ohms-3 | TOP=L2:L3=L2/L4:L6=L5/L7:BOTTOM=L7 |
| DRV_ACT_7 | 50OHM_Y12MIL | BUS | 1 | 6.75 | 5 | 10 | 5 | 14 | 6 | 15 | 12 | 12 | 12 | 12 |  | 50 Ohms-3 | TOP=L2:L3=L2/L4:L6=L5/L7:BOTTOM=L7 |
| DRV_ACT_7 | 50OHM_Y12MIL | BUS | 2 | 6 | 5 | 10 | 5 | 14 | 6 | 15 | 12 | 12 | 12 | 12 |  | 50 Ohms-3 | TOP=L2:L3=L2/L4:L6=L5/L7:BOTTOM=L7 |
| DRV_ACT_7 | 50OHM_Y12MIL | BUS | 3 | 6 | 5 | 10 | 5 | 14 | 6 | 15 | 12 | 12 | 12 | 12 |  | 50 Ohms-3 | TOP=L2:L3=L2/L4:L6=L5/L7:BOTTOM=L7 |
| DRV_ACT_7 | 50OHM_Y12MIL | BUS | 4 | 6 | 5 | 10 | 5 | 14 | 6 | 15 | 12 | 12 | 12 | 12 |  | 50 Ohms-3 | TOP=L2:L3=L2/L4:L6=L5/L7:BOTTOM=L7 |
| DRV_ACT_7 | 50OHM_Y12MIL | BUS | 5 | 6 | 5 | 10 | 5 | 14 | 6 | 15 | 12 | 12 | 12 | 12 |  | 50 Ohms-3 | TOP=L2:L3=L2/L4:L6=L5/L7:BOTTOM=L7 |
| DRV_ACT_7 | 50OHM_Y12MIL | BUS | 6 | 6 | 5 | 10 | 5 | 14 | 6 | 15 | 12 | 12 | 12 | 12 |  | 50 Ohms-3 | TOP=L2:L3=L2/L4:L6=L5/L7:BOTTOM=L7 |
| DRV_ACT_7 | 50OHM_Y12MIL | BUS | 7 | 6 | 5 | 10 | 5 | 14 | 6 | 15 | 12 | 12 | 12 | 12 |  | 50 Ohms-3 | TOP=L2:L3=L2/L4:L6=L5/L7:BOTTOM=L7 |
| DRV_ACT_7 | 50OHM_Y12MIL | BUS | 8 | 6.75 | 5 | 10 | 5 | 14 | 6 | 15 | 12 | 12 | 12 | 12 |  | 50 Ohms-3 | TOP=L2:L3=L2/L4:L6=L5/L7:BOTTOM=L7 |
| DRV_ACT_8 | 50OHM_Y12MIL | BUS | 1 | 6.75 | 5 | 10 | 5 | 14 | 6 | 15 | 12 | 12 | 12 | 12 |  | 50 Ohms-3 | TOP=L2:L3=L2/L4:L6=L5/L7:BOTTOM=L7 |
| DRV_ACT_8 | 50OHM_Y12MIL | BUS | 2 | 6 | 5 | 10 | 5 | 14 | 6 | 15 | 12 | 12 | 12 | 12 |  | 50 Ohms-3 | TOP=L2:L3=L2/L4:L6=L5/L7:BOTTOM=L7 |
| DRV_ACT_8 | 50OHM_Y12MIL | BUS | 3 | 6 | 5 | 10 | 5 | 14 | 6 | 15 | 12 | 12 | 12 | 12 |  | 50 Ohms-3 | TOP=L2:L3=L2/L4:L6=L5/L7:BOTTOM=L7 |
| DRV_ACT_8 | 50OHM_Y12MIL | BUS | 4 | 6 | 5 | 10 | 5 | 14 | 6 | 15 | 12 | 12 | 12 | 12 |  | 50 Ohms-3 | TOP=L2:L3=L2/L4:L6=L5/L7:BOTTOM=L7 |
| DRV_ACT_8 | 50OHM_Y12MIL | BUS | 5 | 6 | 5 | 10 | 5 | 14 | 6 | 15 | 12 | 12 | 12 | 12 |  | 50 Ohms-3 | TOP=L2:L3=L2/L4:L6=L5/L7:BOTTOM=L7 |
| DRV_ACT_8 | 50OHM_Y12MIL | BUS | 6 | 6 | 5 | 10 | 5 | 14 | 6 | 15 | 12 | 12 | 12 | 12 |  | 50 Ohms-3 | TOP=L2:L3=L2/L4:L6=L5/L7:BOTTOM=L7 |
| DRV_ACT_8 | 50OHM_Y12MIL | BUS | 7 | 6 | 5 | 10 | 5 | 14 | 6 | 15 | 12 | 12 | 12 | 12 |  | 50 Ohms-3 | TOP=L2:L3=L2/L4:L6=L5/L7:BOTTOM=L7 |
| DRV_ACT_8 | 50OHM_Y12MIL | BUS | 8 | 6.75 | 5 | 10 | 5 | 14 | 6 | 15 | 12 | 12 | 12 | 12 |  | 50 Ohms-3 | TOP=L2:L3=L2/L4:L6=L5/L7:BOTTOM=L7 |
| DRV_ACT_9 | 50OHM_Y12MIL | BUS | 1 | 6.75 | 5 | 10 | 5 | 14 | 6 | 15 | 12 | 12 | 12 | 12 |  | 50 Ohms-3 | TOP=L2:L3=L2/L4:L6=L5/L7:BOTTOM=L7 |
| DRV_ACT_9 | 50OHM_Y12MIL | BUS | 2 | 6 | 5 | 10 | 5 | 14 | 6 | 15 | 12 | 12 | 12 | 12 |  | 50 Ohms-3 | TOP=L2:L3=L2/L4:L6=L5/L7:BOTTOM=L7 |
| DRV_ACT_9 | 50OHM_Y12MIL | BUS | 3 | 6 | 5 | 10 | 5 | 14 | 6 | 15 | 12 | 12 | 12 | 12 |  | 50 Ohms-3 | TOP=L2:L3=L2/L4:L6=L5/L7:BOTTOM=L7 |
| DRV_ACT_9 | 50OHM_Y12MIL | BUS | 4 | 6 | 5 | 10 | 5 | 14 | 6 | 15 | 12 | 12 | 12 | 12 |  | 50 Ohms-3 | TOP=L2:L3=L2/L4:L6=L5/L7:BOTTOM=L7 |
| DRV_ACT_9 | 50OHM_Y12MIL | BUS | 5 | 6 | 5 | 10 | 5 | 14 | 6 | 15 | 12 | 12 | 12 | 12 |  | 50 Ohms-3 | TOP=L2:L3=L2/L4:L6=L5/L7:BOTTOM=L7 |
| DRV_ACT_9 | 50OHM_Y12MIL | BUS | 6 | 6 | 5 | 10 | 5 | 14 | 6 | 15 | 12 | 12 | 12 | 12 |  | 50 Ohms-3 | TOP=L2:L3=L2/L4:L6=L5/L7:BOTTOM=L7 |
| DRV_ACT_9 | 50OHM_Y12MIL | BUS | 7 | 6 | 5 | 10 | 5 | 14 | 6 | 15 | 12 | 12 | 12 | 12 |  | 50 Ohms-3 | TOP=L2:L3=L2/L4:L6=L5/L7:BOTTOM=L7 |
| DRV_ACT_9 | 50OHM_Y12MIL | BUS | 8 | 6.75 | 5 | 10 | 5 | 14 | 6 | 15 | 12 | 12 | 12 | 12 |  | 50 Ohms-3 | TOP=L2:L3=L2/L4:L6=L5/L7:BOTTOM=L7 |
| DRV_ATTN_0 | 50OHM_Y12MIL | BUS | 1 | 6.75 | 5 | 10 | 5 | 14 | 6 | 15 | 12 | 12 | 12 | 12 |  | 50 Ohms-3 | TOP=L2:L3=L2/L4:L6=L5/L7:BOTTOM=L7 |
| DRV_ATTN_0 | 50OHM_Y12MIL | BUS | 2 | 6 | 5 | 10 | 5 | 14 | 6 | 15 | 12 | 12 | 12 | 12 |  | 50 Ohms-3 | TOP=L2:L3=L2/L4:L6=L5/L7:BOTTOM=L7 |
| DRV_ATTN_0 | 50OHM_Y12MIL | BUS | 3 | 6 | 5 | 10 | 5 | 14 | 6 | 15 | 12 | 12 | 12 | 12 |  | 50 Ohms-3 | TOP=L2:L3=L2/L4:L6=L5/L7:BOTTOM=L7 |
| DRV_ATTN_0 | 50OHM_Y12MIL | BUS | 4 | 6 | 5 | 10 | 5 | 14 | 6 | 15 | 12 | 12 | 12 | 12 |  | 50 Ohms-3 | TOP=L2:L3=L2/L4:L6=L5/L7:BOTTOM=L7 |
| DRV_ATTN_0 | 50OHM_Y12MIL | BUS | 5 | 6 | 5 | 10 | 5 | 14 | 6 | 15 | 12 | 12 | 12 | 12 |  | 50 Ohms-3 | TOP=L2:L3=L2/L4:L6=L5/L7:BOTTOM=L7 |
| DRV_ATTN_0 | 50OHM_Y12MIL | BUS | 6 | 6 | 5 | 10 | 5 | 14 | 6 | 15 | 12 | 12 | 12 | 12 |  | 50 Ohms-3 | TOP=L2:L3=L2/L4:L6=L5/L7:BOTTOM=L7 |
| DRV_ATTN_0 | 50OHM_Y12MIL | BUS | 7 | 6 | 5 | 10 | 5 | 14 | 6 | 15 | 12 | 12 | 12 | 12 |  | 50 Ohms-3 | TOP=L2:L3=L2/L4:L6=L5/L7:BOTTOM=L7 |
| DRV_ATTN_0 | 50OHM_Y12MIL | BUS | 8 | 6.75 | 5 | 10 | 5 | 14 | 6 | 15 | 12 | 12 | 12 | 12 |  | 50 Ohms-3 | TOP=L2:L3=L2/L4:L6=L5/L7:BOTTOM=L7 |
| DRV_ATTN_1 | 50OHM_Y12MIL | BUS | 1 | 6.75 | 5 | 10 | 5 | 14 | 6 | 15 | 12 | 12 | 12 | 12 |  | 50 Ohms-3 | TOP=L2:L3=L2/L4:L6=L5/L7:BOTTOM=L7 |
| DRV_ATTN_1 | 50OHM_Y12MIL | BUS | 2 | 6 | 5 | 10 | 5 | 14 | 6 | 15 | 12 | 12 | 12 | 12 |  | 50 Ohms-3 | TOP=L2:L3=L2/L4:L6=L5/L7:BOTTOM=L7 |
| DRV_ATTN_1 | 50OHM_Y12MIL | BUS | 3 | 6 | 5 | 10 | 5 | 14 | 6 | 15 | 12 | 12 | 12 | 12 |  | 50 Ohms-3 | TOP=L2:L3=L2/L4:L6=L5/L7:BOTTOM=L7 |
| DRV_ATTN_1 | 50OHM_Y12MIL | BUS | 4 | 6 | 5 | 10 | 5 | 14 | 6 | 15 | 12 | 12 | 12 | 12 |  | 50 Ohms-3 | TOP=L2:L3=L2/L4:L6=L5/L7:BOTTOM=L7 |
| DRV_ATTN_1 | 50OHM_Y12MIL | BUS | 5 | 6 | 5 | 10 | 5 | 14 | 6 | 15 | 12 | 12 | 12 | 12 |  | 50 Ohms-3 | TOP=L2:L3=L2/L4:L6=L5/L7:BOTTOM=L7 |
| DRV_ATTN_1 | 50OHM_Y12MIL | BUS | 6 | 6 | 5 | 10 | 5 | 14 | 6 | 15 | 12 | 12 | 12 | 12 |  | 50 Ohms-3 | TOP=L2:L3=L2/L4:L6=L5/L7:BOTTOM=L7 |
| DRV_ATTN_1 | 50OHM_Y12MIL | BUS | 7 | 6 | 5 | 10 | 5 | 14 | 6 | 15 | 12 | 12 | 12 | 12 |  | 50 Ohms-3 | TOP=L2:L3=L2/L4:L6=L5/L7:BOTTOM=L7 |
| DRV_ATTN_1 | 50OHM_Y12MIL | BUS | 8 | 6.75 | 5 | 10 | 5 | 14 | 6 | 15 | 12 | 12 | 12 | 12 |  | 50 Ohms-3 | TOP=L2:L3=L2/L4:L6=L5/L7:BOTTOM=L7 |
| DRV_ATTN_10 | 50OHM_Y12MIL | BUS | 1 | 6.75 | 5 | 10 | 5 | 14 | 6 | 15 | 12 | 12 | 12 | 12 |  | 50 Ohms-3 | TOP=L2:L3=L2/L4:L6=L5/L7:BOTTOM=L7 |
| DRV_ATTN_10 | 50OHM_Y12MIL | BUS | 2 | 6 | 5 | 10 | 5 | 14 | 6 | 15 | 12 | 12 | 12 | 12 |  | 50 Ohms-3 | TOP=L2:L3=L2/L4:L6=L5/L7:BOTTOM=L7 |
| DRV_ATTN_10 | 50OHM_Y12MIL | BUS | 3 | 6 | 5 | 10 | 5 | 14 | 6 | 15 | 12 | 12 | 12 | 12 |  | 50 Ohms-3 | TOP=L2:L3=L2/L4:L6=L5/L7:BOTTOM=L7 |
| DRV_ATTN_10 | 50OHM_Y12MIL | BUS | 4 | 6 | 5 | 10 | 5 | 14 | 6 | 15 | 12 | 12 | 12 | 12 |  | 50 Ohms-3 | TOP=L2:L3=L2/L4:L6=L5/L7:BOTTOM=L7 |
| DRV_ATTN_10 | 50OHM_Y12MIL | BUS | 5 | 6 | 5 | 10 | 5 | 14 | 6 | 15 | 12 | 12 | 12 | 12 |  | 50 Ohms-3 | TOP=L2:L3=L2/L4:L6=L5/L7:BOTTOM=L7 |
| DRV_ATTN_10 | 50OHM_Y12MIL | BUS | 6 | 6 | 5 | 10 | 5 | 14 | 6 | 15 | 12 | 12 | 12 | 12 |  | 50 Ohms-3 | TOP=L2:L3=L2/L4:L6=L5/L7:BOTTOM=L7 |
| DRV_ATTN_10 | 50OHM_Y12MIL | BUS | 7 | 6 | 5 | 10 | 5 | 14 | 6 | 15 | 12 | 12 | 12 | 12 |  | 50 Ohms-3 | TOP=L2:L3=L2/L4:L6=L5/L7:BOTTOM=L7 |
| DRV_ATTN_10 | 50OHM_Y12MIL | BUS | 8 | 6.75 | 5 | 10 | 5 | 14 | 6 | 15 | 12 | 12 | 12 | 12 |  | 50 Ohms-3 | TOP=L2:L3=L2/L4:L6=L5/L7:BOTTOM=L7 |
| DRV_ATTN_11 | 50OHM_Y12MIL | BUS | 1 | 6.75 | 5 | 10 | 5 | 14 | 6 | 15 | 12 | 12 | 12 | 12 |  | 50 Ohms-3 | TOP=L2:L3=L2/L4:L6=L5/L7:BOTTOM=L7 |
| DRV_ATTN_11 | 50OHM_Y12MIL | BUS | 2 | 6 | 5 | 10 | 5 | 14 | 6 | 15 | 12 | 12 | 12 | 12 |  | 50 Ohms-3 | TOP=L2:L3=L2/L4:L6=L5/L7:BOTTOM=L7 |
| DRV_ATTN_11 | 50OHM_Y12MIL | BUS | 3 | 6 | 5 | 10 | 5 | 14 | 6 | 15 | 12 | 12 | 12 | 12 |  | 50 Ohms-3 | TOP=L2:L3=L2/L4:L6=L5/L7:BOTTOM=L7 |
| DRV_ATTN_11 | 50OHM_Y12MIL | BUS | 4 | 6 | 5 | 10 | 5 | 14 | 6 | 15 | 12 | 12 | 12 | 12 |  | 50 Ohms-3 | TOP=L2:L3=L2/L4:L6=L5/L7:BOTTOM=L7 |
| DRV_ATTN_11 | 50OHM_Y12MIL | BUS | 5 | 6 | 5 | 10 | 5 | 14 | 6 | 15 | 12 | 12 | 12 | 12 |  | 50 Ohms-3 | TOP=L2:L3=L2/L4:L6=L5/L7:BOTTOM=L7 |
| DRV_ATTN_11 | 50OHM_Y12MIL | BUS | 6 | 6 | 5 | 10 | 5 | 14 | 6 | 15 | 12 | 12 | 12 | 12 |  | 50 Ohms-3 | TOP=L2:L3=L2/L4:L6=L5/L7:BOTTOM=L7 |
| DRV_ATTN_11 | 50OHM_Y12MIL | BUS | 7 | 6 | 5 | 10 | 5 | 14 | 6 | 15 | 12 | 12 | 12 | 12 |  | 50 Ohms-3 | TOP=L2:L3=L2/L4:L6=L5/L7:BOTTOM=L7 |
| DRV_ATTN_11 | 50OHM_Y12MIL | BUS | 8 | 6.75 | 5 | 10 | 5 | 14 | 6 | 15 | 12 | 12 | 12 | 12 |  | 50 Ohms-3 | TOP=L2:L3=L2/L4:L6=L5/L7:BOTTOM=L7 |
| DRV_ATTN_12 | 50OHM_Y12MIL | BUS | 1 | 6.75 | 5 | 10 | 5 | 14 | 6 | 15 | 12 | 12 | 12 | 12 |  | 50 Ohms-3 | TOP=L2:L3=L2/L4:L6=L5/L7:BOTTOM=L7 |
| DRV_ATTN_12 | 50OHM_Y12MIL | BUS | 2 | 6 | 5 | 10 | 5 | 14 | 6 | 15 | 12 | 12 | 12 | 12 |  | 50 Ohms-3 | TOP=L2:L3=L2/L4:L6=L5/L7:BOTTOM=L7 |
| DRV_ATTN_12 | 50OHM_Y12MIL | BUS | 3 | 6 | 5 | 10 | 5 | 14 | 6 | 15 | 12 | 12 | 12 | 12 |  | 50 Ohms-3 | TOP=L2:L3=L2/L4:L6=L5/L7:BOTTOM=L7 |
| DRV_ATTN_12 | 50OHM_Y12MIL | BUS | 4 | 6 | 5 | 10 | 5 | 14 | 6 | 15 | 12 | 12 | 12 | 12 |  | 50 Ohms-3 | TOP=L2:L3=L2/L4:L6=L5/L7:BOTTOM=L7 |
| DRV_ATTN_12 | 50OHM_Y12MIL | BUS | 5 | 6 | 5 | 10 | 5 | 14 | 6 | 15 | 12 | 12 | 12 | 12 |  | 50 Ohms-3 | TOP=L2:L3=L2/L4:L6=L5/L7:BOTTOM=L7 |
| DRV_ATTN_12 | 50OHM_Y12MIL | BUS | 6 | 6 | 5 | 10 | 5 | 14 | 6 | 15 | 12 | 12 | 12 | 12 |  | 50 Ohms-3 | TOP=L2:L3=L2/L4:L6=L5/L7:BOTTOM=L7 |
| DRV_ATTN_12 | 50OHM_Y12MIL | BUS | 7 | 6 | 5 | 10 | 5 | 14 | 6 | 15 | 12 | 12 | 12 | 12 |  | 50 Ohms-3 | TOP=L2:L3=L2/L4:L6=L5/L7:BOTTOM=L7 |
| DRV_ATTN_12 | 50OHM_Y12MIL | BUS | 8 | 6.75 | 5 | 10 | 5 | 14 | 6 | 15 | 12 | 12 | 12 | 12 |  | 50 Ohms-3 | TOP=L2:L3=L2/L4:L6=L5/L7:BOTTOM=L7 |
| DRV_ATTN_13 | 50OHM_Y12MIL | BUS | 1 | 6.75 | 5 | 10 | 5 | 14 | 6 | 15 | 12 | 12 | 12 | 12 |  | 50 Ohms-3 | TOP=L2:L3=L2/L4:L6=L5/L7:BOTTOM=L7 |
| DRV_ATTN_13 | 50OHM_Y12MIL | BUS | 2 | 6 | 5 | 10 | 5 | 14 | 6 | 15 | 12 | 12 | 12 | 12 |  | 50 Ohms-3 | TOP=L2:L3=L2/L4:L6=L5/L7:BOTTOM=L7 |
| DRV_ATTN_13 | 50OHM_Y12MIL | BUS | 3 | 6 | 5 | 10 | 5 | 14 | 6 | 15 | 12 | 12 | 12 | 12 |  | 50 Ohms-3 | TOP=L2:L3=L2/L4:L6=L5/L7:BOTTOM=L7 |
| DRV_ATTN_13 | 50OHM_Y12MIL | BUS | 4 | 6 | 5 | 10 | 5 | 14 | 6 | 15 | 12 | 12 | 12 | 12 |  | 50 Ohms-3 | TOP=L2:L3=L2/L4:L6=L5/L7:BOTTOM=L7 |
| DRV_ATTN_13 | 50OHM_Y12MIL | BUS | 5 | 6 | 5 | 10 | 5 | 14 | 6 | 15 | 12 | 12 | 12 | 12 |  | 50 Ohms-3 | TOP=L2:L3=L2/L4:L6=L5/L7:BOTTOM=L7 |
| DRV_ATTN_13 | 50OHM_Y12MIL | BUS | 6 | 6 | 5 | 10 | 5 | 14 | 6 | 15 | 12 | 12 | 12 | 12 |  | 50 Ohms-3 | TOP=L2:L3=L2/L4:L6=L5/L7:BOTTOM=L7 |
| DRV_ATTN_13 | 50OHM_Y12MIL | BUS | 7 | 6 | 5 | 10 | 5 | 14 | 6 | 15 | 12 | 12 | 12 | 12 |  | 50 Ohms-3 | TOP=L2:L3=L2/L4:L6=L5/L7:BOTTOM=L7 |
| DRV_ATTN_13 | 50OHM_Y12MIL | BUS | 8 | 6.75 | 5 | 10 | 5 | 14 | 6 | 15 | 12 | 12 | 12 | 12 |  | 50 Ohms-3 | TOP=L2:L3=L2/L4:L6=L5/L7:BOTTOM=L7 |
| DRV_ATTN_14 | 50OHM_Y12MIL | BUS | 1 | 6.75 | 5 | 10 | 5 | 14 | 6 | 15 | 12 | 12 | 12 | 12 |  | 50 Ohms-3 | TOP=L2:L3=L2/L4:L6=L5/L7:BOTTOM=L7 |
| DRV_ATTN_14 | 50OHM_Y12MIL | BUS | 2 | 6 | 5 | 10 | 5 | 14 | 6 | 15 | 12 | 12 | 12 | 12 |  | 50 Ohms-3 | TOP=L2:L3=L2/L4:L6=L5/L7:BOTTOM=L7 |
| DRV_ATTN_14 | 50OHM_Y12MIL | BUS | 3 | 6 | 5 | 10 | 5 | 14 | 6 | 15 | 12 | 12 | 12 | 12 |  | 50 Ohms-3 | TOP=L2:L3=L2/L4:L6=L5/L7:BOTTOM=L7 |
| DRV_ATTN_14 | 50OHM_Y12MIL | BUS | 4 | 6 | 5 | 10 | 5 | 14 | 6 | 15 | 12 | 12 | 12 | 12 |  | 50 Ohms-3 | TOP=L2:L3=L2/L4:L6=L5/L7:BOTTOM=L7 |
| DRV_ATTN_14 | 50OHM_Y12MIL | BUS | 5 | 6 | 5 | 10 | 5 | 14 | 6 | 15 | 12 | 12 | 12 | 12 |  | 50 Ohms-3 | TOP=L2:L3=L2/L4:L6=L5/L7:BOTTOM=L7 |
| DRV_ATTN_14 | 50OHM_Y12MIL | BUS | 6 | 6 | 5 | 10 | 5 | 14 | 6 | 15 | 12 | 12 | 12 | 12 |  | 50 Ohms-3 | TOP=L2:L3=L2/L4:L6=L5/L7:BOTTOM=L7 |
| DRV_ATTN_14 | 50OHM_Y12MIL | BUS | 7 | 6 | 5 | 10 | 5 | 14 | 6 | 15 | 12 | 12 | 12 | 12 |  | 50 Ohms-3 | TOP=L2:L3=L2/L4:L6=L5/L7:BOTTOM=L7 |
| DRV_ATTN_14 | 50OHM_Y12MIL | BUS | 8 | 6.75 | 5 | 10 | 5 | 14 | 6 | 15 | 12 | 12 | 12 | 12 |  | 50 Ohms-3 | TOP=L2:L3=L2/L4:L6=L5/L7:BOTTOM=L7 |
| DRV_ATTN_2 | 50OHM_Y12MIL | BUS | 1 | 6.75 | 5 | 10 | 5 | 14 | 6 | 15 | 12 | 12 | 12 | 12 |  | 50 Ohms-3 | TOP=L2:L3=L2/L4:L6=L5/L7:BOTTOM=L7 |
| DRV_ATTN_2 | 50OHM_Y12MIL | BUS | 2 | 6 | 5 | 10 | 5 | 14 | 6 | 15 | 12 | 12 | 12 | 12 |  | 50 Ohms-3 | TOP=L2:L3=L2/L4:L6=L5/L7:BOTTOM=L7 |
| DRV_ATTN_2 | 50OHM_Y12MIL | BUS | 3 | 6 | 5 | 10 | 5 | 14 | 6 | 15 | 12 | 12 | 12 | 12 |  | 50 Ohms-3 | TOP=L2:L3=L2/L4:L6=L5/L7:BOTTOM=L7 |
| DRV_ATTN_2 | 50OHM_Y12MIL | BUS | 4 | 6 | 5 | 10 | 5 | 14 | 6 | 15 | 12 | 12 | 12 | 12 |  | 50 Ohms-3 | TOP=L2:L3=L2/L4:L6=L5/L7:BOTTOM=L7 |
| DRV_ATTN_2 | 50OHM_Y12MIL | BUS | 5 | 6 | 5 | 10 | 5 | 14 | 6 | 15 | 12 | 12 | 12 | 12 |  | 50 Ohms-3 | TOP=L2:L3=L2/L4:L6=L5/L7:BOTTOM=L7 |
| DRV_ATTN_2 | 50OHM_Y12MIL | BUS | 6 | 6 | 5 | 10 | 5 | 14 | 6 | 15 | 12 | 12 | 12 | 12 |  | 50 Ohms-3 | TOP=L2:L3=L2/L4:L6=L5/L7:BOTTOM=L7 |
| DRV_ATTN_2 | 50OHM_Y12MIL | BUS | 7 | 6 | 5 | 10 | 5 | 14 | 6 | 15 | 12 | 12 | 12 | 12 |  | 50 Ohms-3 | TOP=L2:L3=L2/L4:L6=L5/L7:BOTTOM=L7 |
| DRV_ATTN_2 | 50OHM_Y12MIL | BUS | 8 | 6.75 | 5 | 10 | 5 | 14 | 6 | 15 | 12 | 12 | 12 | 12 |  | 50 Ohms-3 | TOP=L2:L3=L2/L4:L6=L5/L7:BOTTOM=L7 |
| DRV_ATTN_3 | 50OHM_Y12MIL | BUS | 1 | 6.75 | 5 | 10 | 5 | 14 | 6 | 15 | 12 | 12 | 12 | 12 |  | 50 Ohms-3 | TOP=L2:L3=L2/L4:L6=L5/L7:BOTTOM=L7 |
| DRV_ATTN_3 | 50OHM_Y12MIL | BUS | 2 | 6 | 5 | 10 | 5 | 14 | 6 | 15 | 12 | 12 | 12 | 12 |  | 50 Ohms-3 | TOP=L2:L3=L2/L4:L6=L5/L7:BOTTOM=L7 |
| DRV_ATTN_3 | 50OHM_Y12MIL | BUS | 3 | 6 | 5 | 10 | 5 | 14 | 6 | 15 | 12 | 12 | 12 | 12 |  | 50 Ohms-3 | TOP=L2:L3=L2/L4:L6=L5/L7:BOTTOM=L7 |
| DRV_ATTN_3 | 50OHM_Y12MIL | BUS | 4 | 6 | 5 | 10 | 5 | 14 | 6 | 15 | 12 | 12 | 12 | 12 |  | 50 Ohms-3 | TOP=L2:L3=L2/L4:L6=L5/L7:BOTTOM=L7 |
| DRV_ATTN_3 | 50OHM_Y12MIL | BUS | 5 | 6 | 5 | 10 | 5 | 14 | 6 | 15 | 12 | 12 | 12 | 12 |  | 50 Ohms-3 | TOP=L2:L3=L2/L4:L6=L5/L7:BOTTOM=L7 |
| DRV_ATTN_3 | 50OHM_Y12MIL | BUS | 6 | 6 | 5 | 10 | 5 | 14 | 6 | 15 | 12 | 12 | 12 | 12 |  | 50 Ohms-3 | TOP=L2:L3=L2/L4:L6=L5/L7:BOTTOM=L7 |
| DRV_ATTN_3 | 50OHM_Y12MIL | BUS | 7 | 6 | 5 | 10 | 5 | 14 | 6 | 15 | 12 | 12 | 12 | 12 |  | 50 Ohms-3 | TOP=L2:L3=L2/L4:L6=L5/L7:BOTTOM=L7 |
| DRV_ATTN_3 | 50OHM_Y12MIL | BUS | 8 | 6.75 | 5 | 10 | 5 | 14 | 6 | 15 | 12 | 12 | 12 | 12 |  | 50 Ohms-3 | TOP=L2:L3=L2/L4:L6=L5/L7:BOTTOM=L7 |
| DRV_ATTN_4 | 50OHM_Y12MIL | BUS | 1 | 6.75 | 5 | 10 | 5 | 14 | 6 | 15 | 12 | 12 | 12 | 12 |  | 50 Ohms-3 | TOP=L2:L3=L2/L4:L6=L5/L7:BOTTOM=L7 |
| DRV_ATTN_4 | 50OHM_Y12MIL | BUS | 2 | 6 | 5 | 10 | 5 | 14 | 6 | 15 | 12 | 12 | 12 | 12 |  | 50 Ohms-3 | TOP=L2:L3=L2/L4:L6=L5/L7:BOTTOM=L7 |
| DRV_ATTN_4 | 50OHM_Y12MIL | BUS | 3 | 6 | 5 | 10 | 5 | 14 | 6 | 15 | 12 | 12 | 12 | 12 |  | 50 Ohms-3 | TOP=L2:L3=L2/L4:L6=L5/L7:BOTTOM=L7 |
| DRV_ATTN_4 | 50OHM_Y12MIL | BUS | 4 | 6 | 5 | 10 | 5 | 14 | 6 | 15 | 12 | 12 | 12 | 12 |  | 50 Ohms-3 | TOP=L2:L3=L2/L4:L6=L5/L7:BOTTOM=L7 |
| DRV_ATTN_4 | 50OHM_Y12MIL | BUS | 5 | 6 | 5 | 10 | 5 | 14 | 6 | 15 | 12 | 12 | 12 | 12 |  | 50 Ohms-3 | TOP=L2:L3=L2/L4:L6=L5/L7:BOTTOM=L7 |
| DRV_ATTN_4 | 50OHM_Y12MIL | BUS | 6 | 6 | 5 | 10 | 5 | 14 | 6 | 15 | 12 | 12 | 12 | 12 |  | 50 Ohms-3 | TOP=L2:L3=L2/L4:L6=L5/L7:BOTTOM=L7 |
| DRV_ATTN_4 | 50OHM_Y12MIL | BUS | 7 | 6 | 5 | 10 | 5 | 14 | 6 | 15 | 12 | 12 | 12 | 12 |  | 50 Ohms-3 | TOP=L2:L3=L2/L4:L6=L5/L7:BOTTOM=L7 |
| DRV_ATTN_4 | 50OHM_Y12MIL | BUS | 8 | 6.75 | 5 | 10 | 5 | 14 | 6 | 15 | 12 | 12 | 12 | 12 |  | 50 Ohms-3 | TOP=L2:L3=L2/L4:L6=L5/L7:BOTTOM=L7 |
| DRV_ATTN_5 | 50OHM_Y12MIL | BUS | 1 | 6.75 | 5 | 10 | 5 | 14 | 6 | 15 | 12 | 12 | 12 | 12 |  | 50 Ohms-3 | TOP=L2:L3=L2/L4:L6=L5/L7:BOTTOM=L7 |
| DRV_ATTN_5 | 50OHM_Y12MIL | BUS | 2 | 6 | 5 | 10 | 5 | 14 | 6 | 15 | 12 | 12 | 12 | 12 |  | 50 Ohms-3 | TOP=L2:L3=L2/L4:L6=L5/L7:BOTTOM=L7 |
| DRV_ATTN_5 | 50OHM_Y12MIL | BUS | 3 | 6 | 5 | 10 | 5 | 14 | 6 | 15 | 12 | 12 | 12 | 12 |  | 50 Ohms-3 | TOP=L2:L3=L2/L4:L6=L5/L7:BOTTOM=L7 |
| DRV_ATTN_5 | 50OHM_Y12MIL | BUS | 4 | 6 | 5 | 10 | 5 | 14 | 6 | 15 | 12 | 12 | 12 | 12 |  | 50 Ohms-3 | TOP=L2:L3=L2/L4:L6=L5/L7:BOTTOM=L7 |
| DRV_ATTN_5 | 50OHM_Y12MIL | BUS | 5 | 6 | 5 | 10 | 5 | 14 | 6 | 15 | 12 | 12 | 12 | 12 |  | 50 Ohms-3 | TOP=L2:L3=L2/L4:L6=L5/L7:BOTTOM=L7 |
| DRV_ATTN_5 | 50OHM_Y12MIL | BUS | 6 | 6 | 5 | 10 | 5 | 14 | 6 | 15 | 12 | 12 | 12 | 12 |  | 50 Ohms-3 | TOP=L2:L3=L2/L4:L6=L5/L7:BOTTOM=L7 |
| DRV_ATTN_5 | 50OHM_Y12MIL | BUS | 7 | 6 | 5 | 10 | 5 | 14 | 6 | 15 | 12 | 12 | 12 | 12 |  | 50 Ohms-3 | TOP=L2:L3=L2/L4:L6=L5/L7:BOTTOM=L7 |
| DRV_ATTN_5 | 50OHM_Y12MIL | BUS | 8 | 6.75 | 5 | 10 | 5 | 14 | 6 | 15 | 12 | 12 | 12 | 12 |  | 50 Ohms-3 | TOP=L2:L3=L2/L4:L6=L5/L7:BOTTOM=L7 |
| DRV_ATTN_6 | 50OHM_Y12MIL | BUS | 1 | 6.75 | 5 | 10 | 5 | 14 | 6 | 15 | 12 | 12 | 12 | 12 |  | 50 Ohms-3 | TOP=L2:L3=L2/L4:L6=L5/L7:BOTTOM=L7 |
| DRV_ATTN_6 | 50OHM_Y12MIL | BUS | 2 | 6 | 5 | 10 | 5 | 14 | 6 | 15 | 12 | 12 | 12 | 12 |  | 50 Ohms-3 | TOP=L2:L3=L2/L4:L6=L5/L7:BOTTOM=L7 |
| DRV_ATTN_6 | 50OHM_Y12MIL | BUS | 3 | 6 | 5 | 10 | 5 | 14 | 6 | 15 | 12 | 12 | 12 | 12 |  | 50 Ohms-3 | TOP=L2:L3=L2/L4:L6=L5/L7:BOTTOM=L7 |
| DRV_ATTN_6 | 50OHM_Y12MIL | BUS | 4 | 6 | 5 | 10 | 5 | 14 | 6 | 15 | 12 | 12 | 12 | 12 |  | 50 Ohms-3 | TOP=L2:L3=L2/L4:L6=L5/L7:BOTTOM=L7 |
| DRV_ATTN_6 | 50OHM_Y12MIL | BUS | 5 | 6 | 5 | 10 | 5 | 14 | 6 | 15 | 12 | 12 | 12 | 12 |  | 50 Ohms-3 | TOP=L2:L3=L2/L4:L6=L5/L7:BOTTOM=L7 |
| DRV_ATTN_6 | 50OHM_Y12MIL | BUS | 6 | 6 | 5 | 10 | 5 | 14 | 6 | 15 | 12 | 12 | 12 | 12 |  | 50 Ohms-3 | TOP=L2:L3=L2/L4:L6=L5/L7:BOTTOM=L7 |
| DRV_ATTN_6 | 50OHM_Y12MIL | BUS | 7 | 6 | 5 | 10 | 5 | 14 | 6 | 15 | 12 | 12 | 12 | 12 |  | 50 Ohms-3 | TOP=L2:L3=L2/L4:L6=L5/L7:BOTTOM=L7 |
| DRV_ATTN_6 | 50OHM_Y12MIL | BUS | 8 | 6.75 | 5 | 10 | 5 | 14 | 6 | 15 | 12 | 12 | 12 | 12 |  | 50 Ohms-3 | TOP=L2:L3=L2/L4:L6=L5/L7:BOTTOM=L7 |
| DRV_ATTN_7 | 50OHM_Y12MIL | BUS | 1 | 6.75 | 5 | 10 | 5 | 14 | 6 | 15 | 12 | 12 | 12 | 12 |  | 50 Ohms-3 | TOP=L2:L3=L2/L4:L6=L5/L7:BOTTOM=L7 |
| DRV_ATTN_7 | 50OHM_Y12MIL | BUS | 2 | 6 | 5 | 10 | 5 | 14 | 6 | 15 | 12 | 12 | 12 | 12 |  | 50 Ohms-3 | TOP=L2:L3=L2/L4:L6=L5/L7:BOTTOM=L7 |
| DRV_ATTN_7 | 50OHM_Y12MIL | BUS | 3 | 6 | 5 | 10 | 5 | 14 | 6 | 15 | 12 | 12 | 12 | 12 |  | 50 Ohms-3 | TOP=L2:L3=L2/L4:L6=L5/L7:BOTTOM=L7 |
| DRV_ATTN_7 | 50OHM_Y12MIL | BUS | 4 | 6 | 5 | 10 | 5 | 14 | 6 | 15 | 12 | 12 | 12 | 12 |  | 50 Ohms-3 | TOP=L2:L3=L2/L4:L6=L5/L7:BOTTOM=L7 |
| DRV_ATTN_7 | 50OHM_Y12MIL | BUS | 5 | 6 | 5 | 10 | 5 | 14 | 6 | 15 | 12 | 12 | 12 | 12 |  | 50 Ohms-3 | TOP=L2:L3=L2/L4:L6=L5/L7:BOTTOM=L7 |
| DRV_ATTN_7 | 50OHM_Y12MIL | BUS | 6 | 6 | 5 | 10 | 5 | 14 | 6 | 15 | 12 | 12 | 12 | 12 |  | 50 Ohms-3 | TOP=L2:L3=L2/L4:L6=L5/L7:BOTTOM=L7 |
| DRV_ATTN_7 | 50OHM_Y12MIL | BUS | 7 | 6 | 5 | 10 | 5 | 14 | 6 | 15 | 12 | 12 | 12 | 12 |  | 50 Ohms-3 | TOP=L2:L3=L2/L4:L6=L5/L7:BOTTOM=L7 |
| DRV_ATTN_7 | 50OHM_Y12MIL | BUS | 8 | 6.75 | 5 | 10 | 5 | 14 | 6 | 15 | 12 | 12 | 12 | 12 |  | 50 Ohms-3 | TOP=L2:L3=L2/L4:L6=L5/L7:BOTTOM=L7 |
| DRV_ATTN_8 | 50OHM_Y12MIL | BUS | 1 | 6.75 | 5 | 10 | 5 | 14 | 6 | 15 | 12 | 12 | 12 | 12 |  | 50 Ohms-3 | TOP=L2:L3=L2/L4:L6=L5/L7:BOTTOM=L7 |
| DRV_ATTN_8 | 50OHM_Y12MIL | BUS | 2 | 6 | 5 | 10 | 5 | 14 | 6 | 15 | 12 | 12 | 12 | 12 |  | 50 Ohms-3 | TOP=L2:L3=L2/L4:L6=L5/L7:BOTTOM=L7 |
| DRV_ATTN_8 | 50OHM_Y12MIL | BUS | 3 | 6 | 5 | 10 | 5 | 14 | 6 | 15 | 12 | 12 | 12 | 12 |  | 50 Ohms-3 | TOP=L2:L3=L2/L4:L6=L5/L7:BOTTOM=L7 |
| DRV_ATTN_8 | 50OHM_Y12MIL | BUS | 4 | 6 | 5 | 10 | 5 | 14 | 6 | 15 | 12 | 12 | 12 | 12 |  | 50 Ohms-3 | TOP=L2:L3=L2/L4:L6=L5/L7:BOTTOM=L7 |
| DRV_ATTN_8 | 50OHM_Y12MIL | BUS | 5 | 6 | 5 | 10 | 5 | 14 | 6 | 15 | 12 | 12 | 12 | 12 |  | 50 Ohms-3 | TOP=L2:L3=L2/L4:L6=L5/L7:BOTTOM=L7 |
| DRV_ATTN_8 | 50OHM_Y12MIL | BUS | 6 | 6 | 5 | 10 | 5 | 14 | 6 | 15 | 12 | 12 | 12 | 12 |  | 50 Ohms-3 | TOP=L2:L3=L2/L4:L6=L5/L7:BOTTOM=L7 |
| DRV_ATTN_8 | 50OHM_Y12MIL | BUS | 7 | 6 | 5 | 10 | 5 | 14 | 6 | 15 | 12 | 12 | 12 | 12 |  | 50 Ohms-3 | TOP=L2:L3=L2/L4:L6=L5/L7:BOTTOM=L7 |
| DRV_ATTN_8 | 50OHM_Y12MIL | BUS | 8 | 6.75 | 5 | 10 | 5 | 14 | 6 | 15 | 12 | 12 | 12 | 12 |  | 50 Ohms-3 | TOP=L2:L3=L2/L4:L6=L5/L7:BOTTOM=L7 |
| DRV_ATTN_9 | 50OHM_Y12MIL | BUS | 1 | 6.75 | 5 | 10 | 5 | 14 | 6 | 15 | 12 | 12 | 12 | 12 |  | 50 Ohms-3 | TOP=L2:L3=L2/L4:L6=L5/L7:BOTTOM=L7 |
| DRV_ATTN_9 | 50OHM_Y12MIL | BUS | 2 | 6 | 5 | 10 | 5 | 14 | 6 | 15 | 12 | 12 | 12 | 12 |  | 50 Ohms-3 | TOP=L2:L3=L2/L4:L6=L5/L7:BOTTOM=L7 |
| DRV_ATTN_9 | 50OHM_Y12MIL | BUS | 3 | 6 | 5 | 10 | 5 | 14 | 6 | 15 | 12 | 12 | 12 | 12 |  | 50 Ohms-3 | TOP=L2:L3=L2/L4:L6=L5/L7:BOTTOM=L7 |
| DRV_ATTN_9 | 50OHM_Y12MIL | BUS | 4 | 6 | 5 | 10 | 5 | 14 | 6 | 15 | 12 | 12 | 12 | 12 |  | 50 Ohms-3 | TOP=L2:L3=L2/L4:L6=L5/L7:BOTTOM=L7 |
| DRV_ATTN_9 | 50OHM_Y12MIL | BUS | 5 | 6 | 5 | 10 | 5 | 14 | 6 | 15 | 12 | 12 | 12 | 12 |  | 50 Ohms-3 | TOP=L2:L3=L2/L4:L6=L5/L7:BOTTOM=L7 |
| DRV_ATTN_9 | 50OHM_Y12MIL | BUS | 6 | 6 | 5 | 10 | 5 | 14 | 6 | 15 | 12 | 12 | 12 | 12 |  | 50 Ohms-3 | TOP=L2:L3=L2/L4:L6=L5/L7:BOTTOM=L7 |
| DRV_ATTN_9 | 50OHM_Y12MIL | BUS | 7 | 6 | 5 | 10 | 5 | 14 | 6 | 15 | 12 | 12 | 12 | 12 |  | 50 Ohms-3 | TOP=L2:L3=L2/L4:L6=L5/L7:BOTTOM=L7 |
| DRV_ATTN_9 | 50OHM_Y12MIL | BUS | 8 | 6.75 | 5 | 10 | 5 | 14 | 6 | 15 | 12 | 12 | 12 | 12 |  | 50 Ohms-3 | TOP=L2:L3=L2/L4:L6=L5/L7:BOTTOM=L7 |
| DUALPORTEN#0 | 50OHM_Y12MIL | BUS | 1 | 6.75 | 5 | 10 | 5 | 14 | 6 | 15 | 12 | 12 | 12 | 12 |  | 50 Ohms-3 | TOP=L2:L3=L2/L4:L6=L5/L7:BOTTOM=L7 |
| DUALPORTEN#0 | 50OHM_Y12MIL | BUS | 2 | 6 | 5 | 10 | 5 | 14 | 6 | 15 | 12 | 12 | 12 | 12 |  | 50 Ohms-3 | TOP=L2:L3=L2/L4:L6=L5/L7:BOTTOM=L7 |
| DUALPORTEN#0 | 50OHM_Y12MIL | BUS | 3 | 6 | 5 | 10 | 5 | 14 | 6 | 15 | 12 | 12 | 12 | 12 |  | 50 Ohms-3 | TOP=L2:L3=L2/L4:L6=L5/L7:BOTTOM=L7 |
| DUALPORTEN#0 | 50OHM_Y12MIL | BUS | 4 | 6 | 5 | 10 | 5 | 14 | 6 | 15 | 12 | 12 | 12 | 12 |  | 50 Ohms-3 | TOP=L2:L3=L2/L4:L6=L5/L7:BOTTOM=L7 |
| DUALPORTEN#0 | 50OHM_Y12MIL | BUS | 5 | 6 | 5 | 10 | 5 | 14 | 6 | 15 | 12 | 12 | 12 | 12 |  | 50 Ohms-3 | TOP=L2:L3=L2/L4:L6=L5/L7:BOTTOM=L7 |
| DUALPORTEN#0 | 50OHM_Y12MIL | BUS | 6 | 6 | 5 | 10 | 5 | 14 | 6 | 15 | 12 | 12 | 12 | 12 |  | 50 Ohms-3 | TOP=L2:L3=L2/L4:L6=L5/L7:BOTTOM=L7 |
| DUALPORTEN#0 | 50OHM_Y12MIL | BUS | 7 | 6 | 5 | 10 | 5 | 14 | 6 | 15 | 12 | 12 | 12 | 12 |  | 50 Ohms-3 | TOP=L2:L3=L2/L4:L6=L5/L7:BOTTOM=L7 |
| DUALPORTEN#0 | 50OHM_Y12MIL | BUS | 8 | 6.75 | 5 | 10 | 5 | 14 | 6 | 15 | 12 | 12 | 12 | 12 |  | 50 Ohms-3 | TOP=L2:L3=L2/L4:L6=L5/L7:BOTTOM=L7 |
| DUALPORTEN#1 | 50OHM_Y12MIL | BUS | 1 | 6.75 | 5 | 10 | 5 | 14 | 6 | 15 | 12 | 12 | 12 | 12 |  | 50 Ohms-3 | TOP=L2:L3=L2/L4:L6=L5/L7:BOTTOM=L7 |
| DUALPORTEN#1 | 50OHM_Y12MIL | BUS | 2 | 6 | 5 | 10 | 5 | 14 | 6 | 15 | 12 | 12 | 12 | 12 |  | 50 Ohms-3 | TOP=L2:L3=L2/L4:L6=L5/L7:BOTTOM=L7 |
| DUALPORTEN#1 | 50OHM_Y12MIL | BUS | 3 | 6 | 5 | 10 | 5 | 14 | 6 | 15 | 12 | 12 | 12 | 12 |  | 50 Ohms-3 | TOP=L2:L3=L2/L4:L6=L5/L7:BOTTOM=L7 |
| DUALPORTEN#1 | 50OHM_Y12MIL | BUS | 4 | 6 | 5 | 10 | 5 | 14 | 6 | 15 | 12 | 12 | 12 | 12 |  | 50 Ohms-3 | TOP=L2:L3=L2/L4:L6=L5/L7:BOTTOM=L7 |
| DUALPORTEN#1 | 50OHM_Y12MIL | BUS | 5 | 6 | 5 | 10 | 5 | 14 | 6 | 15 | 12 | 12 | 12 | 12 |  | 50 Ohms-3 | TOP=L2:L3=L2/L4:L6=L5/L7:BOTTOM=L7 |
| DUALPORTEN#1 | 50OHM_Y12MIL | BUS | 6 | 6 | 5 | 10 | 5 | 14 | 6 | 15 | 12 | 12 | 12 | 12 |  | 50 Ohms-3 | TOP=L2:L3=L2/L4:L6=L5/L7:BOTTOM=L7 |
| DUALPORTEN#1 | 50OHM_Y12MIL | BUS | 7 | 6 | 5 | 10 | 5 | 14 | 6 | 15 | 12 | 12 | 12 | 12 |  | 50 Ohms-3 | TOP=L2:L3=L2/L4:L6=L5/L7:BOTTOM=L7 |
| DUALPORTEN#1 | 50OHM_Y12MIL | BUS | 8 | 6.75 | 5 | 10 | 5 | 14 | 6 | 15 | 12 | 12 | 12 | 12 |  | 50 Ohms-3 | TOP=L2:L3=L2/L4:L6=L5/L7:BOTTOM=L7 |
| DUALPORTEN#10 | 50OHM_Y12MIL | BUS | 1 | 6.75 | 5 | 10 | 5 | 14 | 6 | 15 | 12 | 12 | 12 | 12 |  | 50 Ohms-3 | TOP=L2:L3=L2/L4:L6=L5/L7:BOTTOM=L7 |
| DUALPORTEN#10 | 50OHM_Y12MIL | BUS | 2 | 6 | 5 | 10 | 5 | 14 | 6 | 15 | 12 | 12 | 12 | 12 |  | 50 Ohms-3 | TOP=L2:L3=L2/L4:L6=L5/L7:BOTTOM=L7 |
| DUALPORTEN#10 | 50OHM_Y12MIL | BUS | 3 | 6 | 5 | 10 | 5 | 14 | 6 | 15 | 12 | 12 | 12 | 12 |  | 50 Ohms-3 | TOP=L2:L3=L2/L4:L6=L5/L7:BOTTOM=L7 |
| DUALPORTEN#10 | 50OHM_Y12MIL | BUS | 4 | 6 | 5 | 10 | 5 | 14 | 6 | 15 | 12 | 12 | 12 | 12 |  | 50 Ohms-3 | TOP=L2:L3=L2/L4:L6=L5/L7:BOTTOM=L7 |
| DUALPORTEN#10 | 50OHM_Y12MIL | BUS | 5 | 6 | 5 | 10 | 5 | 14 | 6 | 15 | 12 | 12 | 12 | 12 |  | 50 Ohms-3 | TOP=L2:L3=L2/L4:L6=L5/L7:BOTTOM=L7 |
| DUALPORTEN#10 | 50OHM_Y12MIL | BUS | 6 | 6 | 5 | 10 | 5 | 14 | 6 | 15 | 12 | 12 | 12 | 12 |  | 50 Ohms-3 | TOP=L2:L3=L2/L4:L6=L5/L7:BOTTOM=L7 |
| DUALPORTEN#10 | 50OHM_Y12MIL | BUS | 7 | 6 | 5 | 10 | 5 | 14 | 6 | 15 | 12 | 12 | 12 | 12 |  | 50 Ohms-3 | TOP=L2:L3=L2/L4:L6=L5/L7:BOTTOM=L7 |
| DUALPORTEN#10 | 50OHM_Y12MIL | BUS | 8 | 6.75 | 5 | 10 | 5 | 14 | 6 | 15 | 12 | 12 | 12 | 12 |  | 50 Ohms-3 | TOP=L2:L3=L2/L4:L6=L5/L7:BOTTOM=L7 |
| DUALPORTEN#11 | 50OHM_Y12MIL | BUS | 1 | 6.75 | 5 | 10 | 5 | 14 | 6 | 15 | 12 | 12 | 12 | 12 |  | 50 Ohms-3 | TOP=L2:L3=L2/L4:L6=L5/L7:BOTTOM=L7 |
| DUALPORTEN#11 | 50OHM_Y12MIL | BUS | 2 | 6 | 5 | 10 | 5 | 14 | 6 | 15 | 12 | 12 | 12 | 12 |  | 50 Ohms-3 | TOP=L2:L3=L2/L4:L6=L5/L7:BOTTOM=L7 |
| DUALPORTEN#11 | 50OHM_Y12MIL | BUS | 3 | 6 | 5 | 10 | 5 | 14 | 6 | 15 | 12 | 12 | 12 | 12 |  | 50 Ohms-3 | TOP=L2:L3=L2/L4:L6=L5/L7:BOTTOM=L7 |
| DUALPORTEN#11 | 50OHM_Y12MIL | BUS | 4 | 6 | 5 | 10 | 5 | 14 | 6 | 15 | 12 | 12 | 12 | 12 |  | 50 Ohms-3 | TOP=L2:L3=L2/L4:L6=L5/L7:BOTTOM=L7 |
| DUALPORTEN#11 | 50OHM_Y12MIL | BUS | 5 | 6 | 5 | 10 | 5 | 14 | 6 | 15 | 12 | 12 | 12 | 12 |  | 50 Ohms-3 | TOP=L2:L3=L2/L4:L6=L5/L7:BOTTOM=L7 |
| DUALPORTEN#11 | 50OHM_Y12MIL | BUS | 6 | 6 | 5 | 10 | 5 | 14 | 6 | 15 | 12 | 12 | 12 | 12 |  | 50 Ohms-3 | TOP=L2:L3=L2/L4:L6=L5/L7:BOTTOM=L7 |
| DUALPORTEN#11 | 50OHM_Y12MIL | BUS | 7 | 6 | 5 | 10 | 5 | 14 | 6 | 15 | 12 | 12 | 12 | 12 |  | 50 Ohms-3 | TOP=L2:L3=L2/L4:L6=L5/L7:BOTTOM=L7 |
| DUALPORTEN#11 | 50OHM_Y12MIL | BUS | 8 | 6.75 | 5 | 10 | 5 | 14 | 6 | 15 | 12 | 12 | 12 | 12 |  | 50 Ohms-3 | TOP=L2:L3=L2/L4:L6=L5/L7:BOTTOM=L7 |
| DUALPORTEN#12 | 50OHM_Y12MIL | BUS | 1 | 6.75 | 5 | 10 | 5 | 14 | 6 | 15 | 12 | 12 | 12 | 12 |  | 50 Ohms-3 | TOP=L2:L3=L2/L4:L6=L5/L7:BOTTOM=L7 |
| DUALPORTEN#12 | 50OHM_Y12MIL | BUS | 2 | 6 | 5 | 10 | 5 | 14 | 6 | 15 | 12 | 12 | 12 | 12 |  | 50 Ohms-3 | TOP=L2:L3=L2/L4:L6=L5/L7:BOTTOM=L7 |
| DUALPORTEN#12 | 50OHM_Y12MIL | BUS | 3 | 6 | 5 | 10 | 5 | 14 | 6 | 15 | 12 | 12 | 12 | 12 |  | 50 Ohms-3 | TOP=L2:L3=L2/L4:L6=L5/L7:BOTTOM=L7 |
| DUALPORTEN#12 | 50OHM_Y12MIL | BUS | 4 | 6 | 5 | 10 | 5 | 14 | 6 | 15 | 12 | 12 | 12 | 12 |  | 50 Ohms-3 | TOP=L2:L3=L2/L4:L6=L5/L7:BOTTOM=L7 |
| DUALPORTEN#12 | 50OHM_Y12MIL | BUS | 5 | 6 | 5 | 10 | 5 | 14 | 6 | 15 | 12 | 12 | 12 | 12 |  | 50 Ohms-3 | TOP=L2:L3=L2/L4:L6=L5/L7:BOTTOM=L7 |
| DUALPORTEN#12 | 50OHM_Y12MIL | BUS | 6 | 6 | 5 | 10 | 5 | 14 | 6 | 15 | 12 | 12 | 12 | 12 |  | 50 Ohms-3 | TOP=L2:L3=L2/L4:L6=L5/L7:BOTTOM=L7 |
| DUALPORTEN#12 | 50OHM_Y12MIL | BUS | 7 | 6 | 5 | 10 | 5 | 14 | 6 | 15 | 12 | 12 | 12 | 12 |  | 50 Ohms-3 | TOP=L2:L3=L2/L4:L6=L5/L7:BOTTOM=L7 |
| DUALPORTEN#12 | 50OHM_Y12MIL | BUS | 8 | 6.75 | 5 | 10 | 5 | 14 | 6 | 15 | 12 | 12 | 12 | 12 |  | 50 Ohms-3 | TOP=L2:L3=L2/L4:L6=L5/L7:BOTTOM=L7 |
| DUALPORTEN#13 | 50OHM_Y12MIL | BUS | 1 | 6.75 | 5 | 10 | 5 | 14 | 6 | 15 | 12 | 12 | 12 | 12 |  | 50 Ohms-3 | TOP=L2:L3=L2/L4:L6=L5/L7:BOTTOM=L7 |
| DUALPORTEN#13 | 50OHM_Y12MIL | BUS | 2 | 6 | 5 | 10 | 5 | 14 | 6 | 15 | 12 | 12 | 12 | 12 |  | 50 Ohms-3 | TOP=L2:L3=L2/L4:L6=L5/L7:BOTTOM=L7 |
| DUALPORTEN#13 | 50OHM_Y12MIL | BUS | 3 | 6 | 5 | 10 | 5 | 14 | 6 | 15 | 12 | 12 | 12 | 12 |  | 50 Ohms-3 | TOP=L2:L3=L2/L4:L6=L5/L7:BOTTOM=L7 |
| DUALPORTEN#13 | 50OHM_Y12MIL | BUS | 4 | 6 | 5 | 10 | 5 | 14 | 6 | 15 | 12 | 12 | 12 | 12 |  | 50 Ohms-3 | TOP=L2:L3=L2/L4:L6=L5/L7:BOTTOM=L7 |
| DUALPORTEN#13 | 50OHM_Y12MIL | BUS | 5 | 6 | 5 | 10 | 5 | 14 | 6 | 15 | 12 | 12 | 12 | 12 |  | 50 Ohms-3 | TOP=L2:L3=L2/L4:L6=L5/L7:BOTTOM=L7 |
| DUALPORTEN#13 | 50OHM_Y12MIL | BUS | 6 | 6 | 5 | 10 | 5 | 14 | 6 | 15 | 12 | 12 | 12 | 12 |  | 50 Ohms-3 | TOP=L2:L3=L2/L4:L6=L5/L7:BOTTOM=L7 |
| DUALPORTEN#13 | 50OHM_Y12MIL | BUS | 7 | 6 | 5 | 10 | 5 | 14 | 6 | 15 | 12 | 12 | 12 | 12 |  | 50 Ohms-3 | TOP=L2:L3=L2/L4:L6=L5/L7:BOTTOM=L7 |
| DUALPORTEN#13 | 50OHM_Y12MIL | BUS | 8 | 6.75 | 5 | 10 | 5 | 14 | 6 | 15 | 12 | 12 | 12 | 12 |  | 50 Ohms-3 | TOP=L2:L3=L2/L4:L6=L5/L7:BOTTOM=L7 |
| DUALPORTEN#14 | 50OHM_Y12MIL | BUS | 1 | 6.75 | 5 | 10 | 5 | 14 | 6 | 15 | 12 | 12 | 12 | 12 |  | 50 Ohms-3 | TOP=L2:L3=L2/L4:L6=L5/L7:BOTTOM=L7 |
| DUALPORTEN#14 | 50OHM_Y12MIL | BUS | 2 | 6 | 5 | 10 | 5 | 14 | 6 | 15 | 12 | 12 | 12 | 12 |  | 50 Ohms-3 | TOP=L2:L3=L2/L4:L6=L5/L7:BOTTOM=L7 |
| DUALPORTEN#14 | 50OHM_Y12MIL | BUS | 3 | 6 | 5 | 10 | 5 | 14 | 6 | 15 | 12 | 12 | 12 | 12 |  | 50 Ohms-3 | TOP=L2:L3=L2/L4:L6=L5/L7:BOTTOM=L7 |
| DUALPORTEN#14 | 50OHM_Y12MIL | BUS | 4 | 6 | 5 | 10 | 5 | 14 | 6 | 15 | 12 | 12 | 12 | 12 |  | 50 Ohms-3 | TOP=L2:L3=L2/L4:L6=L5/L7:BOTTOM=L7 |
| DUALPORTEN#14 | 50OHM_Y12MIL | BUS | 5 | 6 | 5 | 10 | 5 | 14 | 6 | 15 | 12 | 12 | 12 | 12 |  | 50 Ohms-3 | TOP=L2:L3=L2/L4:L6=L5/L7:BOTTOM=L7 |
| DUALPORTEN#14 | 50OHM_Y12MIL | BUS | 6 | 6 | 5 | 10 | 5 | 14 | 6 | 15 | 12 | 12 | 12 | 12 |  | 50 Ohms-3 | TOP=L2:L3=L2/L4:L6=L5/L7:BOTTOM=L7 |
| DUALPORTEN#14 | 50OHM_Y12MIL | BUS | 7 | 6 | 5 | 10 | 5 | 14 | 6 | 15 | 12 | 12 | 12 | 12 |  | 50 Ohms-3 | TOP=L2:L3=L2/L4:L6=L5/L7:BOTTOM=L7 |
| DUALPORTEN#14 | 50OHM_Y12MIL | BUS | 8 | 6.75 | 5 | 10 | 5 | 14 | 6 | 15 | 12 | 12 | 12 | 12 |  | 50 Ohms-3 | TOP=L2:L3=L2/L4:L6=L5/L7:BOTTOM=L7 |
| DUALPORTEN#2 | 50OHM_Y12MIL | BUS | 1 | 6.75 | 5 | 10 | 5 | 14 | 6 | 15 | 12 | 12 | 12 | 12 |  | 50 Ohms-3 | TOP=L2:L3=L2/L4:L6=L5/L7:BOTTOM=L7 |
| DUALPORTEN#2 | 50OHM_Y12MIL | BUS | 2 | 6 | 5 | 10 | 5 | 14 | 6 | 15 | 12 | 12 | 12 | 12 |  | 50 Ohms-3 | TOP=L2:L3=L2/L4:L6=L5/L7:BOTTOM=L7 |
| DUALPORTEN#2 | 50OHM_Y12MIL | BUS | 3 | 6 | 5 | 10 | 5 | 14 | 6 | 15 | 12 | 12 | 12 | 12 |  | 50 Ohms-3 | TOP=L2:L3=L2/L4:L6=L5/L7:BOTTOM=L7 |
| DUALPORTEN#2 | 50OHM_Y12MIL | BUS | 4 | 6 | 5 | 10 | 5 | 14 | 6 | 15 | 12 | 12 | 12 | 12 |  | 50 Ohms-3 | TOP=L2:L3=L2/L4:L6=L5/L7:BOTTOM=L7 |
| DUALPORTEN#2 | 50OHM_Y12MIL | BUS | 5 | 6 | 5 | 10 | 5 | 14 | 6 | 15 | 12 | 12 | 12 | 12 |  | 50 Ohms-3 | TOP=L2:L3=L2/L4:L6=L5/L7:BOTTOM=L7 |
| DUALPORTEN#2 | 50OHM_Y12MIL | BUS | 6 | 6 | 5 | 10 | 5 | 14 | 6 | 15 | 12 | 12 | 12 | 12 |  | 50 Ohms-3 | TOP=L2:L3=L2/L4:L6=L5/L7:BOTTOM=L7 |
| DUALPORTEN#2 | 50OHM_Y12MIL | BUS | 7 | 6 | 5 | 10 | 5 | 14 | 6 | 15 | 12 | 12 | 12 | 12 |  | 50 Ohms-3 | TOP=L2:L3=L2/L4:L6=L5/L7:BOTTOM=L7 |
| DUALPORTEN#2 | 50OHM_Y12MIL | BUS | 8 | 6.75 | 5 | 10 | 5 | 14 | 6 | 15 | 12 | 12 | 12 | 12 |  | 50 Ohms-3 | TOP=L2:L3=L2/L4:L6=L5/L7:BOTTOM=L7 |
| DUALPORTEN#3 | 50OHM_Y12MIL | BUS | 1 | 6.75 | 5 | 10 | 5 | 14 | 6 | 15 | 12 | 12 | 12 | 12 |  | 50 Ohms-3 | TOP=L2:L3=L2/L4:L6=L5/L7:BOTTOM=L7 |
| DUALPORTEN#3 | 50OHM_Y12MIL | BUS | 2 | 6 | 5 | 10 | 5 | 14 | 6 | 15 | 12 | 12 | 12 | 12 |  | 50 Ohms-3 | TOP=L2:L3=L2/L4:L6=L5/L7:BOTTOM=L7 |
| DUALPORTEN#3 | 50OHM_Y12MIL | BUS | 3 | 6 | 5 | 10 | 5 | 14 | 6 | 15 | 12 | 12 | 12 | 12 |  | 50 Ohms-3 | TOP=L2:L3=L2/L4:L6=L5/L7:BOTTOM=L7 |
| DUALPORTEN#3 | 50OHM_Y12MIL | BUS | 4 | 6 | 5 | 10 | 5 | 14 | 6 | 15 | 12 | 12 | 12 | 12 |  | 50 Ohms-3 | TOP=L2:L3=L2/L4:L6=L5/L7:BOTTOM=L7 |
| DUALPORTEN#3 | 50OHM_Y12MIL | BUS | 5 | 6 | 5 | 10 | 5 | 14 | 6 | 15 | 12 | 12 | 12 | 12 |  | 50 Ohms-3 | TOP=L2:L3=L2/L4:L6=L5/L7:BOTTOM=L7 |
| DUALPORTEN#3 | 50OHM_Y12MIL | BUS | 6 | 6 | 5 | 10 | 5 | 14 | 6 | 15 | 12 | 12 | 12 | 12 |  | 50 Ohms-3 | TOP=L2:L3=L2/L4:L6=L5/L7:BOTTOM=L7 |
| DUALPORTEN#3 | 50OHM_Y12MIL | BUS | 7 | 6 | 5 | 10 | 5 | 14 | 6 | 15 | 12 | 12 | 12 | 12 |  | 50 Ohms-3 | TOP=L2:L3=L2/L4:L6=L5/L7:BOTTOM=L7 |
| DUALPORTEN#3 | 50OHM_Y12MIL | BUS | 8 | 6.75 | 5 | 10 | 5 | 14 | 6 | 15 | 12 | 12 | 12 | 12 |  | 50 Ohms-3 | TOP=L2:L3=L2/L4:L6=L5/L7:BOTTOM=L7 |
| DUALPORTEN#4 | 50OHM_Y12MIL | BUS | 1 | 6.75 | 5 | 10 | 5 | 14 | 6 | 15 | 12 | 12 | 12 | 12 |  | 50 Ohms-3 | TOP=L2:L3=L2/L4:L6=L5/L7:BOTTOM=L7 |
| DUALPORTEN#4 | 50OHM_Y12MIL | BUS | 2 | 6 | 5 | 10 | 5 | 14 | 6 | 15 | 12 | 12 | 12 | 12 |  | 50 Ohms-3 | TOP=L2:L3=L2/L4:L6=L5/L7:BOTTOM=L7 |
| DUALPORTEN#4 | 50OHM_Y12MIL | BUS | 3 | 6 | 5 | 10 | 5 | 14 | 6 | 15 | 12 | 12 | 12 | 12 |  | 50 Ohms-3 | TOP=L2:L3=L2/L4:L6=L5/L7:BOTTOM=L7 |
| DUALPORTEN#4 | 50OHM_Y12MIL | BUS | 4 | 6 | 5 | 10 | 5 | 14 | 6 | 15 | 12 | 12 | 12 | 12 |  | 50 Ohms-3 | TOP=L2:L3=L2/L4:L6=L5/L7:BOTTOM=L7 |
| DUALPORTEN#4 | 50OHM_Y12MIL | BUS | 5 | 6 | 5 | 10 | 5 | 14 | 6 | 15 | 12 | 12 | 12 | 12 |  | 50 Ohms-3 | TOP=L2:L3=L2/L4:L6=L5/L7:BOTTOM=L7 |
| DUALPORTEN#4 | 50OHM_Y12MIL | BUS | 6 | 6 | 5 | 10 | 5 | 14 | 6 | 15 | 12 | 12 | 12 | 12 |  | 50 Ohms-3 | TOP=L2:L3=L2/L4:L6=L5/L7:BOTTOM=L7 |
| DUALPORTEN#4 | 50OHM_Y12MIL | BUS | 7 | 6 | 5 | 10 | 5 | 14 | 6 | 15 | 12 | 12 | 12 | 12 |  | 50 Ohms-3 | TOP=L2:L3=L2/L4:L6=L5/L7:BOTTOM=L7 |
| DUALPORTEN#4 | 50OHM_Y12MIL | BUS | 8 | 6.75 | 5 | 10 | 5 | 14 | 6 | 15 | 12 | 12 | 12 | 12 |  | 50 Ohms-3 | TOP=L2:L3=L2/L4:L6=L5/L7:BOTTOM=L7 |
| DUALPORTEN#5 | 50OHM_Y12MIL | BUS | 1 | 6.75 | 5 | 10 | 5 | 14 | 6 | 15 | 12 | 12 | 12 | 12 |  | 50 Ohms-3 | TOP=L2:L3=L2/L4:L6=L5/L7:BOTTOM=L7 |
| DUALPORTEN#5 | 50OHM_Y12MIL | BUS | 2 | 6 | 5 | 10 | 5 | 14 | 6 | 15 | 12 | 12 | 12 | 12 |  | 50 Ohms-3 | TOP=L2:L3=L2/L4:L6=L5/L7:BOTTOM=L7 |
| DUALPORTEN#5 | 50OHM_Y12MIL | BUS | 3 | 6 | 5 | 10 | 5 | 14 | 6 | 15 | 12 | 12 | 12 | 12 |  | 50 Ohms-3 | TOP=L2:L3=L2/L4:L6=L5/L7:BOTTOM=L7 |
| DUALPORTEN#5 | 50OHM_Y12MIL | BUS | 4 | 6 | 5 | 10 | 5 | 14 | 6 | 15 | 12 | 12 | 12 | 12 |  | 50 Ohms-3 | TOP=L2:L3=L2/L4:L6=L5/L7:BOTTOM=L7 |
| DUALPORTEN#5 | 50OHM_Y12MIL | BUS | 5 | 6 | 5 | 10 | 5 | 14 | 6 | 15 | 12 | 12 | 12 | 12 |  | 50 Ohms-3 | TOP=L2:L3=L2/L4:L6=L5/L7:BOTTOM=L7 |
| DUALPORTEN#5 | 50OHM_Y12MIL | BUS | 6 | 6 | 5 | 10 | 5 | 14 | 6 | 15 | 12 | 12 | 12 | 12 |  | 50 Ohms-3 | TOP=L2:L3=L2/L4:L6=L5/L7:BOTTOM=L7 |
| DUALPORTEN#5 | 50OHM_Y12MIL | BUS | 7 | 6 | 5 | 10 | 5 | 14 | 6 | 15 | 12 | 12 | 12 | 12 |  | 50 Ohms-3 | TOP=L2:L3=L2/L4:L6=L5/L7:BOTTOM=L7 |
| DUALPORTEN#5 | 50OHM_Y12MIL | BUS | 8 | 6.75 | 5 | 10 | 5 | 14 | 6 | 15 | 12 | 12 | 12 | 12 |  | 50 Ohms-3 | TOP=L2:L3=L2/L4:L6=L5/L7:BOTTOM=L7 |
| DUALPORTEN#6 | 50OHM_Y12MIL | BUS | 1 | 6.75 | 5 | 10 | 5 | 14 | 6 | 15 | 12 | 12 | 12 | 12 |  | 50 Ohms-3 | TOP=L2:L3=L2/L4:L6=L5/L7:BOTTOM=L7 |
| DUALPORTEN#6 | 50OHM_Y12MIL | BUS | 2 | 6 | 5 | 10 | 5 | 14 | 6 | 15 | 12 | 12 | 12 | 12 |  | 50 Ohms-3 | TOP=L2:L3=L2/L4:L6=L5/L7:BOTTOM=L7 |
| DUALPORTEN#6 | 50OHM_Y12MIL | BUS | 3 | 6 | 5 | 10 | 5 | 14 | 6 | 15 | 12 | 12 | 12 | 12 |  | 50 Ohms-3 | TOP=L2:L3=L2/L4:L6=L5/L7:BOTTOM=L7 |
| DUALPORTEN#6 | 50OHM_Y12MIL | BUS | 4 | 6 | 5 | 10 | 5 | 14 | 6 | 15 | 12 | 12 | 12 | 12 |  | 50 Ohms-3 | TOP=L2:L3=L2/L4:L6=L5/L7:BOTTOM=L7 |
| DUALPORTEN#6 | 50OHM_Y12MIL | BUS | 5 | 6 | 5 | 10 | 5 | 14 | 6 | 15 | 12 | 12 | 12 | 12 |  | 50 Ohms-3 | TOP=L2:L3=L2/L4:L6=L5/L7:BOTTOM=L7 |
| DUALPORTEN#6 | 50OHM_Y12MIL | BUS | 6 | 6 | 5 | 10 | 5 | 14 | 6 | 15 | 12 | 12 | 12 | 12 |  | 50 Ohms-3 | TOP=L2:L3=L2/L4:L6=L5/L7:BOTTOM=L7 |
| DUALPORTEN#6 | 50OHM_Y12MIL | BUS | 7 | 6 | 5 | 10 | 5 | 14 | 6 | 15 | 12 | 12 | 12 | 12 |  | 50 Ohms-3 | TOP=L2:L3=L2/L4:L6=L5/L7:BOTTOM=L7 |
| DUALPORTEN#6 | 50OHM_Y12MIL | BUS | 8 | 6.75 | 5 | 10 | 5 | 14 | 6 | 15 | 12 | 12 | 12 | 12 |  | 50 Ohms-3 | TOP=L2:L3=L2/L4:L6=L5/L7:BOTTOM=L7 |
| DUALPORTEN#7 | 50OHM_Y12MIL | BUS | 1 | 6.75 | 5 | 10 | 5 | 14 | 6 | 15 | 12 | 12 | 12 | 12 |  | 50 Ohms-3 | TOP=L2:L3=L2/L4:L6=L5/L7:BOTTOM=L7 |
| DUALPORTEN#7 | 50OHM_Y12MIL | BUS | 2 | 6 | 5 | 10 | 5 | 14 | 6 | 15 | 12 | 12 | 12 | 12 |  | 50 Ohms-3 | TOP=L2:L3=L2/L4:L6=L5/L7:BOTTOM=L7 |
| DUALPORTEN#7 | 50OHM_Y12MIL | BUS | 3 | 6 | 5 | 10 | 5 | 14 | 6 | 15 | 12 | 12 | 12 | 12 |  | 50 Ohms-3 | TOP=L2:L3=L2/L4:L6=L5/L7:BOTTOM=L7 |
| DUALPORTEN#7 | 50OHM_Y12MIL | BUS | 4 | 6 | 5 | 10 | 5 | 14 | 6 | 15 | 12 | 12 | 12 | 12 |  | 50 Ohms-3 | TOP=L2:L3=L2/L4:L6=L5/L7:BOTTOM=L7 |
| DUALPORTEN#7 | 50OHM_Y12MIL | BUS | 5 | 6 | 5 | 10 | 5 | 14 | 6 | 15 | 12 | 12 | 12 | 12 |  | 50 Ohms-3 | TOP=L2:L3=L2/L4:L6=L5/L7:BOTTOM=L7 |
| DUALPORTEN#7 | 50OHM_Y12MIL | BUS | 6 | 6 | 5 | 10 | 5 | 14 | 6 | 15 | 12 | 12 | 12 | 12 |  | 50 Ohms-3 | TOP=L2:L3=L2/L4:L6=L5/L7:BOTTOM=L7 |
| DUALPORTEN#7 | 50OHM_Y12MIL | BUS | 7 | 6 | 5 | 10 | 5 | 14 | 6 | 15 | 12 | 12 | 12 | 12 |  | 50 Ohms-3 | TOP=L2:L3=L2/L4:L6=L5/L7:BOTTOM=L7 |
| DUALPORTEN#7 | 50OHM_Y12MIL | BUS | 8 | 6.75 | 5 | 10 | 5 | 14 | 6 | 15 | 12 | 12 | 12 | 12 |  | 50 Ohms-3 | TOP=L2:L3=L2/L4:L6=L5/L7:BOTTOM=L7 |
| DUALPORTEN#8 | 50OHM_Y12MIL | BUS | 1 | 6.75 | 5 | 10 | 5 | 14 | 6 | 15 | 12 | 12 | 12 | 12 |  | 50 Ohms-3 | TOP=L2:L3=L2/L4:L6=L5/L7:BOTTOM=L7 |
| DUALPORTEN#8 | 50OHM_Y12MIL | BUS | 2 | 6 | 5 | 10 | 5 | 14 | 6 | 15 | 12 | 12 | 12 | 12 |  | 50 Ohms-3 | TOP=L2:L3=L2/L4:L6=L5/L7:BOTTOM=L7 |
| DUALPORTEN#8 | 50OHM_Y12MIL | BUS | 3 | 6 | 5 | 10 | 5 | 14 | 6 | 15 | 12 | 12 | 12 | 12 |  | 50 Ohms-3 | TOP=L2:L3=L2/L4:L6=L5/L7:BOTTOM=L7 |
| DUALPORTEN#8 | 50OHM_Y12MIL | BUS | 4 | 6 | 5 | 10 | 5 | 14 | 6 | 15 | 12 | 12 | 12 | 12 |  | 50 Ohms-3 | TOP=L2:L3=L2/L4:L6=L5/L7:BOTTOM=L7 |
| DUALPORTEN#8 | 50OHM_Y12MIL | BUS | 5 | 6 | 5 | 10 | 5 | 14 | 6 | 15 | 12 | 12 | 12 | 12 |  | 50 Ohms-3 | TOP=L2:L3=L2/L4:L6=L5/L7:BOTTOM=L7 |
| DUALPORTEN#8 | 50OHM_Y12MIL | BUS | 6 | 6 | 5 | 10 | 5 | 14 | 6 | 15 | 12 | 12 | 12 | 12 |  | 50 Ohms-3 | TOP=L2:L3=L2/L4:L6=L5/L7:BOTTOM=L7 |
| DUALPORTEN#8 | 50OHM_Y12MIL | BUS | 7 | 6 | 5 | 10 | 5 | 14 | 6 | 15 | 12 | 12 | 12 | 12 |  | 50 Ohms-3 | TOP=L2:L3=L2/L4:L6=L5/L7:BOTTOM=L7 |
| DUALPORTEN#8 | 50OHM_Y12MIL | BUS | 8 | 6.75 | 5 | 10 | 5 | 14 | 6 | 15 | 12 | 12 | 12 | 12 |  | 50 Ohms-3 | TOP=L2:L3=L2/L4:L6=L5/L7:BOTTOM=L7 |
| DUALPORTEN#9 | 50OHM_Y12MIL | BUS | 1 | 6.75 | 5 | 10 | 5 | 14 | 6 | 15 | 12 | 12 | 12 | 12 |  | 50 Ohms-3 | TOP=L2:L3=L2/L4:L6=L5/L7:BOTTOM=L7 |
| DUALPORTEN#9 | 50OHM_Y12MIL | BUS | 2 | 6 | 5 | 10 | 5 | 14 | 6 | 15 | 12 | 12 | 12 | 12 |  | 50 Ohms-3 | TOP=L2:L3=L2/L4:L6=L5/L7:BOTTOM=L7 |
| DUALPORTEN#9 | 50OHM_Y12MIL | BUS | 3 | 6 | 5 | 10 | 5 | 14 | 6 | 15 | 12 | 12 | 12 | 12 |  | 50 Ohms-3 | TOP=L2:L3=L2/L4:L6=L5/L7:BOTTOM=L7 |
| DUALPORTEN#9 | 50OHM_Y12MIL | BUS | 4 | 6 | 5 | 10 | 5 | 14 | 6 | 15 | 12 | 12 | 12 | 12 |  | 50 Ohms-3 | TOP=L2:L3=L2/L4:L6=L5/L7:BOTTOM=L7 |
| DUALPORTEN#9 | 50OHM_Y12MIL | BUS | 5 | 6 | 5 | 10 | 5 | 14 | 6 | 15 | 12 | 12 | 12 | 12 |  | 50 Ohms-3 | TOP=L2:L3=L2/L4:L6=L5/L7:BOTTOM=L7 |
| DUALPORTEN#9 | 50OHM_Y12MIL | BUS | 6 | 6 | 5 | 10 | 5 | 14 | 6 | 15 | 12 | 12 | 12 | 12 |  | 50 Ohms-3 | TOP=L2:L3=L2/L4:L6=L5/L7:BOTTOM=L7 |
| DUALPORTEN#9 | 50OHM_Y12MIL | BUS | 7 | 6 | 5 | 10 | 5 | 14 | 6 | 15 | 12 | 12 | 12 | 12 |  | 50 Ohms-3 | TOP=L2:L3=L2/L4:L6=L5/L7:BOTTOM=L7 |
| DUALPORTEN#9 | 50OHM_Y12MIL | BUS | 8 | 6.75 | 5 | 10 | 5 | 14 | 6 | 15 | 12 | 12 | 12 | 12 |  | 50 Ohms-3 | TOP=L2:L3=L2/L4:L6=L5/L7:BOTTOM=L7 |
| EEPROM_A0 | 50OHM_Y12MIL | BUS | 1 | 6.75 | 5 | 10 | 5 | 14 | 6 | 15 | 12 | 12 | 12 | 12 |  | 50 Ohms-3 | TOP=L2:L3=L2/L4:L6=L5/L7:BOTTOM=L7 |
| EEPROM_A0 | 50OHM_Y12MIL | BUS | 2 | 6 | 5 | 10 | 5 | 14 | 6 | 15 | 12 | 12 | 12 | 12 |  | 50 Ohms-3 | TOP=L2:L3=L2/L4:L6=L5/L7:BOTTOM=L7 |
| EEPROM_A0 | 50OHM_Y12MIL | BUS | 3 | 6 | 5 | 10 | 5 | 14 | 6 | 15 | 12 | 12 | 12 | 12 |  | 50 Ohms-3 | TOP=L2:L3=L2/L4:L6=L5/L7:BOTTOM=L7 |
| EEPROM_A0 | 50OHM_Y12MIL | BUS | 4 | 6 | 5 | 10 | 5 | 14 | 6 | 15 | 12 | 12 | 12 | 12 |  | 50 Ohms-3 | TOP=L2:L3=L2/L4:L6=L5/L7:BOTTOM=L7 |
| EEPROM_A0 | 50OHM_Y12MIL | BUS | 5 | 6 | 5 | 10 | 5 | 14 | 6 | 15 | 12 | 12 | 12 | 12 |  | 50 Ohms-3 | TOP=L2:L3=L2/L4:L6=L5/L7:BOTTOM=L7 |
| EEPROM_A0 | 50OHM_Y12MIL | BUS | 6 | 6 | 5 | 10 | 5 | 14 | 6 | 15 | 12 | 12 | 12 | 12 |  | 50 Ohms-3 | TOP=L2:L3=L2/L4:L6=L5/L7:BOTTOM=L7 |
| EEPROM_A0 | 50OHM_Y12MIL | BUS | 7 | 6 | 5 | 10 | 5 | 14 | 6 | 15 | 12 | 12 | 12 | 12 |  | 50 Ohms-3 | TOP=L2:L3=L2/L4:L6=L5/L7:BOTTOM=L7 |
| EEPROM_A0 | 50OHM_Y12MIL | BUS | 8 | 6.75 | 5 | 10 | 5 | 14 | 6 | 15 | 12 | 12 | 12 | 12 |  | 50 Ohms-3 | TOP=L2:L3=L2/L4:L6=L5/L7:BOTTOM=L7 |
| EEPROM_A1 | 50OHM_Y12MIL | BUS | 1 | 6.75 | 5 | 10 | 5 | 14 | 6 | 15 | 12 | 12 | 12 | 12 |  | 50 Ohms-3 | TOP=L2:L3=L2/L4:L6=L5/L7:BOTTOM=L7 |
| EEPROM_A1 | 50OHM_Y12MIL | BUS | 2 | 6 | 5 | 10 | 5 | 14 | 6 | 15 | 12 | 12 | 12 | 12 |  | 50 Ohms-3 | TOP=L2:L3=L2/L4:L6=L5/L7:BOTTOM=L7 |
| EEPROM_A1 | 50OHM_Y12MIL | BUS | 3 | 6 | 5 | 10 | 5 | 14 | 6 | 15 | 12 | 12 | 12 | 12 |  | 50 Ohms-3 | TOP=L2:L3=L2/L4:L6=L5/L7:BOTTOM=L7 |
| EEPROM_A1 | 50OHM_Y12MIL | BUS | 4 | 6 | 5 | 10 | 5 | 14 | 6 | 15 | 12 | 12 | 12 | 12 |  | 50 Ohms-3 | TOP=L2:L3=L2/L4:L6=L5/L7:BOTTOM=L7 |
| EEPROM_A1 | 50OHM_Y12MIL | BUS | 5 | 6 | 5 | 10 | 5 | 14 | 6 | 15 | 12 | 12 | 12 | 12 |  | 50 Ohms-3 | TOP=L2:L3=L2/L4:L6=L5/L7:BOTTOM=L7 |
| EEPROM_A1 | 50OHM_Y12MIL | BUS | 6 | 6 | 5 | 10 | 5 | 14 | 6 | 15 | 12 | 12 | 12 | 12 |  | 50 Ohms-3 | TOP=L2:L3=L2/L4:L6=L5/L7:BOTTOM=L7 |
| EEPROM_A1 | 50OHM_Y12MIL | BUS | 7 | 6 | 5 | 10 | 5 | 14 | 6 | 15 | 12 | 12 | 12 | 12 |  | 50 Ohms-3 | TOP=L2:L3=L2/L4:L6=L5/L7:BOTTOM=L7 |
| EEPROM_A1 | 50OHM_Y12MIL | BUS | 8 | 6.75 | 5 | 10 | 5 | 14 | 6 | 15 | 12 | 12 | 12 | 12 |  | 50 Ohms-3 | TOP=L2:L3=L2/L4:L6=L5/L7:BOTTOM=L7 |
| EEPROM_A2 | 50OHM_Y12MIL | BUS | 1 | 6.75 | 5 | 10 | 5 | 14 | 6 | 15 | 12 | 12 | 12 | 12 |  | 50 Ohms-3 | TOP=L2:L3=L2/L4:L6=L5/L7:BOTTOM=L7 |
| EEPROM_A2 | 50OHM_Y12MIL | BUS | 2 | 6 | 5 | 10 | 5 | 14 | 6 | 15 | 12 | 12 | 12 | 12 |  | 50 Ohms-3 | TOP=L2:L3=L2/L4:L6=L5/L7:BOTTOM=L7 |
| EEPROM_A2 | 50OHM_Y12MIL | BUS | 3 | 6 | 5 | 10 | 5 | 14 | 6 | 15 | 12 | 12 | 12 | 12 |  | 50 Ohms-3 | TOP=L2:L3=L2/L4:L6=L5/L7:BOTTOM=L7 |
| EEPROM_A2 | 50OHM_Y12MIL | BUS | 4 | 6 | 5 | 10 | 5 | 14 | 6 | 15 | 12 | 12 | 12 | 12 |  | 50 Ohms-3 | TOP=L2:L3=L2/L4:L6=L5/L7:BOTTOM=L7 |
| EEPROM_A2 | 50OHM_Y12MIL | BUS | 5 | 6 | 5 | 10 | 5 | 14 | 6 | 15 | 12 | 12 | 12 | 12 |  | 50 Ohms-3 | TOP=L2:L3=L2/L4:L6=L5/L7:BOTTOM=L7 |
| EEPROM_A2 | 50OHM_Y12MIL | BUS | 6 | 6 | 5 | 10 | 5 | 14 | 6 | 15 | 12 | 12 | 12 | 12 |  | 50 Ohms-3 | TOP=L2:L3=L2/L4:L6=L5/L7:BOTTOM=L7 |
| EEPROM_A2 | 50OHM_Y12MIL | BUS | 7 | 6 | 5 | 10 | 5 | 14 | 6 | 15 | 12 | 12 | 12 | 12 |  | 50 Ohms-3 | TOP=L2:L3=L2/L4:L6=L5/L7:BOTTOM=L7 |
| EEPROM_A2 | 50OHM_Y12MIL | BUS | 8 | 6.75 | 5 | 10 | 5 | 14 | 6 | 15 | 12 | 12 | 12 | 12 |  | 50 Ohms-3 | TOP=L2:L3=L2/L4:L6=L5/L7:BOTTOM=L7 |
| EEPROM_SCL | 50OHM_Y12MIL | BUS | 1 | 6.75 | 5 | 10 | 5 | 14 | 6 | 15 | 12 | 12 | 12 | 12 |  | 50 Ohms-3 | TOP=L2:L3=L2/L4:L6=L5/L7:BOTTOM=L7 |
| EEPROM_SCL | 50OHM_Y12MIL | BUS | 2 | 6 | 5 | 10 | 5 | 14 | 6 | 15 | 12 | 12 | 12 | 12 |  | 50 Ohms-3 | TOP=L2:L3=L2/L4:L6=L5/L7:BOTTOM=L7 |
| EEPROM_SCL | 50OHM_Y12MIL | BUS | 3 | 6 | 5 | 10 | 5 | 14 | 6 | 15 | 12 | 12 | 12 | 12 |  | 50 Ohms-3 | TOP=L2:L3=L2/L4:L6=L5/L7:BOTTOM=L7 |
| EEPROM_SCL | 50OHM_Y12MIL | BUS | 4 | 6 | 5 | 10 | 5 | 14 | 6 | 15 | 12 | 12 | 12 | 12 |  | 50 Ohms-3 | TOP=L2:L3=L2/L4:L6=L5/L7:BOTTOM=L7 |
| EEPROM_SCL | 50OHM_Y12MIL | BUS | 5 | 6 | 5 | 10 | 5 | 14 | 6 | 15 | 12 | 12 | 12 | 12 |  | 50 Ohms-3 | TOP=L2:L3=L2/L4:L6=L5/L7:BOTTOM=L7 |
| EEPROM_SCL | 50OHM_Y12MIL | BUS | 6 | 6 | 5 | 10 | 5 | 14 | 6 | 15 | 12 | 12 | 12 | 12 |  | 50 Ohms-3 | TOP=L2:L3=L2/L4:L6=L5/L7:BOTTOM=L7 |
| EEPROM_SCL | 50OHM_Y12MIL | BUS | 7 | 6 | 5 | 10 | 5 | 14 | 6 | 15 | 12 | 12 | 12 | 12 |  | 50 Ohms-3 | TOP=L2:L3=L2/L4:L6=L5/L7:BOTTOM=L7 |
| EEPROM_SCL | 50OHM_Y12MIL | BUS | 8 | 6.75 | 5 | 10 | 5 | 14 | 6 | 15 | 12 | 12 | 12 | 12 |  | 50 Ohms-3 | TOP=L2:L3=L2/L4:L6=L5/L7:BOTTOM=L7 |
| EEPROM_SDA | 50OHM_Y12MIL | BUS | 1 | 6.75 | 5 | 10 | 5 | 14 | 6 | 15 | 12 | 12 | 12 | 12 |  | 50 Ohms-3 | TOP=L2:L3=L2/L4:L6=L5/L7:BOTTOM=L7 |
| EEPROM_SDA | 50OHM_Y12MIL | BUS | 2 | 6 | 5 | 10 | 5 | 14 | 6 | 15 | 12 | 12 | 12 | 12 |  | 50 Ohms-3 | TOP=L2:L3=L2/L4:L6=L5/L7:BOTTOM=L7 |
| EEPROM_SDA | 50OHM_Y12MIL | BUS | 3 | 6 | 5 | 10 | 5 | 14 | 6 | 15 | 12 | 12 | 12 | 12 |  | 50 Ohms-3 | TOP=L2:L3=L2/L4:L6=L5/L7:BOTTOM=L7 |
| EEPROM_SDA | 50OHM_Y12MIL | BUS | 4 | 6 | 5 | 10 | 5 | 14 | 6 | 15 | 12 | 12 | 12 | 12 |  | 50 Ohms-3 | TOP=L2:L3=L2/L4:L6=L5/L7:BOTTOM=L7 |
| EEPROM_SDA | 50OHM_Y12MIL | BUS | 5 | 6 | 5 | 10 | 5 | 14 | 6 | 15 | 12 | 12 | 12 | 12 |  | 50 Ohms-3 | TOP=L2:L3=L2/L4:L6=L5/L7:BOTTOM=L7 |
| EEPROM_SDA | 50OHM_Y12MIL | BUS | 6 | 6 | 5 | 10 | 5 | 14 | 6 | 15 | 12 | 12 | 12 | 12 |  | 50 Ohms-3 | TOP=L2:L3=L2/L4:L6=L5/L7:BOTTOM=L7 |
| EEPROM_SDA | 50OHM_Y12MIL | BUS | 7 | 6 | 5 | 10 | 5 | 14 | 6 | 15 | 12 | 12 | 12 | 12 |  | 50 Ohms-3 | TOP=L2:L3=L2/L4:L6=L5/L7:BOTTOM=L7 |
| EEPROM_SDA | 50OHM_Y12MIL | BUS | 8 | 6.75 | 5 | 10 | 5 | 14 | 6 | 15 | 12 | 12 | 12 | 12 |  | 50 Ohms-3 | TOP=L2:L3=L2/L4:L6=L5/L7:BOTTOM=L7 |
| EEPROM_WP | 50OHM_Y12MIL | BUS | 1 | 6.75 | 5 | 10 | 5 | 14 | 6 | 15 | 12 | 12 | 12 | 12 |  | 50 Ohms-3 | TOP=L2:L3=L2/L4:L6=L5/L7:BOTTOM=L7 |
| EEPROM_WP | 50OHM_Y12MIL | BUS | 2 | 6 | 5 | 10 | 5 | 14 | 6 | 15 | 12 | 12 | 12 | 12 |  | 50 Ohms-3 | TOP=L2:L3=L2/L4:L6=L5/L7:BOTTOM=L7 |
| EEPROM_WP | 50OHM_Y12MIL | BUS | 3 | 6 | 5 | 10 | 5 | 14 | 6 | 15 | 12 | 12 | 12 | 12 |  | 50 Ohms-3 | TOP=L2:L3=L2/L4:L6=L5/L7:BOTTOM=L7 |
| EEPROM_WP | 50OHM_Y12MIL | BUS | 4 | 6 | 5 | 10 | 5 | 14 | 6 | 15 | 12 | 12 | 12 | 12 |  | 50 Ohms-3 | TOP=L2:L3=L2/L4:L6=L5/L7:BOTTOM=L7 |
| EEPROM_WP | 50OHM_Y12MIL | BUS | 5 | 6 | 5 | 10 | 5 | 14 | 6 | 15 | 12 | 12 | 12 | 12 |  | 50 Ohms-3 | TOP=L2:L3=L2/L4:L6=L5/L7:BOTTOM=L7 |
| EEPROM_WP | 50OHM_Y12MIL | BUS | 6 | 6 | 5 | 10 | 5 | 14 | 6 | 15 | 12 | 12 | 12 | 12 |  | 50 Ohms-3 | TOP=L2:L3=L2/L4:L6=L5/L7:BOTTOM=L7 |
| EEPROM_WP | 50OHM_Y12MIL | BUS | 7 | 6 | 5 | 10 | 5 | 14 | 6 | 15 | 12 | 12 | 12 | 12 |  | 50 Ohms-3 | TOP=L2:L3=L2/L4:L6=L5/L7:BOTTOM=L7 |
| EEPROM_WP | 50OHM_Y12MIL | BUS | 8 | 6.75 | 5 | 10 | 5 | 14 | 6 | 15 | 12 | 12 | 12 | 12 |  | 50 Ohms-3 | TOP=L2:L3=L2/L4:L6=L5/L7:BOTTOM=L7 |
| FCB_HW_REVISION | 50OHM_Y12MIL | BUS | 1 | 6.75 | 5 | 10 | 5 | 14 | 6 | 15 | 12 | 12 | 12 | 12 |  | 50 Ohms-3 | TOP=L2:L3=L2/L4:L6=L5/L7:BOTTOM=L7 |
| FCB_HW_REVISION | 50OHM_Y12MIL | BUS | 2 | 6 | 5 | 10 | 5 | 14 | 6 | 15 | 12 | 12 | 12 | 12 |  | 50 Ohms-3 | TOP=L2:L3=L2/L4:L6=L5/L7:BOTTOM=L7 |
| FCB_HW_REVISION | 50OHM_Y12MIL | BUS | 3 | 6 | 5 | 10 | 5 | 14 | 6 | 15 | 12 | 12 | 12 | 12 |  | 50 Ohms-3 | TOP=L2:L3=L2/L4:L6=L5/L7:BOTTOM=L7 |
| FCB_HW_REVISION | 50OHM_Y12MIL | BUS | 4 | 6 | 5 | 10 | 5 | 14 | 6 | 15 | 12 | 12 | 12 | 12 |  | 50 Ohms-3 | TOP=L2:L3=L2/L4:L6=L5/L7:BOTTOM=L7 |
| FCB_HW_REVISION | 50OHM_Y12MIL | BUS | 5 | 6 | 5 | 10 | 5 | 14 | 6 | 15 | 12 | 12 | 12 | 12 |  | 50 Ohms-3 | TOP=L2:L3=L2/L4:L6=L5/L7:BOTTOM=L7 |
| FCB_HW_REVISION | 50OHM_Y12MIL | BUS | 6 | 6 | 5 | 10 | 5 | 14 | 6 | 15 | 12 | 12 | 12 | 12 |  | 50 Ohms-3 | TOP=L2:L3=L2/L4:L6=L5/L7:BOTTOM=L7 |
| FCB_HW_REVISION | 50OHM_Y12MIL | BUS | 7 | 6 | 5 | 10 | 5 | 14 | 6 | 15 | 12 | 12 | 12 | 12 |  | 50 Ohms-3 | TOP=L2:L3=L2/L4:L6=L5/L7:BOTTOM=L7 |
| FCB_HW_REVISION | 50OHM_Y12MIL | BUS | 8 | 6.75 | 5 | 10 | 5 | 14 | 6 | 15 | 12 | 12 | 12 | 12 |  | 50 Ohms-3 | TOP=L2:L3=L2/L4:L6=L5/L7:BOTTOM=L7 |
| I2C_B_TMP1_A0 | 50OHM_Y12MIL | BUS | 1 | 6.75 | 5 | 10 | 5 | 14 | 6 | 15 | 12 | 12 | 12 | 12 |  | 50 Ohms-3 | TOP=L2:L3=L2/L4:L6=L5/L7:BOTTOM=L7 |
| I2C_B_TMP1_A0 | 50OHM_Y12MIL | BUS | 2 | 6 | 5 | 10 | 5 | 14 | 6 | 15 | 12 | 12 | 12 | 12 |  | 50 Ohms-3 | TOP=L2:L3=L2/L4:L6=L5/L7:BOTTOM=L7 |
| I2C_B_TMP1_A0 | 50OHM_Y12MIL | BUS | 3 | 6 | 5 | 10 | 5 | 14 | 6 | 15 | 12 | 12 | 12 | 12 |  | 50 Ohms-3 | TOP=L2:L3=L2/L4:L6=L5/L7:BOTTOM=L7 |
| I2C_B_TMP1_A0 | 50OHM_Y12MIL | BUS | 4 | 6 | 5 | 10 | 5 | 14 | 6 | 15 | 12 | 12 | 12 | 12 |  | 50 Ohms-3 | TOP=L2:L3=L2/L4:L6=L5/L7:BOTTOM=L7 |
| I2C_B_TMP1_A0 | 50OHM_Y12MIL | BUS | 5 | 6 | 5 | 10 | 5 | 14 | 6 | 15 | 12 | 12 | 12 | 12 |  | 50 Ohms-3 | TOP=L2:L3=L2/L4:L6=L5/L7:BOTTOM=L7 |
| I2C_B_TMP1_A0 | 50OHM_Y12MIL | BUS | 6 | 6 | 5 | 10 | 5 | 14 | 6 | 15 | 12 | 12 | 12 | 12 |  | 50 Ohms-3 | TOP=L2:L3=L2/L4:L6=L5/L7:BOTTOM=L7 |
| I2C_B_TMP1_A0 | 50OHM_Y12MIL | BUS | 7 | 6 | 5 | 10 | 5 | 14 | 6 | 15 | 12 | 12 | 12 | 12 |  | 50 Ohms-3 | TOP=L2:L3=L2/L4:L6=L5/L7:BOTTOM=L7 |
| I2C_B_TMP1_A0 | 50OHM_Y12MIL | BUS | 8 | 6.75 | 5 | 10 | 5 | 14 | 6 | 15 | 12 | 12 | 12 | 12 |  | 50 Ohms-3 | TOP=L2:L3=L2/L4:L6=L5/L7:BOTTOM=L7 |
| I2C_B_TMP1_A1 | 50OHM_Y12MIL | BUS | 1 | 6.75 | 5 | 10 | 5 | 14 | 6 | 15 | 12 | 12 | 12 | 12 |  | 50 Ohms-3 | TOP=L2:L3=L2/L4:L6=L5/L7:BOTTOM=L7 |
| I2C_B_TMP1_A1 | 50OHM_Y12MIL | BUS | 2 | 6 | 5 | 10 | 5 | 14 | 6 | 15 | 12 | 12 | 12 | 12 |  | 50 Ohms-3 | TOP=L2:L3=L2/L4:L6=L5/L7:BOTTOM=L7 |
| I2C_B_TMP1_A1 | 50OHM_Y12MIL | BUS | 3 | 6 | 5 | 10 | 5 | 14 | 6 | 15 | 12 | 12 | 12 | 12 |  | 50 Ohms-3 | TOP=L2:L3=L2/L4:L6=L5/L7:BOTTOM=L7 |
| I2C_B_TMP1_A1 | 50OHM_Y12MIL | BUS | 4 | 6 | 5 | 10 | 5 | 14 | 6 | 15 | 12 | 12 | 12 | 12 |  | 50 Ohms-3 | TOP=L2:L3=L2/L4:L6=L5/L7:BOTTOM=L7 |
| I2C_B_TMP1_A1 | 50OHM_Y12MIL | BUS | 5 | 6 | 5 | 10 | 5 | 14 | 6 | 15 | 12 | 12 | 12 | 12 |  | 50 Ohms-3 | TOP=L2:L3=L2/L4:L6=L5/L7:BOTTOM=L7 |
| I2C_B_TMP1_A1 | 50OHM_Y12MIL | BUS | 6 | 6 | 5 | 10 | 5 | 14 | 6 | 15 | 12 | 12 | 12 | 12 |  | 50 Ohms-3 | TOP=L2:L3=L2/L4:L6=L5/L7:BOTTOM=L7 |
| I2C_B_TMP1_A1 | 50OHM_Y12MIL | BUS | 7 | 6 | 5 | 10 | 5 | 14 | 6 | 15 | 12 | 12 | 12 | 12 |  | 50 Ohms-3 | TOP=L2:L3=L2/L4:L6=L5/L7:BOTTOM=L7 |
| I2C_B_TMP1_A1 | 50OHM_Y12MIL | BUS | 8 | 6.75 | 5 | 10 | 5 | 14 | 6 | 15 | 12 | 12 | 12 | 12 |  | 50 Ohms-3 | TOP=L2:L3=L2/L4:L6=L5/L7:BOTTOM=L7 |
| I2C_B_TMP1_A2 | 50OHM_Y12MIL | BUS | 1 | 6.75 | 5 | 10 | 5 | 14 | 6 | 15 | 12 | 12 | 12 | 12 |  | 50 Ohms-3 | TOP=L2:L3=L2/L4:L6=L5/L7:BOTTOM=L7 |
| I2C_B_TMP1_A2 | 50OHM_Y12MIL | BUS | 2 | 6 | 5 | 10 | 5 | 14 | 6 | 15 | 12 | 12 | 12 | 12 |  | 50 Ohms-3 | TOP=L2:L3=L2/L4:L6=L5/L7:BOTTOM=L7 |
| I2C_B_TMP1_A2 | 50OHM_Y12MIL | BUS | 3 | 6 | 5 | 10 | 5 | 14 | 6 | 15 | 12 | 12 | 12 | 12 |  | 50 Ohms-3 | TOP=L2:L3=L2/L4:L6=L5/L7:BOTTOM=L7 |
| I2C_B_TMP1_A2 | 50OHM_Y12MIL | BUS | 4 | 6 | 5 | 10 | 5 | 14 | 6 | 15 | 12 | 12 | 12 | 12 |  | 50 Ohms-3 | TOP=L2:L3=L2/L4:L6=L5/L7:BOTTOM=L7 |
| I2C_B_TMP1_A2 | 50OHM_Y12MIL | BUS | 5 | 6 | 5 | 10 | 5 | 14 | 6 | 15 | 12 | 12 | 12 | 12 |  | 50 Ohms-3 | TOP=L2:L3=L2/L4:L6=L5/L7:BOTTOM=L7 |
| I2C_B_TMP1_A2 | 50OHM_Y12MIL | BUS | 6 | 6 | 5 | 10 | 5 | 14 | 6 | 15 | 12 | 12 | 12 | 12 |  | 50 Ohms-3 | TOP=L2:L3=L2/L4:L6=L5/L7:BOTTOM=L7 |
| I2C_B_TMP1_A2 | 50OHM_Y12MIL | BUS | 7 | 6 | 5 | 10 | 5 | 14 | 6 | 15 | 12 | 12 | 12 | 12 |  | 50 Ohms-3 | TOP=L2:L3=L2/L4:L6=L5/L7:BOTTOM=L7 |
| I2C_B_TMP1_A2 | 50OHM_Y12MIL | BUS | 8 | 6.75 | 5 | 10 | 5 | 14 | 6 | 15 | 12 | 12 | 12 | 12 |  | 50 Ohms-3 | TOP=L2:L3=L2/L4:L6=L5/L7:BOTTOM=L7 |
| I2C_B_TMP1_ALERT | 50OHM_Y12MIL | BUS | 1 | 6.75 | 5 | 10 | 5 | 14 | 6 | 15 | 12 | 12 | 12 | 12 |  | 50 Ohms-3 | TOP=L2:L3=L2/L4:L6=L5/L7:BOTTOM=L7 |
| I2C_B_TMP1_ALERT | 50OHM_Y12MIL | BUS | 2 | 6 | 5 | 10 | 5 | 14 | 6 | 15 | 12 | 12 | 12 | 12 |  | 50 Ohms-3 | TOP=L2:L3=L2/L4:L6=L5/L7:BOTTOM=L7 |
| I2C_B_TMP1_ALERT | 50OHM_Y12MIL | BUS | 3 | 6 | 5 | 10 | 5 | 14 | 6 | 15 | 12 | 12 | 12 | 12 |  | 50 Ohms-3 | TOP=L2:L3=L2/L4:L6=L5/L7:BOTTOM=L7 |
| I2C_B_TMP1_ALERT | 50OHM_Y12MIL | BUS | 4 | 6 | 5 | 10 | 5 | 14 | 6 | 15 | 12 | 12 | 12 | 12 |  | 50 Ohms-3 | TOP=L2:L3=L2/L4:L6=L5/L7:BOTTOM=L7 |
| I2C_B_TMP1_ALERT | 50OHM_Y12MIL | BUS | 5 | 6 | 5 | 10 | 5 | 14 | 6 | 15 | 12 | 12 | 12 | 12 |  | 50 Ohms-3 | TOP=L2:L3=L2/L4:L6=L5/L7:BOTTOM=L7 |
| I2C_B_TMP1_ALERT | 50OHM_Y12MIL | BUS | 6 | 6 | 5 | 10 | 5 | 14 | 6 | 15 | 12 | 12 | 12 | 12 |  | 50 Ohms-3 | TOP=L2:L3=L2/L4:L6=L5/L7:BOTTOM=L7 |
| I2C_B_TMP1_ALERT | 50OHM_Y12MIL | BUS | 7 | 6 | 5 | 10 | 5 | 14 | 6 | 15 | 12 | 12 | 12 | 12 |  | 50 Ohms-3 | TOP=L2:L3=L2/L4:L6=L5/L7:BOTTOM=L7 |
| I2C_B_TMP1_ALERT | 50OHM_Y12MIL | BUS | 8 | 6.75 | 5 | 10 | 5 | 14 | 6 | 15 | 12 | 12 | 12 | 12 |  | 50 Ohms-3 | TOP=L2:L3=L2/L4:L6=L5/L7:BOTTOM=L7 |
| I2C_B_TMP2_A0 | 50OHM_Y12MIL | BUS | 1 | 6.75 | 5 | 10 | 5 | 14 | 6 | 15 | 12 | 12 | 12 | 12 |  | 50 Ohms-3 | TOP=L2:L3=L2/L4:L6=L5/L7:BOTTOM=L7 |
| I2C_B_TMP2_A0 | 50OHM_Y12MIL | BUS | 2 | 6 | 5 | 10 | 5 | 14 | 6 | 15 | 12 | 12 | 12 | 12 |  | 50 Ohms-3 | TOP=L2:L3=L2/L4:L6=L5/L7:BOTTOM=L7 |
| I2C_B_TMP2_A0 | 50OHM_Y12MIL | BUS | 3 | 6 | 5 | 10 | 5 | 14 | 6 | 15 | 12 | 12 | 12 | 12 |  | 50 Ohms-3 | TOP=L2:L3=L2/L4:L6=L5/L7:BOTTOM=L7 |
| I2C_B_TMP2_A0 | 50OHM_Y12MIL | BUS | 4 | 6 | 5 | 10 | 5 | 14 | 6 | 15 | 12 | 12 | 12 | 12 |  | 50 Ohms-3 | TOP=L2:L3=L2/L4:L6=L5/L7:BOTTOM=L7 |
| I2C_B_TMP2_A0 | 50OHM_Y12MIL | BUS | 5 | 6 | 5 | 10 | 5 | 14 | 6 | 15 | 12 | 12 | 12 | 12 |  | 50 Ohms-3 | TOP=L2:L3=L2/L4:L6=L5/L7:BOTTOM=L7 |
| I2C_B_TMP2_A0 | 50OHM_Y12MIL | BUS | 6 | 6 | 5 | 10 | 5 | 14 | 6 | 15 | 12 | 12 | 12 | 12 |  | 50 Ohms-3 | TOP=L2:L3=L2/L4:L6=L5/L7:BOTTOM=L7 |
| I2C_B_TMP2_A0 | 50OHM_Y12MIL | BUS | 7 | 6 | 5 | 10 | 5 | 14 | 6 | 15 | 12 | 12 | 12 | 12 |  | 50 Ohms-3 | TOP=L2:L3=L2/L4:L6=L5/L7:BOTTOM=L7 |
| I2C_B_TMP2_A0 | 50OHM_Y12MIL | BUS | 8 | 6.75 | 5 | 10 | 5 | 14 | 6 | 15 | 12 | 12 | 12 | 12 |  | 50 Ohms-3 | TOP=L2:L3=L2/L4:L6=L5/L7:BOTTOM=L7 |
| I2C_B_TMP2_A1 | 50OHM_Y12MIL | BUS | 1 | 6.75 | 5 | 10 | 5 | 14 | 6 | 15 | 12 | 12 | 12 | 12 |  | 50 Ohms-3 | TOP=L2:L3=L2/L4:L6=L5/L7:BOTTOM=L7 |
| I2C_B_TMP2_A1 | 50OHM_Y12MIL | BUS | 2 | 6 | 5 | 10 | 5 | 14 | 6 | 15 | 12 | 12 | 12 | 12 |  | 50 Ohms-3 | TOP=L2:L3=L2/L4:L6=L5/L7:BOTTOM=L7 |
| I2C_B_TMP2_A1 | 50OHM_Y12MIL | BUS | 3 | 6 | 5 | 10 | 5 | 14 | 6 | 15 | 12 | 12 | 12 | 12 |  | 50 Ohms-3 | TOP=L2:L3=L2/L4:L6=L5/L7:BOTTOM=L7 |
| I2C_B_TMP2_A1 | 50OHM_Y12MIL | BUS | 4 | 6 | 5 | 10 | 5 | 14 | 6 | 15 | 12 | 12 | 12 | 12 |  | 50 Ohms-3 | TOP=L2:L3=L2/L4:L6=L5/L7:BOTTOM=L7 |
| I2C_B_TMP2_A1 | 50OHM_Y12MIL | BUS | 5 | 6 | 5 | 10 | 5 | 14 | 6 | 15 | 12 | 12 | 12 | 12 |  | 50 Ohms-3 | TOP=L2:L3=L2/L4:L6=L5/L7:BOTTOM=L7 |
| I2C_B_TMP2_A1 | 50OHM_Y12MIL | BUS | 6 | 6 | 5 | 10 | 5 | 14 | 6 | 15 | 12 | 12 | 12 | 12 |  | 50 Ohms-3 | TOP=L2:L3=L2/L4:L6=L5/L7:BOTTOM=L7 |
| I2C_B_TMP2_A1 | 50OHM_Y12MIL | BUS | 7 | 6 | 5 | 10 | 5 | 14 | 6 | 15 | 12 | 12 | 12 | 12 |  | 50 Ohms-3 | TOP=L2:L3=L2/L4:L6=L5/L7:BOTTOM=L7 |
| I2C_B_TMP2_A1 | 50OHM_Y12MIL | BUS | 8 | 6.75 | 5 | 10 | 5 | 14 | 6 | 15 | 12 | 12 | 12 | 12 |  | 50 Ohms-3 | TOP=L2:L3=L2/L4:L6=L5/L7:BOTTOM=L7 |
| I2C_B_TMP2_A2 | 50OHM_Y12MIL | BUS | 1 | 6.75 | 5 | 10 | 5 | 14 | 6 | 15 | 12 | 12 | 12 | 12 |  | 50 Ohms-3 | TOP=L2:L3=L2/L4:L6=L5/L7:BOTTOM=L7 |
| I2C_B_TMP2_A2 | 50OHM_Y12MIL | BUS | 2 | 6 | 5 | 10 | 5 | 14 | 6 | 15 | 12 | 12 | 12 | 12 |  | 50 Ohms-3 | TOP=L2:L3=L2/L4:L6=L5/L7:BOTTOM=L7 |
| I2C_B_TMP2_A2 | 50OHM_Y12MIL | BUS | 3 | 6 | 5 | 10 | 5 | 14 | 6 | 15 | 12 | 12 | 12 | 12 |  | 50 Ohms-3 | TOP=L2:L3=L2/L4:L6=L5/L7:BOTTOM=L7 |
| I2C_B_TMP2_A2 | 50OHM_Y12MIL | BUS | 4 | 6 | 5 | 10 | 5 | 14 | 6 | 15 | 12 | 12 | 12 | 12 |  | 50 Ohms-3 | TOP=L2:L3=L2/L4:L6=L5/L7:BOTTOM=L7 |
| I2C_B_TMP2_A2 | 50OHM_Y12MIL | BUS | 5 | 6 | 5 | 10 | 5 | 14 | 6 | 15 | 12 | 12 | 12 | 12 |  | 50 Ohms-3 | TOP=L2:L3=L2/L4:L6=L5/L7:BOTTOM=L7 |
| I2C_B_TMP2_A2 | 50OHM_Y12MIL | BUS | 6 | 6 | 5 | 10 | 5 | 14 | 6 | 15 | 12 | 12 | 12 | 12 |  | 50 Ohms-3 | TOP=L2:L3=L2/L4:L6=L5/L7:BOTTOM=L7 |
| I2C_B_TMP2_A2 | 50OHM_Y12MIL | BUS | 7 | 6 | 5 | 10 | 5 | 14 | 6 | 15 | 12 | 12 | 12 | 12 |  | 50 Ohms-3 | TOP=L2:L3=L2/L4:L6=L5/L7:BOTTOM=L7 |
| I2C_B_TMP2_A2 | 50OHM_Y12MIL | BUS | 8 | 6.75 | 5 | 10 | 5 | 14 | 6 | 15 | 12 | 12 | 12 | 12 |  | 50 Ohms-3 | TOP=L2:L3=L2/L4:L6=L5/L7:BOTTOM=L7 |
| I2C_B_TMP2_ALERT | 50OHM_Y12MIL | BUS | 1 | 6.75 | 5 | 10 | 5 | 14 | 6 | 15 | 12 | 12 | 12 | 12 |  | 50 Ohms-3 | TOP=L2:L3=L2/L4:L6=L5/L7:BOTTOM=L7 |
| I2C_B_TMP2_ALERT | 50OHM_Y12MIL | BUS | 2 | 6 | 5 | 10 | 5 | 14 | 6 | 15 | 12 | 12 | 12 | 12 |  | 50 Ohms-3 | TOP=L2:L3=L2/L4:L6=L5/L7:BOTTOM=L7 |
| I2C_B_TMP2_ALERT | 50OHM_Y12MIL | BUS | 3 | 6 | 5 | 10 | 5 | 14 | 6 | 15 | 12 | 12 | 12 | 12 |  | 50 Ohms-3 | TOP=L2:L3=L2/L4:L6=L5/L7:BOTTOM=L7 |
| I2C_B_TMP2_ALERT | 50OHM_Y12MIL | BUS | 4 | 6 | 5 | 10 | 5 | 14 | 6 | 15 | 12 | 12 | 12 | 12 |  | 50 Ohms-3 | TOP=L2:L3=L2/L4:L6=L5/L7:BOTTOM=L7 |
| I2C_B_TMP2_ALERT | 50OHM_Y12MIL | BUS | 5 | 6 | 5 | 10 | 5 | 14 | 6 | 15 | 12 | 12 | 12 | 12 |  | 50 Ohms-3 | TOP=L2:L3=L2/L4:L6=L5/L7:BOTTOM=L7 |
| I2C_B_TMP2_ALERT | 50OHM_Y12MIL | BUS | 6 | 6 | 5 | 10 | 5 | 14 | 6 | 15 | 12 | 12 | 12 | 12 |  | 50 Ohms-3 | TOP=L2:L3=L2/L4:L6=L5/L7:BOTTOM=L7 |
| I2C_B_TMP2_ALERT | 50OHM_Y12MIL | BUS | 7 | 6 | 5 | 10 | 5 | 14 | 6 | 15 | 12 | 12 | 12 | 12 |  | 50 Ohms-3 | TOP=L2:L3=L2/L4:L6=L5/L7:BOTTOM=L7 |
| I2C_B_TMP2_ALERT | 50OHM_Y12MIL | BUS | 8 | 6.75 | 5 | 10 | 5 | 14 | 6 | 15 | 12 | 12 | 12 | 12 |  | 50 Ohms-3 | TOP=L2:L3=L2/L4:L6=L5/L7:BOTTOM=L7 |
| I2C_B_TMP3_A0 | 50OHM_Y12MIL | BUS | 1 | 6.75 | 5 | 10 | 5 | 14 | 6 | 15 | 12 | 12 | 12 | 12 |  | 50 Ohms-3 | TOP=L2:L3=L2/L4:L6=L5/L7:BOTTOM=L7 |
| I2C_B_TMP3_A0 | 50OHM_Y12MIL | BUS | 2 | 6 | 5 | 10 | 5 | 14 | 6 | 15 | 12 | 12 | 12 | 12 |  | 50 Ohms-3 | TOP=L2:L3=L2/L4:L6=L5/L7:BOTTOM=L7 |
| I2C_B_TMP3_A0 | 50OHM_Y12MIL | BUS | 3 | 6 | 5 | 10 | 5 | 14 | 6 | 15 | 12 | 12 | 12 | 12 |  | 50 Ohms-3 | TOP=L2:L3=L2/L4:L6=L5/L7:BOTTOM=L7 |
| I2C_B_TMP3_A0 | 50OHM_Y12MIL | BUS | 4 | 6 | 5 | 10 | 5 | 14 | 6 | 15 | 12 | 12 | 12 | 12 |  | 50 Ohms-3 | TOP=L2:L3=L2/L4:L6=L5/L7:BOTTOM=L7 |
| I2C_B_TMP3_A0 | 50OHM_Y12MIL | BUS | 5 | 6 | 5 | 10 | 5 | 14 | 6 | 15 | 12 | 12 | 12 | 12 |  | 50 Ohms-3 | TOP=L2:L3=L2/L4:L6=L5/L7:BOTTOM=L7 |
| I2C_B_TMP3_A0 | 50OHM_Y12MIL | BUS | 6 | 6 | 5 | 10 | 5 | 14 | 6 | 15 | 12 | 12 | 12 | 12 |  | 50 Ohms-3 | TOP=L2:L3=L2/L4:L6=L5/L7:BOTTOM=L7 |
| I2C_B_TMP3_A0 | 50OHM_Y12MIL | BUS | 7 | 6 | 5 | 10 | 5 | 14 | 6 | 15 | 12 | 12 | 12 | 12 |  | 50 Ohms-3 | TOP=L2:L3=L2/L4:L6=L5/L7:BOTTOM=L7 |
| I2C_B_TMP3_A0 | 50OHM_Y12MIL | BUS | 8 | 6.75 | 5 | 10 | 5 | 14 | 6 | 15 | 12 | 12 | 12 | 12 |  | 50 Ohms-3 | TOP=L2:L3=L2/L4:L6=L5/L7:BOTTOM=L7 |
| I2C_B_TMP3_A1 | 50OHM_Y12MIL | BUS | 1 | 6.75 | 5 | 10 | 5 | 14 | 6 | 15 | 12 | 12 | 12 | 12 |  | 50 Ohms-3 | TOP=L2:L3=L2/L4:L6=L5/L7:BOTTOM=L7 |
| I2C_B_TMP3_A1 | 50OHM_Y12MIL | BUS | 2 | 6 | 5 | 10 | 5 | 14 | 6 | 15 | 12 | 12 | 12 | 12 |  | 50 Ohms-3 | TOP=L2:L3=L2/L4:L6=L5/L7:BOTTOM=L7 |
| I2C_B_TMP3_A1 | 50OHM_Y12MIL | BUS | 3 | 6 | 5 | 10 | 5 | 14 | 6 | 15 | 12 | 12 | 12 | 12 |  | 50 Ohms-3 | TOP=L2:L3=L2/L4:L6=L5/L7:BOTTOM=L7 |
| I2C_B_TMP3_A1 | 50OHM_Y12MIL | BUS | 4 | 6 | 5 | 10 | 5 | 14 | 6 | 15 | 12 | 12 | 12 | 12 |  | 50 Ohms-3 | TOP=L2:L3=L2/L4:L6=L5/L7:BOTTOM=L7 |
| I2C_B_TMP3_A1 | 50OHM_Y12MIL | BUS | 5 | 6 | 5 | 10 | 5 | 14 | 6 | 15 | 12 | 12 | 12 | 12 |  | 50 Ohms-3 | TOP=L2:L3=L2/L4:L6=L5/L7:BOTTOM=L7 |
| I2C_B_TMP3_A1 | 50OHM_Y12MIL | BUS | 6 | 6 | 5 | 10 | 5 | 14 | 6 | 15 | 12 | 12 | 12 | 12 |  | 50 Ohms-3 | TOP=L2:L3=L2/L4:L6=L5/L7:BOTTOM=L7 |
| I2C_B_TMP3_A1 | 50OHM_Y12MIL | BUS | 7 | 6 | 5 | 10 | 5 | 14 | 6 | 15 | 12 | 12 | 12 | 12 |  | 50 Ohms-3 | TOP=L2:L3=L2/L4:L6=L5/L7:BOTTOM=L7 |
| I2C_B_TMP3_A1 | 50OHM_Y12MIL | BUS | 8 | 6.75 | 5 | 10 | 5 | 14 | 6 | 15 | 12 | 12 | 12 | 12 |  | 50 Ohms-3 | TOP=L2:L3=L2/L4:L6=L5/L7:BOTTOM=L7 |
| I2C_B_TMP3_A2 | 50OHM_Y12MIL | BUS | 1 | 6.75 | 5 | 10 | 5 | 14 | 6 | 15 | 12 | 12 | 12 | 12 |  | 50 Ohms-3 | TOP=L2:L3=L2/L4:L6=L5/L7:BOTTOM=L7 |
| I2C_B_TMP3_A2 | 50OHM_Y12MIL | BUS | 2 | 6 | 5 | 10 | 5 | 14 | 6 | 15 | 12 | 12 | 12 | 12 |  | 50 Ohms-3 | TOP=L2:L3=L2/L4:L6=L5/L7:BOTTOM=L7 |
| I2C_B_TMP3_A2 | 50OHM_Y12MIL | BUS | 3 | 6 | 5 | 10 | 5 | 14 | 6 | 15 | 12 | 12 | 12 | 12 |  | 50 Ohms-3 | TOP=L2:L3=L2/L4:L6=L5/L7:BOTTOM=L7 |
| I2C_B_TMP3_A2 | 50OHM_Y12MIL | BUS | 4 | 6 | 5 | 10 | 5 | 14 | 6 | 15 | 12 | 12 | 12 | 12 |  | 50 Ohms-3 | TOP=L2:L3=L2/L4:L6=L5/L7:BOTTOM=L7 |
| I2C_B_TMP3_A2 | 50OHM_Y12MIL | BUS | 5 | 6 | 5 | 10 | 5 | 14 | 6 | 15 | 12 | 12 | 12 | 12 |  | 50 Ohms-3 | TOP=L2:L3=L2/L4:L6=L5/L7:BOTTOM=L7 |
| I2C_B_TMP3_A2 | 50OHM_Y12MIL | BUS | 6 | 6 | 5 | 10 | 5 | 14 | 6 | 15 | 12 | 12 | 12 | 12 |  | 50 Ohms-3 | TOP=L2:L3=L2/L4:L6=L5/L7:BOTTOM=L7 |
| I2C_B_TMP3_A2 | 50OHM_Y12MIL | BUS | 7 | 6 | 5 | 10 | 5 | 14 | 6 | 15 | 12 | 12 | 12 | 12 |  | 50 Ohms-3 | TOP=L2:L3=L2/L4:L6=L5/L7:BOTTOM=L7 |
| I2C_B_TMP3_A2 | 50OHM_Y12MIL | BUS | 8 | 6.75 | 5 | 10 | 5 | 14 | 6 | 15 | 12 | 12 | 12 | 12 |  | 50 Ohms-3 | TOP=L2:L3=L2/L4:L6=L5/L7:BOTTOM=L7 |
| I2C_B_TMP3_ALERT | 50OHM_Y12MIL | BUS | 1 | 6.75 | 5 | 10 | 5 | 14 | 6 | 15 | 12 | 12 | 12 | 12 |  | 50 Ohms-3 | TOP=L2:L3=L2/L4:L6=L5/L7:BOTTOM=L7 |
| I2C_B_TMP3_ALERT | 50OHM_Y12MIL | BUS | 2 | 6 | 5 | 10 | 5 | 14 | 6 | 15 | 12 | 12 | 12 | 12 |  | 50 Ohms-3 | TOP=L2:L3=L2/L4:L6=L5/L7:BOTTOM=L7 |
| I2C_B_TMP3_ALERT | 50OHM_Y12MIL | BUS | 3 | 6 | 5 | 10 | 5 | 14 | 6 | 15 | 12 | 12 | 12 | 12 |  | 50 Ohms-3 | TOP=L2:L3=L2/L4:L6=L5/L7:BOTTOM=L7 |
| I2C_B_TMP3_ALERT | 50OHM_Y12MIL | BUS | 4 | 6 | 5 | 10 | 5 | 14 | 6 | 15 | 12 | 12 | 12 | 12 |  | 50 Ohms-3 | TOP=L2:L3=L2/L4:L6=L5/L7:BOTTOM=L7 |
| I2C_B_TMP3_ALERT | 50OHM_Y12MIL | BUS | 5 | 6 | 5 | 10 | 5 | 14 | 6 | 15 | 12 | 12 | 12 | 12 |  | 50 Ohms-3 | TOP=L2:L3=L2/L4:L6=L5/L7:BOTTOM=L7 |
| I2C_B_TMP3_ALERT | 50OHM_Y12MIL | BUS | 6 | 6 | 5 | 10 | 5 | 14 | 6 | 15 | 12 | 12 | 12 | 12 |  | 50 Ohms-3 | TOP=L2:L3=L2/L4:L6=L5/L7:BOTTOM=L7 |
| I2C_B_TMP3_ALERT | 50OHM_Y12MIL | BUS | 7 | 6 | 5 | 10 | 5 | 14 | 6 | 15 | 12 | 12 | 12 | 12 |  | 50 Ohms-3 | TOP=L2:L3=L2/L4:L6=L5/L7:BOTTOM=L7 |
| I2C_B_TMP3_ALERT | 50OHM_Y12MIL | BUS | 8 | 6.75 | 5 | 10 | 5 | 14 | 6 | 15 | 12 | 12 | 12 | 12 |  | 50 Ohms-3 | TOP=L2:L3=L2/L4:L6=L5/L7:BOTTOM=L7 |
| I2C_B_TMP4_A0 | 50OHM_Y12MIL | BUS | 1 | 6.75 | 5 | 10 | 5 | 14 | 6 | 15 | 12 | 12 | 12 | 12 |  | 50 Ohms-3 | TOP=L2:L3=L2/L4:L6=L5/L7:BOTTOM=L7 |
| I2C_B_TMP4_A0 | 50OHM_Y12MIL | BUS | 2 | 6 | 5 | 10 | 5 | 14 | 6 | 15 | 12 | 12 | 12 | 12 |  | 50 Ohms-3 | TOP=L2:L3=L2/L4:L6=L5/L7:BOTTOM=L7 |
| I2C_B_TMP4_A0 | 50OHM_Y12MIL | BUS | 3 | 6 | 5 | 10 | 5 | 14 | 6 | 15 | 12 | 12 | 12 | 12 |  | 50 Ohms-3 | TOP=L2:L3=L2/L4:L6=L5/L7:BOTTOM=L7 |
| I2C_B_TMP4_A0 | 50OHM_Y12MIL | BUS | 4 | 6 | 5 | 10 | 5 | 14 | 6 | 15 | 12 | 12 | 12 | 12 |  | 50 Ohms-3 | TOP=L2:L3=L2/L4:L6=L5/L7:BOTTOM=L7 |
| I2C_B_TMP4_A0 | 50OHM_Y12MIL | BUS | 5 | 6 | 5 | 10 | 5 | 14 | 6 | 15 | 12 | 12 | 12 | 12 |  | 50 Ohms-3 | TOP=L2:L3=L2/L4:L6=L5/L7:BOTTOM=L7 |
| I2C_B_TMP4_A0 | 50OHM_Y12MIL | BUS | 6 | 6 | 5 | 10 | 5 | 14 | 6 | 15 | 12 | 12 | 12 | 12 |  | 50 Ohms-3 | TOP=L2:L3=L2/L4:L6=L5/L7:BOTTOM=L7 |
| I2C_B_TMP4_A0 | 50OHM_Y12MIL | BUS | 7 | 6 | 5 | 10 | 5 | 14 | 6 | 15 | 12 | 12 | 12 | 12 |  | 50 Ohms-3 | TOP=L2:L3=L2/L4:L6=L5/L7:BOTTOM=L7 |
| I2C_B_TMP4_A0 | 50OHM_Y12MIL | BUS | 8 | 6.75 | 5 | 10 | 5 | 14 | 6 | 15 | 12 | 12 | 12 | 12 |  | 50 Ohms-3 | TOP=L2:L3=L2/L4:L6=L5/L7:BOTTOM=L7 |
| I2C_B_TMP4_A1 | 50OHM_Y12MIL | BUS | 1 | 6.75 | 5 | 10 | 5 | 14 | 6 | 15 | 12 | 12 | 12 | 12 |  | 50 Ohms-3 | TOP=L2:L3=L2/L4:L6=L5/L7:BOTTOM=L7 |
| I2C_B_TMP4_A1 | 50OHM_Y12MIL | BUS | 2 | 6 | 5 | 10 | 5 | 14 | 6 | 15 | 12 | 12 | 12 | 12 |  | 50 Ohms-3 | TOP=L2:L3=L2/L4:L6=L5/L7:BOTTOM=L7 |
| I2C_B_TMP4_A1 | 50OHM_Y12MIL | BUS | 3 | 6 | 5 | 10 | 5 | 14 | 6 | 15 | 12 | 12 | 12 | 12 |  | 50 Ohms-3 | TOP=L2:L3=L2/L4:L6=L5/L7:BOTTOM=L7 |
| I2C_B_TMP4_A1 | 50OHM_Y12MIL | BUS | 4 | 6 | 5 | 10 | 5 | 14 | 6 | 15 | 12 | 12 | 12 | 12 |  | 50 Ohms-3 | TOP=L2:L3=L2/L4:L6=L5/L7:BOTTOM=L7 |
| I2C_B_TMP4_A1 | 50OHM_Y12MIL | BUS | 5 | 6 | 5 | 10 | 5 | 14 | 6 | 15 | 12 | 12 | 12 | 12 |  | 50 Ohms-3 | TOP=L2:L3=L2/L4:L6=L5/L7:BOTTOM=L7 |
| I2C_B_TMP4_A1 | 50OHM_Y12MIL | BUS | 6 | 6 | 5 | 10 | 5 | 14 | 6 | 15 | 12 | 12 | 12 | 12 |  | 50 Ohms-3 | TOP=L2:L3=L2/L4:L6=L5/L7:BOTTOM=L7 |
| I2C_B_TMP4_A1 | 50OHM_Y12MIL | BUS | 7 | 6 | 5 | 10 | 5 | 14 | 6 | 15 | 12 | 12 | 12 | 12 |  | 50 Ohms-3 | TOP=L2:L3=L2/L4:L6=L5/L7:BOTTOM=L7 |
| I2C_B_TMP4_A1 | 50OHM_Y12MIL | BUS | 8 | 6.75 | 5 | 10 | 5 | 14 | 6 | 15 | 12 | 12 | 12 | 12 |  | 50 Ohms-3 | TOP=L2:L3=L2/L4:L6=L5/L7:BOTTOM=L7 |
| I2C_B_TMP4_A2 | 50OHM_Y12MIL | BUS | 1 | 6.75 | 5 | 10 | 5 | 14 | 6 | 15 | 12 | 12 | 12 | 12 |  | 50 Ohms-3 | TOP=L2:L3=L2/L4:L6=L5/L7:BOTTOM=L7 |
| I2C_B_TMP4_A2 | 50OHM_Y12MIL | BUS | 2 | 6 | 5 | 10 | 5 | 14 | 6 | 15 | 12 | 12 | 12 | 12 |  | 50 Ohms-3 | TOP=L2:L3=L2/L4:L6=L5/L7:BOTTOM=L7 |
| I2C_B_TMP4_A2 | 50OHM_Y12MIL | BUS | 3 | 6 | 5 | 10 | 5 | 14 | 6 | 15 | 12 | 12 | 12 | 12 |  | 50 Ohms-3 | TOP=L2:L3=L2/L4:L6=L5/L7:BOTTOM=L7 |
| I2C_B_TMP4_A2 | 50OHM_Y12MIL | BUS | 4 | 6 | 5 | 10 | 5 | 14 | 6 | 15 | 12 | 12 | 12 | 12 |  | 50 Ohms-3 | TOP=L2:L3=L2/L4:L6=L5/L7:BOTTOM=L7 |
| I2C_B_TMP4_A2 | 50OHM_Y12MIL | BUS | 5 | 6 | 5 | 10 | 5 | 14 | 6 | 15 | 12 | 12 | 12 | 12 |  | 50 Ohms-3 | TOP=L2:L3=L2/L4:L6=L5/L7:BOTTOM=L7 |
| I2C_B_TMP4_A2 | 50OHM_Y12MIL | BUS | 6 | 6 | 5 | 10 | 5 | 14 | 6 | 15 | 12 | 12 | 12 | 12 |  | 50 Ohms-3 | TOP=L2:L3=L2/L4:L6=L5/L7:BOTTOM=L7 |
| I2C_B_TMP4_A2 | 50OHM_Y12MIL | BUS | 7 | 6 | 5 | 10 | 5 | 14 | 6 | 15 | 12 | 12 | 12 | 12 |  | 50 Ohms-3 | TOP=L2:L3=L2/L4:L6=L5/L7:BOTTOM=L7 |
| I2C_B_TMP4_A2 | 50OHM_Y12MIL | BUS | 8 | 6.75 | 5 | 10 | 5 | 14 | 6 | 15 | 12 | 12 | 12 | 12 |  | 50 Ohms-3 | TOP=L2:L3=L2/L4:L6=L5/L7:BOTTOM=L7 |
| I2C_B_TMP4_ALERT | 50OHM_Y12MIL | BUS | 1 | 6.75 | 5 | 10 | 5 | 14 | 6 | 15 | 12 | 12 | 12 | 12 |  | 50 Ohms-3 | TOP=L2:L3=L2/L4:L6=L5/L7:BOTTOM=L7 |
| I2C_B_TMP4_ALERT | 50OHM_Y12MIL | BUS | 2 | 6 | 5 | 10 | 5 | 14 | 6 | 15 | 12 | 12 | 12 | 12 |  | 50 Ohms-3 | TOP=L2:L3=L2/L4:L6=L5/L7:BOTTOM=L7 |
| I2C_B_TMP4_ALERT | 50OHM_Y12MIL | BUS | 3 | 6 | 5 | 10 | 5 | 14 | 6 | 15 | 12 | 12 | 12 | 12 |  | 50 Ohms-3 | TOP=L2:L3=L2/L4:L6=L5/L7:BOTTOM=L7 |
| I2C_B_TMP4_ALERT | 50OHM_Y12MIL | BUS | 4 | 6 | 5 | 10 | 5 | 14 | 6 | 15 | 12 | 12 | 12 | 12 |  | 50 Ohms-3 | TOP=L2:L3=L2/L4:L6=L5/L7:BOTTOM=L7 |
| I2C_B_TMP4_ALERT | 50OHM_Y12MIL | BUS | 5 | 6 | 5 | 10 | 5 | 14 | 6 | 15 | 12 | 12 | 12 | 12 |  | 50 Ohms-3 | TOP=L2:L3=L2/L4:L6=L5/L7:BOTTOM=L7 |
| I2C_B_TMP4_ALERT | 50OHM_Y12MIL | BUS | 6 | 6 | 5 | 10 | 5 | 14 | 6 | 15 | 12 | 12 | 12 | 12 |  | 50 Ohms-3 | TOP=L2:L3=L2/L4:L6=L5/L7:BOTTOM=L7 |
| I2C_B_TMP4_ALERT | 50OHM_Y12MIL | BUS | 7 | 6 | 5 | 10 | 5 | 14 | 6 | 15 | 12 | 12 | 12 | 12 |  | 50 Ohms-3 | TOP=L2:L3=L2/L4:L6=L5/L7:BOTTOM=L7 |
| I2C_B_TMP4_ALERT | 50OHM_Y12MIL | BUS | 8 | 6.75 | 5 | 10 | 5 | 14 | 6 | 15 | 12 | 12 | 12 | 12 |  | 50 Ohms-3 | TOP=L2:L3=L2/L4:L6=L5/L7:BOTTOM=L7 |
| I2C_MUX_RESET | 50OHM_Y12MIL | BUS | 1 | 6.75 | 5 | 10 | 5 | 14 | 6 | 15 | 12 | 12 | 12 | 12 |  | 50 Ohms-3 | TOP=L2:L3=L2/L4:L6=L5/L7:BOTTOM=L7 |
| I2C_MUX_RESET | 50OHM_Y12MIL | BUS | 2 | 6 | 5 | 10 | 5 | 14 | 6 | 15 | 12 | 12 | 12 | 12 |  | 50 Ohms-3 | TOP=L2:L3=L2/L4:L6=L5/L7:BOTTOM=L7 |
| I2C_MUX_RESET | 50OHM_Y12MIL | BUS | 3 | 6 | 5 | 10 | 5 | 14 | 6 | 15 | 12 | 12 | 12 | 12 |  | 50 Ohms-3 | TOP=L2:L3=L2/L4:L6=L5/L7:BOTTOM=L7 |
| I2C_MUX_RESET | 50OHM_Y12MIL | BUS | 4 | 6 | 5 | 10 | 5 | 14 | 6 | 15 | 12 | 12 | 12 | 12 |  | 50 Ohms-3 | TOP=L2:L3=L2/L4:L6=L5/L7:BOTTOM=L7 |
| I2C_MUX_RESET | 50OHM_Y12MIL | BUS | 5 | 6 | 5 | 10 | 5 | 14 | 6 | 15 | 12 | 12 | 12 | 12 |  | 50 Ohms-3 | TOP=L2:L3=L2/L4:L6=L5/L7:BOTTOM=L7 |
| I2C_MUX_RESET | 50OHM_Y12MIL | BUS | 6 | 6 | 5 | 10 | 5 | 14 | 6 | 15 | 12 | 12 | 12 | 12 |  | 50 Ohms-3 | TOP=L2:L3=L2/L4:L6=L5/L7:BOTTOM=L7 |
| I2C_MUX_RESET | 50OHM_Y12MIL | BUS | 7 | 6 | 5 | 10 | 5 | 14 | 6 | 15 | 12 | 12 | 12 | 12 |  | 50 Ohms-3 | TOP=L2:L3=L2/L4:L6=L5/L7:BOTTOM=L7 |
| I2C_MUX_RESET | 50OHM_Y12MIL | BUS | 8 | 6.75 | 5 | 10 | 5 | 14 | 6 | 15 | 12 | 12 | 12 | 12 |  | 50 Ohms-3 | TOP=L2:L3=L2/L4:L6=L5/L7:BOTTOM=L7 |
| I2C_MUX_RESET_PEB | 50OHM_Y12MIL | BUS | 1 | 6.75 | 5 | 10 | 5 | 14 | 6 | 15 | 12 | 12 | 12 | 12 |  | 50 Ohms-3 | TOP=L2:L3=L2/L4:L6=L5/L7:BOTTOM=L7 |
| I2C_MUX_RESET_PEB | 50OHM_Y12MIL | BUS | 2 | 6 | 5 | 10 | 5 | 14 | 6 | 15 | 12 | 12 | 12 | 12 |  | 50 Ohms-3 | TOP=L2:L3=L2/L4:L6=L5/L7:BOTTOM=L7 |
| I2C_MUX_RESET_PEB | 50OHM_Y12MIL | BUS | 3 | 6 | 5 | 10 | 5 | 14 | 6 | 15 | 12 | 12 | 12 | 12 |  | 50 Ohms-3 | TOP=L2:L3=L2/L4:L6=L5/L7:BOTTOM=L7 |
| I2C_MUX_RESET_PEB | 50OHM_Y12MIL | BUS | 4 | 6 | 5 | 10 | 5 | 14 | 6 | 15 | 12 | 12 | 12 | 12 |  | 50 Ohms-3 | TOP=L2:L3=L2/L4:L6=L5/L7:BOTTOM=L7 |
| I2C_MUX_RESET_PEB | 50OHM_Y12MIL | BUS | 5 | 6 | 5 | 10 | 5 | 14 | 6 | 15 | 12 | 12 | 12 | 12 |  | 50 Ohms-3 | TOP=L2:L3=L2/L4:L6=L5/L7:BOTTOM=L7 |
| I2C_MUX_RESET_PEB | 50OHM_Y12MIL | BUS | 6 | 6 | 5 | 10 | 5 | 14 | 6 | 15 | 12 | 12 | 12 | 12 |  | 50 Ohms-3 | TOP=L2:L3=L2/L4:L6=L5/L7:BOTTOM=L7 |
| I2C_MUX_RESET_PEB | 50OHM_Y12MIL | BUS | 7 | 6 | 5 | 10 | 5 | 14 | 6 | 15 | 12 | 12 | 12 | 12 |  | 50 Ohms-3 | TOP=L2:L3=L2/L4:L6=L5/L7:BOTTOM=L7 |
| I2C_MUX_RESET_PEB | 50OHM_Y12MIL | BUS | 8 | 6.75 | 5 | 10 | 5 | 14 | 6 | 15 | 12 | 12 | 12 | 12 |  | 50 Ohms-3 | TOP=L2:L3=L2/L4:L6=L5/L7:BOTTOM=L7 |
| I2C_MUX_RESET_R_EU16 | 50OHM_Y12MIL | BUS | 1 | 6.75 | 5 | 10 | 5 | 14 | 6 | 15 | 12 | 12 | 12 | 12 |  | 50 Ohms-3 | TOP=L2:L3=L2/L4:L6=L5/L7:BOTTOM=L7 |
| I2C_MUX_RESET_R_EU16 | 50OHM_Y12MIL | BUS | 2 | 6 | 5 | 10 | 5 | 14 | 6 | 15 | 12 | 12 | 12 | 12 |  | 50 Ohms-3 | TOP=L2:L3=L2/L4:L6=L5/L7:BOTTOM=L7 |
| I2C_MUX_RESET_R_EU16 | 50OHM_Y12MIL | BUS | 3 | 6 | 5 | 10 | 5 | 14 | 6 | 15 | 12 | 12 | 12 | 12 |  | 50 Ohms-3 | TOP=L2:L3=L2/L4:L6=L5/L7:BOTTOM=L7 |
| I2C_MUX_RESET_R_EU16 | 50OHM_Y12MIL | BUS | 4 | 6 | 5 | 10 | 5 | 14 | 6 | 15 | 12 | 12 | 12 | 12 |  | 50 Ohms-3 | TOP=L2:L3=L2/L4:L6=L5/L7:BOTTOM=L7 |
| I2C_MUX_RESET_R_EU16 | 50OHM_Y12MIL | BUS | 5 | 6 | 5 | 10 | 5 | 14 | 6 | 15 | 12 | 12 | 12 | 12 |  | 50 Ohms-3 | TOP=L2:L3=L2/L4:L6=L5/L7:BOTTOM=L7 |
| I2C_MUX_RESET_R_EU16 | 50OHM_Y12MIL | BUS | 6 | 6 | 5 | 10 | 5 | 14 | 6 | 15 | 12 | 12 | 12 | 12 |  | 50 Ohms-3 | TOP=L2:L3=L2/L4:L6=L5/L7:BOTTOM=L7 |
| I2C_MUX_RESET_R_EU16 | 50OHM_Y12MIL | BUS | 7 | 6 | 5 | 10 | 5 | 14 | 6 | 15 | 12 | 12 | 12 | 12 |  | 50 Ohms-3 | TOP=L2:L3=L2/L4:L6=L5/L7:BOTTOM=L7 |
| I2C_MUX_RESET_R_EU16 | 50OHM_Y12MIL | BUS | 8 | 6.75 | 5 | 10 | 5 | 14 | 6 | 15 | 12 | 12 | 12 | 12 |  | 50 Ohms-3 | TOP=L2:L3=L2/L4:L6=L5/L7:BOTTOM=L7 |
| I2C_MUX_RESET_R_EU17 | 50OHM_Y12MIL | BUS | 1 | 6.75 | 5 | 10 | 5 | 14 | 6 | 15 | 12 | 12 | 12 | 12 |  | 50 Ohms-3 | TOP=L2:L3=L2/L4:L6=L5/L7:BOTTOM=L7 |
| I2C_MUX_RESET_R_EU17 | 50OHM_Y12MIL | BUS | 2 | 6 | 5 | 10 | 5 | 14 | 6 | 15 | 12 | 12 | 12 | 12 |  | 50 Ohms-3 | TOP=L2:L3=L2/L4:L6=L5/L7:BOTTOM=L7 |
| I2C_MUX_RESET_R_EU17 | 50OHM_Y12MIL | BUS | 3 | 6 | 5 | 10 | 5 | 14 | 6 | 15 | 12 | 12 | 12 | 12 |  | 50 Ohms-3 | TOP=L2:L3=L2/L4:L6=L5/L7:BOTTOM=L7 |
| I2C_MUX_RESET_R_EU17 | 50OHM_Y12MIL | BUS | 4 | 6 | 5 | 10 | 5 | 14 | 6 | 15 | 12 | 12 | 12 | 12 |  | 50 Ohms-3 | TOP=L2:L3=L2/L4:L6=L5/L7:BOTTOM=L7 |
| I2C_MUX_RESET_R_EU17 | 50OHM_Y12MIL | BUS | 5 | 6 | 5 | 10 | 5 | 14 | 6 | 15 | 12 | 12 | 12 | 12 |  | 50 Ohms-3 | TOP=L2:L3=L2/L4:L6=L5/L7:BOTTOM=L7 |
| I2C_MUX_RESET_R_EU17 | 50OHM_Y12MIL | BUS | 6 | 6 | 5 | 10 | 5 | 14 | 6 | 15 | 12 | 12 | 12 | 12 |  | 50 Ohms-3 | TOP=L2:L3=L2/L4:L6=L5/L7:BOTTOM=L7 |
| I2C_MUX_RESET_R_EU17 | 50OHM_Y12MIL | BUS | 7 | 6 | 5 | 10 | 5 | 14 | 6 | 15 | 12 | 12 | 12 | 12 |  | 50 Ohms-3 | TOP=L2:L3=L2/L4:L6=L5/L7:BOTTOM=L7 |
| I2C_MUX_RESET_R_EU17 | 50OHM_Y12MIL | BUS | 8 | 6.75 | 5 | 10 | 5 | 14 | 6 | 15 | 12 | 12 | 12 | 12 |  | 50 Ohms-3 | TOP=L2:L3=L2/L4:L6=L5/L7:BOTTOM=L7 |
| I2C_SW_EU16_ADDRESS_A0 | 50OHM_Y12MIL | BUS | 1 | 6.75 | 5 | 10 | 5 | 14 | 6 | 15 | 12 | 12 | 12 | 12 |  | 50 Ohms-3 | TOP=L2:L3=L2/L4:L6=L5/L7:BOTTOM=L7 |
| I2C_SW_EU16_ADDRESS_A0 | 50OHM_Y12MIL | BUS | 2 | 6 | 5 | 10 | 5 | 14 | 6 | 15 | 12 | 12 | 12 | 12 |  | 50 Ohms-3 | TOP=L2:L3=L2/L4:L6=L5/L7:BOTTOM=L7 |
| I2C_SW_EU16_ADDRESS_A0 | 50OHM_Y12MIL | BUS | 3 | 6 | 5 | 10 | 5 | 14 | 6 | 15 | 12 | 12 | 12 | 12 |  | 50 Ohms-3 | TOP=L2:L3=L2/L4:L6=L5/L7:BOTTOM=L7 |
| I2C_SW_EU16_ADDRESS_A0 | 50OHM_Y12MIL | BUS | 4 | 6 | 5 | 10 | 5 | 14 | 6 | 15 | 12 | 12 | 12 | 12 |  | 50 Ohms-3 | TOP=L2:L3=L2/L4:L6=L5/L7:BOTTOM=L7 |
| I2C_SW_EU16_ADDRESS_A0 | 50OHM_Y12MIL | BUS | 5 | 6 | 5 | 10 | 5 | 14 | 6 | 15 | 12 | 12 | 12 | 12 |  | 50 Ohms-3 | TOP=L2:L3=L2/L4:L6=L5/L7:BOTTOM=L7 |
| I2C_SW_EU16_ADDRESS_A0 | 50OHM_Y12MIL | BUS | 6 | 6 | 5 | 10 | 5 | 14 | 6 | 15 | 12 | 12 | 12 | 12 |  | 50 Ohms-3 | TOP=L2:L3=L2/L4:L6=L5/L7:BOTTOM=L7 |
| I2C_SW_EU16_ADDRESS_A0 | 50OHM_Y12MIL | BUS | 7 | 6 | 5 | 10 | 5 | 14 | 6 | 15 | 12 | 12 | 12 | 12 |  | 50 Ohms-3 | TOP=L2:L3=L2/L4:L6=L5/L7:BOTTOM=L7 |
| I2C_SW_EU16_ADDRESS_A0 | 50OHM_Y12MIL | BUS | 8 | 6.75 | 5 | 10 | 5 | 14 | 6 | 15 | 12 | 12 | 12 | 12 |  | 50 Ohms-3 | TOP=L2:L3=L2/L4:L6=L5/L7:BOTTOM=L7 |
| I2C_SW_EU16_ADDRESS_A1 | 50OHM_Y12MIL | BUS | 1 | 6.75 | 5 | 10 | 5 | 14 | 6 | 15 | 12 | 12 | 12 | 12 |  | 50 Ohms-3 | TOP=L2:L3=L2/L4:L6=L5/L7:BOTTOM=L7 |
| I2C_SW_EU16_ADDRESS_A1 | 50OHM_Y12MIL | BUS | 2 | 6 | 5 | 10 | 5 | 14 | 6 | 15 | 12 | 12 | 12 | 12 |  | 50 Ohms-3 | TOP=L2:L3=L2/L4:L6=L5/L7:BOTTOM=L7 |
| I2C_SW_EU16_ADDRESS_A1 | 50OHM_Y12MIL | BUS | 3 | 6 | 5 | 10 | 5 | 14 | 6 | 15 | 12 | 12 | 12 | 12 |  | 50 Ohms-3 | TOP=L2:L3=L2/L4:L6=L5/L7:BOTTOM=L7 |
| I2C_SW_EU16_ADDRESS_A1 | 50OHM_Y12MIL | BUS | 4 | 6 | 5 | 10 | 5 | 14 | 6 | 15 | 12 | 12 | 12 | 12 |  | 50 Ohms-3 | TOP=L2:L3=L2/L4:L6=L5/L7:BOTTOM=L7 |
| I2C_SW_EU16_ADDRESS_A1 | 50OHM_Y12MIL | BUS | 5 | 6 | 5 | 10 | 5 | 14 | 6 | 15 | 12 | 12 | 12 | 12 |  | 50 Ohms-3 | TOP=L2:L3=L2/L4:L6=L5/L7:BOTTOM=L7 |
| I2C_SW_EU16_ADDRESS_A1 | 50OHM_Y12MIL | BUS | 6 | 6 | 5 | 10 | 5 | 14 | 6 | 15 | 12 | 12 | 12 | 12 |  | 50 Ohms-3 | TOP=L2:L3=L2/L4:L6=L5/L7:BOTTOM=L7 |
| I2C_SW_EU16_ADDRESS_A1 | 50OHM_Y12MIL | BUS | 7 | 6 | 5 | 10 | 5 | 14 | 6 | 15 | 12 | 12 | 12 | 12 |  | 50 Ohms-3 | TOP=L2:L3=L2/L4:L6=L5/L7:BOTTOM=L7 |
| I2C_SW_EU16_ADDRESS_A1 | 50OHM_Y12MIL | BUS | 8 | 6.75 | 5 | 10 | 5 | 14 | 6 | 15 | 12 | 12 | 12 | 12 |  | 50 Ohms-3 | TOP=L2:L3=L2/L4:L6=L5/L7:BOTTOM=L7 |
| I2C_SW_EU16_ADDRESS_A2 | 50OHM_Y12MIL | BUS | 1 | 6.75 | 5 | 10 | 5 | 14 | 6 | 15 | 12 | 12 | 12 | 12 |  | 50 Ohms-3 | TOP=L2:L3=L2/L4:L6=L5/L7:BOTTOM=L7 |
| I2C_SW_EU16_ADDRESS_A2 | 50OHM_Y12MIL | BUS | 2 | 6 | 5 | 10 | 5 | 14 | 6 | 15 | 12 | 12 | 12 | 12 |  | 50 Ohms-3 | TOP=L2:L3=L2/L4:L6=L5/L7:BOTTOM=L7 |
| I2C_SW_EU16_ADDRESS_A2 | 50OHM_Y12MIL | BUS | 3 | 6 | 5 | 10 | 5 | 14 | 6 | 15 | 12 | 12 | 12 | 12 |  | 50 Ohms-3 | TOP=L2:L3=L2/L4:L6=L5/L7:BOTTOM=L7 |
| I2C_SW_EU16_ADDRESS_A2 | 50OHM_Y12MIL | BUS | 4 | 6 | 5 | 10 | 5 | 14 | 6 | 15 | 12 | 12 | 12 | 12 |  | 50 Ohms-3 | TOP=L2:L3=L2/L4:L6=L5/L7:BOTTOM=L7 |
| I2C_SW_EU16_ADDRESS_A2 | 50OHM_Y12MIL | BUS | 5 | 6 | 5 | 10 | 5 | 14 | 6 | 15 | 12 | 12 | 12 | 12 |  | 50 Ohms-3 | TOP=L2:L3=L2/L4:L6=L5/L7:BOTTOM=L7 |
| I2C_SW_EU16_ADDRESS_A2 | 50OHM_Y12MIL | BUS | 6 | 6 | 5 | 10 | 5 | 14 | 6 | 15 | 12 | 12 | 12 | 12 |  | 50 Ohms-3 | TOP=L2:L3=L2/L4:L6=L5/L7:BOTTOM=L7 |
| I2C_SW_EU16_ADDRESS_A2 | 50OHM_Y12MIL | BUS | 7 | 6 | 5 | 10 | 5 | 14 | 6 | 15 | 12 | 12 | 12 | 12 |  | 50 Ohms-3 | TOP=L2:L3=L2/L4:L6=L5/L7:BOTTOM=L7 |
| I2C_SW_EU16_ADDRESS_A2 | 50OHM_Y12MIL | BUS | 8 | 6.75 | 5 | 10 | 5 | 14 | 6 | 15 | 12 | 12 | 12 | 12 |  | 50 Ohms-3 | TOP=L2:L3=L2/L4:L6=L5/L7:BOTTOM=L7 |
| I2C_SW_EU17_ADDRESS_A0 | 50OHM_Y12MIL | BUS | 1 | 6.75 | 5 | 10 | 5 | 14 | 6 | 15 | 12 | 12 | 12 | 12 |  | 50 Ohms-3 | TOP=L2:L3=L2/L4:L6=L5/L7:BOTTOM=L7 |
| I2C_SW_EU17_ADDRESS_A0 | 50OHM_Y12MIL | BUS | 2 | 6 | 5 | 10 | 5 | 14 | 6 | 15 | 12 | 12 | 12 | 12 |  | 50 Ohms-3 | TOP=L2:L3=L2/L4:L6=L5/L7:BOTTOM=L7 |
| I2C_SW_EU17_ADDRESS_A0 | 50OHM_Y12MIL | BUS | 3 | 6 | 5 | 10 | 5 | 14 | 6 | 15 | 12 | 12 | 12 | 12 |  | 50 Ohms-3 | TOP=L2:L3=L2/L4:L6=L5/L7:BOTTOM=L7 |
| I2C_SW_EU17_ADDRESS_A0 | 50OHM_Y12MIL | BUS | 4 | 6 | 5 | 10 | 5 | 14 | 6 | 15 | 12 | 12 | 12 | 12 |  | 50 Ohms-3 | TOP=L2:L3=L2/L4:L6=L5/L7:BOTTOM=L7 |
| I2C_SW_EU17_ADDRESS_A0 | 50OHM_Y12MIL | BUS | 5 | 6 | 5 | 10 | 5 | 14 | 6 | 15 | 12 | 12 | 12 | 12 |  | 50 Ohms-3 | TOP=L2:L3=L2/L4:L6=L5/L7:BOTTOM=L7 |
| I2C_SW_EU17_ADDRESS_A0 | 50OHM_Y12MIL | BUS | 6 | 6 | 5 | 10 | 5 | 14 | 6 | 15 | 12 | 12 | 12 | 12 |  | 50 Ohms-3 | TOP=L2:L3=L2/L4:L6=L5/L7:BOTTOM=L7 |
| I2C_SW_EU17_ADDRESS_A0 | 50OHM_Y12MIL | BUS | 7 | 6 | 5 | 10 | 5 | 14 | 6 | 15 | 12 | 12 | 12 | 12 |  | 50 Ohms-3 | TOP=L2:L3=L2/L4:L6=L5/L7:BOTTOM=L7 |
| I2C_SW_EU17_ADDRESS_A0 | 50OHM_Y12MIL | BUS | 8 | 6.75 | 5 | 10 | 5 | 14 | 6 | 15 | 12 | 12 | 12 | 12 |  | 50 Ohms-3 | TOP=L2:L3=L2/L4:L6=L5/L7:BOTTOM=L7 |
| I2C_SW_EU17_ADDRESS_A1 | 50OHM_Y12MIL | BUS | 1 | 6.75 | 5 | 10 | 5 | 14 | 6 | 15 | 12 | 12 | 12 | 12 |  | 50 Ohms-3 | TOP=L2:L3=L2/L4:L6=L5/L7:BOTTOM=L7 |
| I2C_SW_EU17_ADDRESS_A1 | 50OHM_Y12MIL | BUS | 2 | 6 | 5 | 10 | 5 | 14 | 6 | 15 | 12 | 12 | 12 | 12 |  | 50 Ohms-3 | TOP=L2:L3=L2/L4:L6=L5/L7:BOTTOM=L7 |
| I2C_SW_EU17_ADDRESS_A1 | 50OHM_Y12MIL | BUS | 3 | 6 | 5 | 10 | 5 | 14 | 6 | 15 | 12 | 12 | 12 | 12 |  | 50 Ohms-3 | TOP=L2:L3=L2/L4:L6=L5/L7:BOTTOM=L7 |
| I2C_SW_EU17_ADDRESS_A1 | 50OHM_Y12MIL | BUS | 4 | 6 | 5 | 10 | 5 | 14 | 6 | 15 | 12 | 12 | 12 | 12 |  | 50 Ohms-3 | TOP=L2:L3=L2/L4:L6=L5/L7:BOTTOM=L7 |
| I2C_SW_EU17_ADDRESS_A1 | 50OHM_Y12MIL | BUS | 5 | 6 | 5 | 10 | 5 | 14 | 6 | 15 | 12 | 12 | 12 | 12 |  | 50 Ohms-3 | TOP=L2:L3=L2/L4:L6=L5/L7:BOTTOM=L7 |
| I2C_SW_EU17_ADDRESS_A1 | 50OHM_Y12MIL | BUS | 6 | 6 | 5 | 10 | 5 | 14 | 6 | 15 | 12 | 12 | 12 | 12 |  | 50 Ohms-3 | TOP=L2:L3=L2/L4:L6=L5/L7:BOTTOM=L7 |
| I2C_SW_EU17_ADDRESS_A1 | 50OHM_Y12MIL | BUS | 7 | 6 | 5 | 10 | 5 | 14 | 6 | 15 | 12 | 12 | 12 | 12 |  | 50 Ohms-3 | TOP=L2:L3=L2/L4:L6=L5/L7:BOTTOM=L7 |
| I2C_SW_EU17_ADDRESS_A1 | 50OHM_Y12MIL | BUS | 8 | 6.75 | 5 | 10 | 5 | 14 | 6 | 15 | 12 | 12 | 12 | 12 |  | 50 Ohms-3 | TOP=L2:L3=L2/L4:L6=L5/L7:BOTTOM=L7 |
| I2C_SW_EU17_ADDRESS_A2 | 50OHM_Y12MIL | BUS | 1 | 6.75 | 5 | 10 | 5 | 14 | 6 | 15 | 12 | 12 | 12 | 12 |  | 50 Ohms-3 | TOP=L2:L3=L2/L4:L6=L5/L7:BOTTOM=L7 |
| I2C_SW_EU17_ADDRESS_A2 | 50OHM_Y12MIL | BUS | 2 | 6 | 5 | 10 | 5 | 14 | 6 | 15 | 12 | 12 | 12 | 12 |  | 50 Ohms-3 | TOP=L2:L3=L2/L4:L6=L5/L7:BOTTOM=L7 |
| I2C_SW_EU17_ADDRESS_A2 | 50OHM_Y12MIL | BUS | 3 | 6 | 5 | 10 | 5 | 14 | 6 | 15 | 12 | 12 | 12 | 12 |  | 50 Ohms-3 | TOP=L2:L3=L2/L4:L6=L5/L7:BOTTOM=L7 |
| I2C_SW_EU17_ADDRESS_A2 | 50OHM_Y12MIL | BUS | 4 | 6 | 5 | 10 | 5 | 14 | 6 | 15 | 12 | 12 | 12 | 12 |  | 50 Ohms-3 | TOP=L2:L3=L2/L4:L6=L5/L7:BOTTOM=L7 |
| I2C_SW_EU17_ADDRESS_A2 | 50OHM_Y12MIL | BUS | 5 | 6 | 5 | 10 | 5 | 14 | 6 | 15 | 12 | 12 | 12 | 12 |  | 50 Ohms-3 | TOP=L2:L3=L2/L4:L6=L5/L7:BOTTOM=L7 |
| I2C_SW_EU17_ADDRESS_A2 | 50OHM_Y12MIL | BUS | 6 | 6 | 5 | 10 | 5 | 14 | 6 | 15 | 12 | 12 | 12 | 12 |  | 50 Ohms-3 | TOP=L2:L3=L2/L4:L6=L5/L7:BOTTOM=L7 |
| I2C_SW_EU17_ADDRESS_A2 | 50OHM_Y12MIL | BUS | 7 | 6 | 5 | 10 | 5 | 14 | 6 | 15 | 12 | 12 | 12 | 12 |  | 50 Ohms-3 | TOP=L2:L3=L2/L4:L6=L5/L7:BOTTOM=L7 |
| I2C_SW_EU17_ADDRESS_A2 | 50OHM_Y12MIL | BUS | 8 | 6.75 | 5 | 10 | 5 | 14 | 6 | 15 | 12 | 12 | 12 | 12 |  | 50 Ohms-3 | TOP=L2:L3=L2/L4:L6=L5/L7:BOTTOM=L7 |
| P12V_MOST0_GATE | 50OHM_Y12MIL | BUS | 1 | 6.75 | 5 | 10 | 5 | 14 | 6 | 15 | 12 | 12 | 12 | 12 |  | 50 Ohms-3 | TOP=L2:L3=L2/L4:L6=L5/L7:BOTTOM=L7 |
| P12V_MOST0_GATE | 50OHM_Y12MIL | BUS | 2 | 6 | 5 | 10 | 5 | 14 | 6 | 15 | 12 | 12 | 12 | 12 |  | 50 Ohms-3 | TOP=L2:L3=L2/L4:L6=L5/L7:BOTTOM=L7 |
| P12V_MOST0_GATE | 50OHM_Y12MIL | BUS | 3 | 6 | 5 | 10 | 5 | 14 | 6 | 15 | 12 | 12 | 12 | 12 |  | 50 Ohms-3 | TOP=L2:L3=L2/L4:L6=L5/L7:BOTTOM=L7 |
| P12V_MOST0_GATE | 50OHM_Y12MIL | BUS | 4 | 6 | 5 | 10 | 5 | 14 | 6 | 15 | 12 | 12 | 12 | 12 |  | 50 Ohms-3 | TOP=L2:L3=L2/L4:L6=L5/L7:BOTTOM=L7 |
| P12V_MOST0_GATE | 50OHM_Y12MIL | BUS | 5 | 6 | 5 | 10 | 5 | 14 | 6 | 15 | 12 | 12 | 12 | 12 |  | 50 Ohms-3 | TOP=L2:L3=L2/L4:L6=L5/L7:BOTTOM=L7 |
| P12V_MOST0_GATE | 50OHM_Y12MIL | BUS | 6 | 6 | 5 | 10 | 5 | 14 | 6 | 15 | 12 | 12 | 12 | 12 |  | 50 Ohms-3 | TOP=L2:L3=L2/L4:L6=L5/L7:BOTTOM=L7 |
| P12V_MOST0_GATE | 50OHM_Y12MIL | BUS | 7 | 6 | 5 | 10 | 5 | 14 | 6 | 15 | 12 | 12 | 12 | 12 |  | 50 Ohms-3 | TOP=L2:L3=L2/L4:L6=L5/L7:BOTTOM=L7 |
| P12V_MOST0_GATE | 50OHM_Y12MIL | BUS | 8 | 6.75 | 5 | 10 | 5 | 14 | 6 | 15 | 12 | 12 | 12 | 12 |  | 50 Ohms-3 | TOP=L2:L3=L2/L4:L6=L5/L7:BOTTOM=L7 |
| P12V_MOST1_GATE | 50OHM_Y12MIL | BUS | 1 | 6.75 | 5 | 10 | 5 | 14 | 6 | 15 | 12 | 12 | 12 | 12 |  | 50 Ohms-3 | TOP=L2:L3=L2/L4:L6=L5/L7:BOTTOM=L7 |
| P12V_MOST1_GATE | 50OHM_Y12MIL | BUS | 2 | 6 | 5 | 10 | 5 | 14 | 6 | 15 | 12 | 12 | 12 | 12 |  | 50 Ohms-3 | TOP=L2:L3=L2/L4:L6=L5/L7:BOTTOM=L7 |
| P12V_MOST1_GATE | 50OHM_Y12MIL | BUS | 3 | 6 | 5 | 10 | 5 | 14 | 6 | 15 | 12 | 12 | 12 | 12 |  | 50 Ohms-3 | TOP=L2:L3=L2/L4:L6=L5/L7:BOTTOM=L7 |
| P12V_MOST1_GATE | 50OHM_Y12MIL | BUS | 4 | 6 | 5 | 10 | 5 | 14 | 6 | 15 | 12 | 12 | 12 | 12 |  | 50 Ohms-3 | TOP=L2:L3=L2/L4:L6=L5/L7:BOTTOM=L7 |
| P12V_MOST1_GATE | 50OHM_Y12MIL | BUS | 5 | 6 | 5 | 10 | 5 | 14 | 6 | 15 | 12 | 12 | 12 | 12 |  | 50 Ohms-3 | TOP=L2:L3=L2/L4:L6=L5/L7:BOTTOM=L7 |
| P12V_MOST1_GATE | 50OHM_Y12MIL | BUS | 6 | 6 | 5 | 10 | 5 | 14 | 6 | 15 | 12 | 12 | 12 | 12 |  | 50 Ohms-3 | TOP=L2:L3=L2/L4:L6=L5/L7:BOTTOM=L7 |
| P12V_MOST1_GATE | 50OHM_Y12MIL | BUS | 7 | 6 | 5 | 10 | 5 | 14 | 6 | 15 | 12 | 12 | 12 | 12 |  | 50 Ohms-3 | TOP=L2:L3=L2/L4:L6=L5/L7:BOTTOM=L7 |
| P12V_MOST1_GATE | 50OHM_Y12MIL | BUS | 8 | 6.75 | 5 | 10 | 5 | 14 | 6 | 15 | 12 | 12 | 12 | 12 |  | 50 Ohms-3 | TOP=L2:L3=L2/L4:L6=L5/L7:BOTTOM=L7 |
| P12V_MOST10_GATE | 50OHM_Y12MIL | BUS | 1 | 6.75 | 5 | 10 | 5 | 14 | 6 | 15 | 12 | 12 | 12 | 12 |  | 50 Ohms-3 | TOP=L2:L3=L2/L4:L6=L5/L7:BOTTOM=L7 |
| P12V_MOST10_GATE | 50OHM_Y12MIL | BUS | 2 | 6 | 5 | 10 | 5 | 14 | 6 | 15 | 12 | 12 | 12 | 12 |  | 50 Ohms-3 | TOP=L2:L3=L2/L4:L6=L5/L7:BOTTOM=L7 |
| P12V_MOST10_GATE | 50OHM_Y12MIL | BUS | 3 | 6 | 5 | 10 | 5 | 14 | 6 | 15 | 12 | 12 | 12 | 12 |  | 50 Ohms-3 | TOP=L2:L3=L2/L4:L6=L5/L7:BOTTOM=L7 |
| P12V_MOST10_GATE | 50OHM_Y12MIL | BUS | 4 | 6 | 5 | 10 | 5 | 14 | 6 | 15 | 12 | 12 | 12 | 12 |  | 50 Ohms-3 | TOP=L2:L3=L2/L4:L6=L5/L7:BOTTOM=L7 |
| P12V_MOST10_GATE | 50OHM_Y12MIL | BUS | 5 | 6 | 5 | 10 | 5 | 14 | 6 | 15 | 12 | 12 | 12 | 12 |  | 50 Ohms-3 | TOP=L2:L3=L2/L4:L6=L5/L7:BOTTOM=L7 |
| P12V_MOST10_GATE | 50OHM_Y12MIL | BUS | 6 | 6 | 5 | 10 | 5 | 14 | 6 | 15 | 12 | 12 | 12 | 12 |  | 50 Ohms-3 | TOP=L2:L3=L2/L4:L6=L5/L7:BOTTOM=L7 |
| P12V_MOST10_GATE | 50OHM_Y12MIL | BUS | 7 | 6 | 5 | 10 | 5 | 14 | 6 | 15 | 12 | 12 | 12 | 12 |  | 50 Ohms-3 | TOP=L2:L3=L2/L4:L6=L5/L7:BOTTOM=L7 |
| P12V_MOST10_GATE | 50OHM_Y12MIL | BUS | 8 | 6.75 | 5 | 10 | 5 | 14 | 6 | 15 | 12 | 12 | 12 | 12 |  | 50 Ohms-3 | TOP=L2:L3=L2/L4:L6=L5/L7:BOTTOM=L7 |
| P12V_MOST11_GATE | 50OHM_Y12MIL | BUS | 1 | 6.75 | 5 | 10 | 5 | 14 | 6 | 15 | 12 | 12 | 12 | 12 |  | 50 Ohms-3 | TOP=L2:L3=L2/L4:L6=L5/L7:BOTTOM=L7 |
| P12V_MOST11_GATE | 50OHM_Y12MIL | BUS | 2 | 6 | 5 | 10 | 5 | 14 | 6 | 15 | 12 | 12 | 12 | 12 |  | 50 Ohms-3 | TOP=L2:L3=L2/L4:L6=L5/L7:BOTTOM=L7 |
| P12V_MOST11_GATE | 50OHM_Y12MIL | BUS | 3 | 6 | 5 | 10 | 5 | 14 | 6 | 15 | 12 | 12 | 12 | 12 |  | 50 Ohms-3 | TOP=L2:L3=L2/L4:L6=L5/L7:BOTTOM=L7 |
| P12V_MOST11_GATE | 50OHM_Y12MIL | BUS | 4 | 6 | 5 | 10 | 5 | 14 | 6 | 15 | 12 | 12 | 12 | 12 |  | 50 Ohms-3 | TOP=L2:L3=L2/L4:L6=L5/L7:BOTTOM=L7 |
| P12V_MOST11_GATE | 50OHM_Y12MIL | BUS | 5 | 6 | 5 | 10 | 5 | 14 | 6 | 15 | 12 | 12 | 12 | 12 |  | 50 Ohms-3 | TOP=L2:L3=L2/L4:L6=L5/L7:BOTTOM=L7 |
| P12V_MOST11_GATE | 50OHM_Y12MIL | BUS | 6 | 6 | 5 | 10 | 5 | 14 | 6 | 15 | 12 | 12 | 12 | 12 |  | 50 Ohms-3 | TOP=L2:L3=L2/L4:L6=L5/L7:BOTTOM=L7 |
| P12V_MOST11_GATE | 50OHM_Y12MIL | BUS | 7 | 6 | 5 | 10 | 5 | 14 | 6 | 15 | 12 | 12 | 12 | 12 |  | 50 Ohms-3 | TOP=L2:L3=L2/L4:L6=L5/L7:BOTTOM=L7 |
| P12V_MOST11_GATE | 50OHM_Y12MIL | BUS | 8 | 6.75 | 5 | 10 | 5 | 14 | 6 | 15 | 12 | 12 | 12 | 12 |  | 50 Ohms-3 | TOP=L2:L3=L2/L4:L6=L5/L7:BOTTOM=L7 |
| P12V_MOST12_GATE | 50OHM_Y12MIL | BUS | 1 | 6.75 | 5 | 10 | 5 | 14 | 6 | 15 | 12 | 12 | 12 | 12 |  | 50 Ohms-3 | TOP=L2:L3=L2/L4:L6=L5/L7:BOTTOM=L7 |
| P12V_MOST12_GATE | 50OHM_Y12MIL | BUS | 2 | 6 | 5 | 10 | 5 | 14 | 6 | 15 | 12 | 12 | 12 | 12 |  | 50 Ohms-3 | TOP=L2:L3=L2/L4:L6=L5/L7:BOTTOM=L7 |
| P12V_MOST12_GATE | 50OHM_Y12MIL | BUS | 3 | 6 | 5 | 10 | 5 | 14 | 6 | 15 | 12 | 12 | 12 | 12 |  | 50 Ohms-3 | TOP=L2:L3=L2/L4:L6=L5/L7:BOTTOM=L7 |
| P12V_MOST12_GATE | 50OHM_Y12MIL | BUS | 4 | 6 | 5 | 10 | 5 | 14 | 6 | 15 | 12 | 12 | 12 | 12 |  | 50 Ohms-3 | TOP=L2:L3=L2/L4:L6=L5/L7:BOTTOM=L7 |
| P12V_MOST12_GATE | 50OHM_Y12MIL | BUS | 5 | 6 | 5 | 10 | 5 | 14 | 6 | 15 | 12 | 12 | 12 | 12 |  | 50 Ohms-3 | TOP=L2:L3=L2/L4:L6=L5/L7:BOTTOM=L7 |
| P12V_MOST12_GATE | 50OHM_Y12MIL | BUS | 6 | 6 | 5 | 10 | 5 | 14 | 6 | 15 | 12 | 12 | 12 | 12 |  | 50 Ohms-3 | TOP=L2:L3=L2/L4:L6=L5/L7:BOTTOM=L7 |
| P12V_MOST12_GATE | 50OHM_Y12MIL | BUS | 7 | 6 | 5 | 10 | 5 | 14 | 6 | 15 | 12 | 12 | 12 | 12 |  | 50 Ohms-3 | TOP=L2:L3=L2/L4:L6=L5/L7:BOTTOM=L7 |
| P12V_MOST12_GATE | 50OHM_Y12MIL | BUS | 8 | 6.75 | 5 | 10 | 5 | 14 | 6 | 15 | 12 | 12 | 12 | 12 |  | 50 Ohms-3 | TOP=L2:L3=L2/L4:L6=L5/L7:BOTTOM=L7 |
| P12V_MOST13_GATE | 50OHM_Y12MIL | BUS | 1 | 6.75 | 5 | 10 | 5 | 14 | 6 | 15 | 12 | 12 | 12 | 12 |  | 50 Ohms-3 | TOP=L2:L3=L2/L4:L6=L5/L7:BOTTOM=L7 |
| P12V_MOST13_GATE | 50OHM_Y12MIL | BUS | 2 | 6 | 5 | 10 | 5 | 14 | 6 | 15 | 12 | 12 | 12 | 12 |  | 50 Ohms-3 | TOP=L2:L3=L2/L4:L6=L5/L7:BOTTOM=L7 |
| P12V_MOST13_GATE | 50OHM_Y12MIL | BUS | 3 | 6 | 5 | 10 | 5 | 14 | 6 | 15 | 12 | 12 | 12 | 12 |  | 50 Ohms-3 | TOP=L2:L3=L2/L4:L6=L5/L7:BOTTOM=L7 |
| P12V_MOST13_GATE | 50OHM_Y12MIL | BUS | 4 | 6 | 5 | 10 | 5 | 14 | 6 | 15 | 12 | 12 | 12 | 12 |  | 50 Ohms-3 | TOP=L2:L3=L2/L4:L6=L5/L7:BOTTOM=L7 |
| P12V_MOST13_GATE | 50OHM_Y12MIL | BUS | 5 | 6 | 5 | 10 | 5 | 14 | 6 | 15 | 12 | 12 | 12 | 12 |  | 50 Ohms-3 | TOP=L2:L3=L2/L4:L6=L5/L7:BOTTOM=L7 |
| P12V_MOST13_GATE | 50OHM_Y12MIL | BUS | 6 | 6 | 5 | 10 | 5 | 14 | 6 | 15 | 12 | 12 | 12 | 12 |  | 50 Ohms-3 | TOP=L2:L3=L2/L4:L6=L5/L7:BOTTOM=L7 |
| P12V_MOST13_GATE | 50OHM_Y12MIL | BUS | 7 | 6 | 5 | 10 | 5 | 14 | 6 | 15 | 12 | 12 | 12 | 12 |  | 50 Ohms-3 | TOP=L2:L3=L2/L4:L6=L5/L7:BOTTOM=L7 |
| P12V_MOST13_GATE | 50OHM_Y12MIL | BUS | 8 | 6.75 | 5 | 10 | 5 | 14 | 6 | 15 | 12 | 12 | 12 | 12 |  | 50 Ohms-3 | TOP=L2:L3=L2/L4:L6=L5/L7:BOTTOM=L7 |
| P12V_MOST14_GATE | 50OHM_Y12MIL | BUS | 1 | 6.75 | 5 | 10 | 5 | 14 | 6 | 15 | 12 | 12 | 12 | 12 |  | 50 Ohms-3 | TOP=L2:L3=L2/L4:L6=L5/L7:BOTTOM=L7 |
| P12V_MOST14_GATE | 50OHM_Y12MIL | BUS | 2 | 6 | 5 | 10 | 5 | 14 | 6 | 15 | 12 | 12 | 12 | 12 |  | 50 Ohms-3 | TOP=L2:L3=L2/L4:L6=L5/L7:BOTTOM=L7 |
| P12V_MOST14_GATE | 50OHM_Y12MIL | BUS | 3 | 6 | 5 | 10 | 5 | 14 | 6 | 15 | 12 | 12 | 12 | 12 |  | 50 Ohms-3 | TOP=L2:L3=L2/L4:L6=L5/L7:BOTTOM=L7 |
| P12V_MOST14_GATE | 50OHM_Y12MIL | BUS | 4 | 6 | 5 | 10 | 5 | 14 | 6 | 15 | 12 | 12 | 12 | 12 |  | 50 Ohms-3 | TOP=L2:L3=L2/L4:L6=L5/L7:BOTTOM=L7 |
| P12V_MOST14_GATE | 50OHM_Y12MIL | BUS | 5 | 6 | 5 | 10 | 5 | 14 | 6 | 15 | 12 | 12 | 12 | 12 |  | 50 Ohms-3 | TOP=L2:L3=L2/L4:L6=L5/L7:BOTTOM=L7 |
| P12V_MOST14_GATE | 50OHM_Y12MIL | BUS | 6 | 6 | 5 | 10 | 5 | 14 | 6 | 15 | 12 | 12 | 12 | 12 |  | 50 Ohms-3 | TOP=L2:L3=L2/L4:L6=L5/L7:BOTTOM=L7 |
| P12V_MOST14_GATE | 50OHM_Y12MIL | BUS | 7 | 6 | 5 | 10 | 5 | 14 | 6 | 15 | 12 | 12 | 12 | 12 |  | 50 Ohms-3 | TOP=L2:L3=L2/L4:L6=L5/L7:BOTTOM=L7 |
| P12V_MOST14_GATE | 50OHM_Y12MIL | BUS | 8 | 6.75 | 5 | 10 | 5 | 14 | 6 | 15 | 12 | 12 | 12 | 12 |  | 50 Ohms-3 | TOP=L2:L3=L2/L4:L6=L5/L7:BOTTOM=L7 |
| P12V_MOST2_GATE | 50OHM_Y12MIL | BUS | 1 | 6.75 | 5 | 10 | 5 | 14 | 6 | 15 | 12 | 12 | 12 | 12 |  | 50 Ohms-3 | TOP=L2:L3=L2/L4:L6=L5/L7:BOTTOM=L7 |
| P12V_MOST2_GATE | 50OHM_Y12MIL | BUS | 2 | 6 | 5 | 10 | 5 | 14 | 6 | 15 | 12 | 12 | 12 | 12 |  | 50 Ohms-3 | TOP=L2:L3=L2/L4:L6=L5/L7:BOTTOM=L7 |
| P12V_MOST2_GATE | 50OHM_Y12MIL | BUS | 3 | 6 | 5 | 10 | 5 | 14 | 6 | 15 | 12 | 12 | 12 | 12 |  | 50 Ohms-3 | TOP=L2:L3=L2/L4:L6=L5/L7:BOTTOM=L7 |
| P12V_MOST2_GATE | 50OHM_Y12MIL | BUS | 4 | 6 | 5 | 10 | 5 | 14 | 6 | 15 | 12 | 12 | 12 | 12 |  | 50 Ohms-3 | TOP=L2:L3=L2/L4:L6=L5/L7:BOTTOM=L7 |
| P12V_MOST2_GATE | 50OHM_Y12MIL | BUS | 5 | 6 | 5 | 10 | 5 | 14 | 6 | 15 | 12 | 12 | 12 | 12 |  | 50 Ohms-3 | TOP=L2:L3=L2/L4:L6=L5/L7:BOTTOM=L7 |
| P12V_MOST2_GATE | 50OHM_Y12MIL | BUS | 6 | 6 | 5 | 10 | 5 | 14 | 6 | 15 | 12 | 12 | 12 | 12 |  | 50 Ohms-3 | TOP=L2:L3=L2/L4:L6=L5/L7:BOTTOM=L7 |
| P12V_MOST2_GATE | 50OHM_Y12MIL | BUS | 7 | 6 | 5 | 10 | 5 | 14 | 6 | 15 | 12 | 12 | 12 | 12 |  | 50 Ohms-3 | TOP=L2:L3=L2/L4:L6=L5/L7:BOTTOM=L7 |
| P12V_MOST2_GATE | 50OHM_Y12MIL | BUS | 8 | 6.75 | 5 | 10 | 5 | 14 | 6 | 15 | 12 | 12 | 12 | 12 |  | 50 Ohms-3 | TOP=L2:L3=L2/L4:L6=L5/L7:BOTTOM=L7 |
| P12V_MOST3_GATE | 50OHM_Y12MIL | BUS | 1 | 6.75 | 5 | 10 | 5 | 14 | 6 | 15 | 12 | 12 | 12 | 12 |  | 50 Ohms-3 | TOP=L2:L3=L2/L4:L6=L5/L7:BOTTOM=L7 |
| P12V_MOST3_GATE | 50OHM_Y12MIL | BUS | 2 | 6 | 5 | 10 | 5 | 14 | 6 | 15 | 12 | 12 | 12 | 12 |  | 50 Ohms-3 | TOP=L2:L3=L2/L4:L6=L5/L7:BOTTOM=L7 |
| P12V_MOST3_GATE | 50OHM_Y12MIL | BUS | 3 | 6 | 5 | 10 | 5 | 14 | 6 | 15 | 12 | 12 | 12 | 12 |  | 50 Ohms-3 | TOP=L2:L3=L2/L4:L6=L5/L7:BOTTOM=L7 |
| P12V_MOST3_GATE | 50OHM_Y12MIL | BUS | 4 | 6 | 5 | 10 | 5 | 14 | 6 | 15 | 12 | 12 | 12 | 12 |  | 50 Ohms-3 | TOP=L2:L3=L2/L4:L6=L5/L7:BOTTOM=L7 |
| P12V_MOST3_GATE | 50OHM_Y12MIL | BUS | 5 | 6 | 5 | 10 | 5 | 14 | 6 | 15 | 12 | 12 | 12 | 12 |  | 50 Ohms-3 | TOP=L2:L3=L2/L4:L6=L5/L7:BOTTOM=L7 |
| P12V_MOST3_GATE | 50OHM_Y12MIL | BUS | 6 | 6 | 5 | 10 | 5 | 14 | 6 | 15 | 12 | 12 | 12 | 12 |  | 50 Ohms-3 | TOP=L2:L3=L2/L4:L6=L5/L7:BOTTOM=L7 |
| P12V_MOST3_GATE | 50OHM_Y12MIL | BUS | 7 | 6 | 5 | 10 | 5 | 14 | 6 | 15 | 12 | 12 | 12 | 12 |  | 50 Ohms-3 | TOP=L2:L3=L2/L4:L6=L5/L7:BOTTOM=L7 |
| P12V_MOST3_GATE | 50OHM_Y12MIL | BUS | 8 | 6.75 | 5 | 10 | 5 | 14 | 6 | 15 | 12 | 12 | 12 | 12 |  | 50 Ohms-3 | TOP=L2:L3=L2/L4:L6=L5/L7:BOTTOM=L7 |
| P12V_MOST4_GATE | 50OHM_Y12MIL | BUS | 1 | 6.75 | 5 | 10 | 5 | 14 | 6 | 15 | 12 | 12 | 12 | 12 |  | 50 Ohms-3 | TOP=L2:L3=L2/L4:L6=L5/L7:BOTTOM=L7 |
| P12V_MOST4_GATE | 50OHM_Y12MIL | BUS | 2 | 6 | 5 | 10 | 5 | 14 | 6 | 15 | 12 | 12 | 12 | 12 |  | 50 Ohms-3 | TOP=L2:L3=L2/L4:L6=L5/L7:BOTTOM=L7 |
| P12V_MOST4_GATE | 50OHM_Y12MIL | BUS | 3 | 6 | 5 | 10 | 5 | 14 | 6 | 15 | 12 | 12 | 12 | 12 |  | 50 Ohms-3 | TOP=L2:L3=L2/L4:L6=L5/L7:BOTTOM=L7 |
| P12V_MOST4_GATE | 50OHM_Y12MIL | BUS | 4 | 6 | 5 | 10 | 5 | 14 | 6 | 15 | 12 | 12 | 12 | 12 |  | 50 Ohms-3 | TOP=L2:L3=L2/L4:L6=L5/L7:BOTTOM=L7 |
| P12V_MOST4_GATE | 50OHM_Y12MIL | BUS | 5 | 6 | 5 | 10 | 5 | 14 | 6 | 15 | 12 | 12 | 12 | 12 |  | 50 Ohms-3 | TOP=L2:L3=L2/L4:L6=L5/L7:BOTTOM=L7 |
| P12V_MOST4_GATE | 50OHM_Y12MIL | BUS | 6 | 6 | 5 | 10 | 5 | 14 | 6 | 15 | 12 | 12 | 12 | 12 |  | 50 Ohms-3 | TOP=L2:L3=L2/L4:L6=L5/L7:BOTTOM=L7 |
| P12V_MOST4_GATE | 50OHM_Y12MIL | BUS | 7 | 6 | 5 | 10 | 5 | 14 | 6 | 15 | 12 | 12 | 12 | 12 |  | 50 Ohms-3 | TOP=L2:L3=L2/L4:L6=L5/L7:BOTTOM=L7 |
| P12V_MOST4_GATE | 50OHM_Y12MIL | BUS | 8 | 6.75 | 5 | 10 | 5 | 14 | 6 | 15 | 12 | 12 | 12 | 12 |  | 50 Ohms-3 | TOP=L2:L3=L2/L4:L6=L5/L7:BOTTOM=L7 |
| P12V_MOST5_GATE | 50OHM_Y12MIL | BUS | 1 | 6.75 | 5 | 10 | 5 | 14 | 6 | 15 | 12 | 12 | 12 | 12 |  | 50 Ohms-3 | TOP=L2:L3=L2/L4:L6=L5/L7:BOTTOM=L7 |
| P12V_MOST5_GATE | 50OHM_Y12MIL | BUS | 2 | 6 | 5 | 10 | 5 | 14 | 6 | 15 | 12 | 12 | 12 | 12 |  | 50 Ohms-3 | TOP=L2:L3=L2/L4:L6=L5/L7:BOTTOM=L7 |
| P12V_MOST5_GATE | 50OHM_Y12MIL | BUS | 3 | 6 | 5 | 10 | 5 | 14 | 6 | 15 | 12 | 12 | 12 | 12 |  | 50 Ohms-3 | TOP=L2:L3=L2/L4:L6=L5/L7:BOTTOM=L7 |
| P12V_MOST5_GATE | 50OHM_Y12MIL | BUS | 4 | 6 | 5 | 10 | 5 | 14 | 6 | 15 | 12 | 12 | 12 | 12 |  | 50 Ohms-3 | TOP=L2:L3=L2/L4:L6=L5/L7:BOTTOM=L7 |
| P12V_MOST5_GATE | 50OHM_Y12MIL | BUS | 5 | 6 | 5 | 10 | 5 | 14 | 6 | 15 | 12 | 12 | 12 | 12 |  | 50 Ohms-3 | TOP=L2:L3=L2/L4:L6=L5/L7:BOTTOM=L7 |
| P12V_MOST5_GATE | 50OHM_Y12MIL | BUS | 6 | 6 | 5 | 10 | 5 | 14 | 6 | 15 | 12 | 12 | 12 | 12 |  | 50 Ohms-3 | TOP=L2:L3=L2/L4:L6=L5/L7:BOTTOM=L7 |
| P12V_MOST5_GATE | 50OHM_Y12MIL | BUS | 7 | 6 | 5 | 10 | 5 | 14 | 6 | 15 | 12 | 12 | 12 | 12 |  | 50 Ohms-3 | TOP=L2:L3=L2/L4:L6=L5/L7:BOTTOM=L7 |
| P12V_MOST5_GATE | 50OHM_Y12MIL | BUS | 8 | 6.75 | 5 | 10 | 5 | 14 | 6 | 15 | 12 | 12 | 12 | 12 |  | 50 Ohms-3 | TOP=L2:L3=L2/L4:L6=L5/L7:BOTTOM=L7 |
| P12V_MOST6_GATE | 50OHM_Y12MIL | BUS | 1 | 6.75 | 5 | 10 | 5 | 14 | 6 | 15 | 12 | 12 | 12 | 12 |  | 50 Ohms-3 | TOP=L2:L3=L2/L4:L6=L5/L7:BOTTOM=L7 |
| P12V_MOST6_GATE | 50OHM_Y12MIL | BUS | 2 | 6 | 5 | 10 | 5 | 14 | 6 | 15 | 12 | 12 | 12 | 12 |  | 50 Ohms-3 | TOP=L2:L3=L2/L4:L6=L5/L7:BOTTOM=L7 |
| P12V_MOST6_GATE | 50OHM_Y12MIL | BUS | 3 | 6 | 5 | 10 | 5 | 14 | 6 | 15 | 12 | 12 | 12 | 12 |  | 50 Ohms-3 | TOP=L2:L3=L2/L4:L6=L5/L7:BOTTOM=L7 |
| P12V_MOST6_GATE | 50OHM_Y12MIL | BUS | 4 | 6 | 5 | 10 | 5 | 14 | 6 | 15 | 12 | 12 | 12 | 12 |  | 50 Ohms-3 | TOP=L2:L3=L2/L4:L6=L5/L7:BOTTOM=L7 |
| P12V_MOST6_GATE | 50OHM_Y12MIL | BUS | 5 | 6 | 5 | 10 | 5 | 14 | 6 | 15 | 12 | 12 | 12 | 12 |  | 50 Ohms-3 | TOP=L2:L3=L2/L4:L6=L5/L7:BOTTOM=L7 |
| P12V_MOST6_GATE | 50OHM_Y12MIL | BUS | 6 | 6 | 5 | 10 | 5 | 14 | 6 | 15 | 12 | 12 | 12 | 12 |  | 50 Ohms-3 | TOP=L2:L3=L2/L4:L6=L5/L7:BOTTOM=L7 |
| P12V_MOST6_GATE | 50OHM_Y12MIL | BUS | 7 | 6 | 5 | 10 | 5 | 14 | 6 | 15 | 12 | 12 | 12 | 12 |  | 50 Ohms-3 | TOP=L2:L3=L2/L4:L6=L5/L7:BOTTOM=L7 |
| P12V_MOST6_GATE | 50OHM_Y12MIL | BUS | 8 | 6.75 | 5 | 10 | 5 | 14 | 6 | 15 | 12 | 12 | 12 | 12 |  | 50 Ohms-3 | TOP=L2:L3=L2/L4:L6=L5/L7:BOTTOM=L7 |
| P12V_MOST7_GATE | 50OHM_Y12MIL | BUS | 1 | 6.75 | 5 | 10 | 5 | 14 | 6 | 15 | 12 | 12 | 12 | 12 |  | 50 Ohms-3 | TOP=L2:L3=L2/L4:L6=L5/L7:BOTTOM=L7 |
| P12V_MOST7_GATE | 50OHM_Y12MIL | BUS | 2 | 6 | 5 | 10 | 5 | 14 | 6 | 15 | 12 | 12 | 12 | 12 |  | 50 Ohms-3 | TOP=L2:L3=L2/L4:L6=L5/L7:BOTTOM=L7 |
| P12V_MOST7_GATE | 50OHM_Y12MIL | BUS | 3 | 6 | 5 | 10 | 5 | 14 | 6 | 15 | 12 | 12 | 12 | 12 |  | 50 Ohms-3 | TOP=L2:L3=L2/L4:L6=L5/L7:BOTTOM=L7 |
| P12V_MOST7_GATE | 50OHM_Y12MIL | BUS | 4 | 6 | 5 | 10 | 5 | 14 | 6 | 15 | 12 | 12 | 12 | 12 |  | 50 Ohms-3 | TOP=L2:L3=L2/L4:L6=L5/L7:BOTTOM=L7 |
| P12V_MOST7_GATE | 50OHM_Y12MIL | BUS | 5 | 6 | 5 | 10 | 5 | 14 | 6 | 15 | 12 | 12 | 12 | 12 |  | 50 Ohms-3 | TOP=L2:L3=L2/L4:L6=L5/L7:BOTTOM=L7 |
| P12V_MOST7_GATE | 50OHM_Y12MIL | BUS | 6 | 6 | 5 | 10 | 5 | 14 | 6 | 15 | 12 | 12 | 12 | 12 |  | 50 Ohms-3 | TOP=L2:L3=L2/L4:L6=L5/L7:BOTTOM=L7 |
| P12V_MOST7_GATE | 50OHM_Y12MIL | BUS | 7 | 6 | 5 | 10 | 5 | 14 | 6 | 15 | 12 | 12 | 12 | 12 |  | 50 Ohms-3 | TOP=L2:L3=L2/L4:L6=L5/L7:BOTTOM=L7 |
| P12V_MOST7_GATE | 50OHM_Y12MIL | BUS | 8 | 6.75 | 5 | 10 | 5 | 14 | 6 | 15 | 12 | 12 | 12 | 12 |  | 50 Ohms-3 | TOP=L2:L3=L2/L4:L6=L5/L7:BOTTOM=L7 |
| P12V_MOST8_GATE | 50OHM_Y12MIL | BUS | 1 | 6.75 | 5 | 10 | 5 | 14 | 6 | 15 | 12 | 12 | 12 | 12 |  | 50 Ohms-3 | TOP=L2:L3=L2/L4:L6=L5/L7:BOTTOM=L7 |
| P12V_MOST8_GATE | 50OHM_Y12MIL | BUS | 2 | 6 | 5 | 10 | 5 | 14 | 6 | 15 | 12 | 12 | 12 | 12 |  | 50 Ohms-3 | TOP=L2:L3=L2/L4:L6=L5/L7:BOTTOM=L7 |
| P12V_MOST8_GATE | 50OHM_Y12MIL | BUS | 3 | 6 | 5 | 10 | 5 | 14 | 6 | 15 | 12 | 12 | 12 | 12 |  | 50 Ohms-3 | TOP=L2:L3=L2/L4:L6=L5/L7:BOTTOM=L7 |
| P12V_MOST8_GATE | 50OHM_Y12MIL | BUS | 4 | 6 | 5 | 10 | 5 | 14 | 6 | 15 | 12 | 12 | 12 | 12 |  | 50 Ohms-3 | TOP=L2:L3=L2/L4:L6=L5/L7:BOTTOM=L7 |
| P12V_MOST8_GATE | 50OHM_Y12MIL | BUS | 5 | 6 | 5 | 10 | 5 | 14 | 6 | 15 | 12 | 12 | 12 | 12 |  | 50 Ohms-3 | TOP=L2:L3=L2/L4:L6=L5/L7:BOTTOM=L7 |
| P12V_MOST8_GATE | 50OHM_Y12MIL | BUS | 6 | 6 | 5 | 10 | 5 | 14 | 6 | 15 | 12 | 12 | 12 | 12 |  | 50 Ohms-3 | TOP=L2:L3=L2/L4:L6=L5/L7:BOTTOM=L7 |
| P12V_MOST8_GATE | 50OHM_Y12MIL | BUS | 7 | 6 | 5 | 10 | 5 | 14 | 6 | 15 | 12 | 12 | 12 | 12 |  | 50 Ohms-3 | TOP=L2:L3=L2/L4:L6=L5/L7:BOTTOM=L7 |
| P12V_MOST8_GATE | 50OHM_Y12MIL | BUS | 8 | 6.75 | 5 | 10 | 5 | 14 | 6 | 15 | 12 | 12 | 12 | 12 |  | 50 Ohms-3 | TOP=L2:L3=L2/L4:L6=L5/L7:BOTTOM=L7 |
| P12V_MOST9_GATE | 50OHM_Y12MIL | BUS | 1 | 6.75 | 5 | 10 | 5 | 14 | 6 | 15 | 12 | 12 | 12 | 12 |  | 50 Ohms-3 | TOP=L2:L3=L2/L4:L6=L5/L7:BOTTOM=L7 |
| P12V_MOST9_GATE | 50OHM_Y12MIL | BUS | 2 | 6 | 5 | 10 | 5 | 14 | 6 | 15 | 12 | 12 | 12 | 12 |  | 50 Ohms-3 | TOP=L2:L3=L2/L4:L6=L5/L7:BOTTOM=L7 |
| P12V_MOST9_GATE | 50OHM_Y12MIL | BUS | 3 | 6 | 5 | 10 | 5 | 14 | 6 | 15 | 12 | 12 | 12 | 12 |  | 50 Ohms-3 | TOP=L2:L3=L2/L4:L6=L5/L7:BOTTOM=L7 |
| P12V_MOST9_GATE | 50OHM_Y12MIL | BUS | 4 | 6 | 5 | 10 | 5 | 14 | 6 | 15 | 12 | 12 | 12 | 12 |  | 50 Ohms-3 | TOP=L2:L3=L2/L4:L6=L5/L7:BOTTOM=L7 |
| P12V_MOST9_GATE | 50OHM_Y12MIL | BUS | 5 | 6 | 5 | 10 | 5 | 14 | 6 | 15 | 12 | 12 | 12 | 12 |  | 50 Ohms-3 | TOP=L2:L3=L2/L4:L6=L5/L7:BOTTOM=L7 |
| P12V_MOST9_GATE | 50OHM_Y12MIL | BUS | 6 | 6 | 5 | 10 | 5 | 14 | 6 | 15 | 12 | 12 | 12 | 12 |  | 50 Ohms-3 | TOP=L2:L3=L2/L4:L6=L5/L7:BOTTOM=L7 |
| P12V_MOST9_GATE | 50OHM_Y12MIL | BUS | 7 | 6 | 5 | 10 | 5 | 14 | 6 | 15 | 12 | 12 | 12 | 12 |  | 50 Ohms-3 | TOP=L2:L3=L2/L4:L6=L5/L7:BOTTOM=L7 |
| P12V_MOST9_GATE | 50OHM_Y12MIL | BUS | 8 | 6.75 | 5 | 10 | 5 | 14 | 6 | 15 | 12 | 12 | 12 | 12 |  | 50 Ohms-3 | TOP=L2:L3=L2/L4:L6=L5/L7:BOTTOM=L7 |
| PCIE_MATED#_A | 50OHM_Y12MIL | BUS | 1 | 6.75 | 5 | 10 | 5 | 14 | 6 | 15 | 12 | 12 | 12 | 12 |  | 50 Ohms-3 | TOP=L2:L3=L2/L4:L6=L5/L7:BOTTOM=L7 |
| PCIE_MATED#_A | 50OHM_Y12MIL | BUS | 2 | 6 | 5 | 10 | 5 | 14 | 6 | 15 | 12 | 12 | 12 | 12 |  | 50 Ohms-3 | TOP=L2:L3=L2/L4:L6=L5/L7:BOTTOM=L7 |
| PCIE_MATED#_A | 50OHM_Y12MIL | BUS | 3 | 6 | 5 | 10 | 5 | 14 | 6 | 15 | 12 | 12 | 12 | 12 |  | 50 Ohms-3 | TOP=L2:L3=L2/L4:L6=L5/L7:BOTTOM=L7 |
| PCIE_MATED#_A | 50OHM_Y12MIL | BUS | 4 | 6 | 5 | 10 | 5 | 14 | 6 | 15 | 12 | 12 | 12 | 12 |  | 50 Ohms-3 | TOP=L2:L3=L2/L4:L6=L5/L7:BOTTOM=L7 |
| PCIE_MATED#_A | 50OHM_Y12MIL | BUS | 5 | 6 | 5 | 10 | 5 | 14 | 6 | 15 | 12 | 12 | 12 | 12 |  | 50 Ohms-3 | TOP=L2:L3=L2/L4:L6=L5/L7:BOTTOM=L7 |
| PCIE_MATED#_A | 50OHM_Y12MIL | BUS | 6 | 6 | 5 | 10 | 5 | 14 | 6 | 15 | 12 | 12 | 12 | 12 |  | 50 Ohms-3 | TOP=L2:L3=L2/L4:L6=L5/L7:BOTTOM=L7 |
| PCIE_MATED#_A | 50OHM_Y12MIL | BUS | 7 | 6 | 5 | 10 | 5 | 14 | 6 | 15 | 12 | 12 | 12 | 12 |  | 50 Ohms-3 | TOP=L2:L3=L2/L4:L6=L5/L7:BOTTOM=L7 |
| PCIE_MATED#_A | 50OHM_Y12MIL | BUS | 8 | 6.75 | 5 | 10 | 5 | 14 | 6 | 15 | 12 | 12 | 12 | 12 |  | 50 Ohms-3 | TOP=L2:L3=L2/L4:L6=L5/L7:BOTTOM=L7 |
| PCIE_MATED#_B | 50OHM_Y12MIL | BUS | 1 | 6.75 | 5 | 10 | 5 | 14 | 6 | 15 | 12 | 12 | 12 | 12 |  | 50 Ohms-3 | TOP=L2:L3=L2/L4:L6=L5/L7:BOTTOM=L7 |
| PCIE_MATED#_B | 50OHM_Y12MIL | BUS | 2 | 6 | 5 | 10 | 5 | 14 | 6 | 15 | 12 | 12 | 12 | 12 |  | 50 Ohms-3 | TOP=L2:L3=L2/L4:L6=L5/L7:BOTTOM=L7 |
| PCIE_MATED#_B | 50OHM_Y12MIL | BUS | 3 | 6 | 5 | 10 | 5 | 14 | 6 | 15 | 12 | 12 | 12 | 12 |  | 50 Ohms-3 | TOP=L2:L3=L2/L4:L6=L5/L7:BOTTOM=L7 |
| PCIE_MATED#_B | 50OHM_Y12MIL | BUS | 4 | 6 | 5 | 10 | 5 | 14 | 6 | 15 | 12 | 12 | 12 | 12 |  | 50 Ohms-3 | TOP=L2:L3=L2/L4:L6=L5/L7:BOTTOM=L7 |
| PCIE_MATED#_B | 50OHM_Y12MIL | BUS | 5 | 6 | 5 | 10 | 5 | 14 | 6 | 15 | 12 | 12 | 12 | 12 |  | 50 Ohms-3 | TOP=L2:L3=L2/L4:L6=L5/L7:BOTTOM=L7 |
| PCIE_MATED#_B | 50OHM_Y12MIL | BUS | 6 | 6 | 5 | 10 | 5 | 14 | 6 | 15 | 12 | 12 | 12 | 12 |  | 50 Ohms-3 | TOP=L2:L3=L2/L4:L6=L5/L7:BOTTOM=L7 |
| PCIE_MATED#_B | 50OHM_Y12MIL | BUS | 7 | 6 | 5 | 10 | 5 | 14 | 6 | 15 | 12 | 12 | 12 | 12 |  | 50 Ohms-3 | TOP=L2:L3=L2/L4:L6=L5/L7:BOTTOM=L7 |
| PCIE_MATED#_B | 50OHM_Y12MIL | BUS | 8 | 6.75 | 5 | 10 | 5 | 14 | 6 | 15 | 12 | 12 | 12 | 12 |  | 50 Ohms-3 | TOP=L2:L3=L2/L4:L6=L5/L7:BOTTOM=L7 |
| PEER_1A&2A_HB | 50OHM_Y12MIL | BUS | 1 | 6.75 | 5 | 10 | 5 | 14 | 6 | 15 | 12 | 12 | 12 | 12 |  | 50 Ohms-3 | TOP=L2:L3=L2/L4:L6=L5/L7:BOTTOM=L7 |
| PEER_1A&2A_HB | 50OHM_Y12MIL | BUS | 2 | 6 | 5 | 10 | 5 | 14 | 6 | 15 | 12 | 12 | 12 | 12 |  | 50 Ohms-3 | TOP=L2:L3=L2/L4:L6=L5/L7:BOTTOM=L7 |
| PEER_1A&2A_HB | 50OHM_Y12MIL | BUS | 3 | 6 | 5 | 10 | 5 | 14 | 6 | 15 | 12 | 12 | 12 | 12 |  | 50 Ohms-3 | TOP=L2:L3=L2/L4:L6=L5/L7:BOTTOM=L7 |
| PEER_1A&2A_HB | 50OHM_Y12MIL | BUS | 4 | 6 | 5 | 10 | 5 | 14 | 6 | 15 | 12 | 12 | 12 | 12 |  | 50 Ohms-3 | TOP=L2:L3=L2/L4:L6=L5/L7:BOTTOM=L7 |
| PEER_1A&2A_HB | 50OHM_Y12MIL | BUS | 5 | 6 | 5 | 10 | 5 | 14 | 6 | 15 | 12 | 12 | 12 | 12 |  | 50 Ohms-3 | TOP=L2:L3=L2/L4:L6=L5/L7:BOTTOM=L7 |
| PEER_1A&2A_HB | 50OHM_Y12MIL | BUS | 6 | 6 | 5 | 10 | 5 | 14 | 6 | 15 | 12 | 12 | 12 | 12 |  | 50 Ohms-3 | TOP=L2:L3=L2/L4:L6=L5/L7:BOTTOM=L7 |
| PEER_1A&2A_HB | 50OHM_Y12MIL | BUS | 7 | 6 | 5 | 10 | 5 | 14 | 6 | 15 | 12 | 12 | 12 | 12 |  | 50 Ohms-3 | TOP=L2:L3=L2/L4:L6=L5/L7:BOTTOM=L7 |
| PEER_1A&2A_HB | 50OHM_Y12MIL | BUS | 8 | 6.75 | 5 | 10 | 5 | 14 | 6 | 15 | 12 | 12 | 12 | 12 |  | 50 Ohms-3 | TOP=L2:L3=L2/L4:L6=L5/L7:BOTTOM=L7 |
| PEER_TRAY_PRESENT | 50OHM_Y12MIL | BUS | 1 | 6.75 | 5 | 10 | 5 | 14 | 6 | 15 | 12 | 12 | 12 | 12 |  | 50 Ohms-3 | TOP=L2:L3=L2/L4:L6=L5/L7:BOTTOM=L7 |
| PEER_TRAY_PRESENT | 50OHM_Y12MIL | BUS | 2 | 6 | 5 | 10 | 5 | 14 | 6 | 15 | 12 | 12 | 12 | 12 |  | 50 Ohms-3 | TOP=L2:L3=L2/L4:L6=L5/L7:BOTTOM=L7 |
| PEER_TRAY_PRESENT | 50OHM_Y12MIL | BUS | 3 | 6 | 5 | 10 | 5 | 14 | 6 | 15 | 12 | 12 | 12 | 12 |  | 50 Ohms-3 | TOP=L2:L3=L2/L4:L6=L5/L7:BOTTOM=L7 |
| PEER_TRAY_PRESENT | 50OHM_Y12MIL | BUS | 4 | 6 | 5 | 10 | 5 | 14 | 6 | 15 | 12 | 12 | 12 | 12 |  | 50 Ohms-3 | TOP=L2:L3=L2/L4:L6=L5/L7:BOTTOM=L7 |
| PEER_TRAY_PRESENT | 50OHM_Y12MIL | BUS | 5 | 6 | 5 | 10 | 5 | 14 | 6 | 15 | 12 | 12 | 12 | 12 |  | 50 Ohms-3 | TOP=L2:L3=L2/L4:L6=L5/L7:BOTTOM=L7 |
| PEER_TRAY_PRESENT | 50OHM_Y12MIL | BUS | 6 | 6 | 5 | 10 | 5 | 14 | 6 | 15 | 12 | 12 | 12 | 12 |  | 50 Ohms-3 | TOP=L2:L3=L2/L4:L6=L5/L7:BOTTOM=L7 |
| PEER_TRAY_PRESENT | 50OHM_Y12MIL | BUS | 7 | 6 | 5 | 10 | 5 | 14 | 6 | 15 | 12 | 12 | 12 | 12 |  | 50 Ohms-3 | TOP=L2:L3=L2/L4:L6=L5/L7:BOTTOM=L7 |
| PEER_TRAY_PRESENT | 50OHM_Y12MIL | BUS | 8 | 6.75 | 5 | 10 | 5 | 14 | 6 | 15 | 12 | 12 | 12 | 12 |  | 50 Ohms-3 | TOP=L2:L3=L2/L4:L6=L5/L7:BOTTOM=L7 |
| PWM_EXP_A | 50OHM_Y12MIL | BUS | 1 | 6.75 | 5 | 10 | 5 | 14 | 6 | 15 | 12 | 12 | 12 | 12 |  | 50 Ohms-3 | TOP=L2:L3=L2/L4:L6=L5/L7:BOTTOM=L7 |
| PWM_EXP_A | 50OHM_Y12MIL | BUS | 2 | 6 | 5 | 10 | 5 | 14 | 6 | 15 | 12 | 12 | 12 | 12 |  | 50 Ohms-3 | TOP=L2:L3=L2/L4:L6=L5/L7:BOTTOM=L7 |
| PWM_EXP_A | 50OHM_Y12MIL | BUS | 3 | 6 | 5 | 10 | 5 | 14 | 6 | 15 | 12 | 12 | 12 | 12 |  | 50 Ohms-3 | TOP=L2:L3=L2/L4:L6=L5/L7:BOTTOM=L7 |
| PWM_EXP_A | 50OHM_Y12MIL | BUS | 4 | 6 | 5 | 10 | 5 | 14 | 6 | 15 | 12 | 12 | 12 | 12 |  | 50 Ohms-3 | TOP=L2:L3=L2/L4:L6=L5/L7:BOTTOM=L7 |
| PWM_EXP_A | 50OHM_Y12MIL | BUS | 5 | 6 | 5 | 10 | 5 | 14 | 6 | 15 | 12 | 12 | 12 | 12 |  | 50 Ohms-3 | TOP=L2:L3=L2/L4:L6=L5/L7:BOTTOM=L7 |
| PWM_EXP_A | 50OHM_Y12MIL | BUS | 6 | 6 | 5 | 10 | 5 | 14 | 6 | 15 | 12 | 12 | 12 | 12 |  | 50 Ohms-3 | TOP=L2:L3=L2/L4:L6=L5/L7:BOTTOM=L7 |
| PWM_EXP_A | 50OHM_Y12MIL | BUS | 7 | 6 | 5 | 10 | 5 | 14 | 6 | 15 | 12 | 12 | 12 | 12 |  | 50 Ohms-3 | TOP=L2:L3=L2/L4:L6=L5/L7:BOTTOM=L7 |
| PWM_EXP_A | 50OHM_Y12MIL | BUS | 8 | 6.75 | 5 | 10 | 5 | 14 | 6 | 15 | 12 | 12 | 12 | 12 |  | 50 Ohms-3 | TOP=L2:L3=L2/L4:L6=L5/L7:BOTTOM=L7 |
| SD_LATCH_RELEASE | 50OHM_Y12MIL | BUS | 1 | 6.75 | 5 | 10 | 5 | 14 | 6 | 15 | 12 | 12 | 12 | 12 |  | 50 Ohms-3 | TOP=L2:L3=L2/L4:L6=L5/L7:BOTTOM=L7 |
| SD_LATCH_RELEASE | 50OHM_Y12MIL | BUS | 2 | 6 | 5 | 10 | 5 | 14 | 6 | 15 | 12 | 12 | 12 | 12 |  | 50 Ohms-3 | TOP=L2:L3=L2/L4:L6=L5/L7:BOTTOM=L7 |
| SD_LATCH_RELEASE | 50OHM_Y12MIL | BUS | 3 | 6 | 5 | 10 | 5 | 14 | 6 | 15 | 12 | 12 | 12 | 12 |  | 50 Ohms-3 | TOP=L2:L3=L2/L4:L6=L5/L7:BOTTOM=L7 |
| SD_LATCH_RELEASE | 50OHM_Y12MIL | BUS | 4 | 6 | 5 | 10 | 5 | 14 | 6 | 15 | 12 | 12 | 12 | 12 |  | 50 Ohms-3 | TOP=L2:L3=L2/L4:L6=L5/L7:BOTTOM=L7 |
| SD_LATCH_RELEASE | 50OHM_Y12MIL | BUS | 5 | 6 | 5 | 10 | 5 | 14 | 6 | 15 | 12 | 12 | 12 | 12 |  | 50 Ohms-3 | TOP=L2:L3=L2/L4:L6=L5/L7:BOTTOM=L7 |
| SD_LATCH_RELEASE | 50OHM_Y12MIL | BUS | 6 | 6 | 5 | 10 | 5 | 14 | 6 | 15 | 12 | 12 | 12 | 12 |  | 50 Ohms-3 | TOP=L2:L3=L2/L4:L6=L5/L7:BOTTOM=L7 |
| SD_LATCH_RELEASE | 50OHM_Y12MIL | BUS | 7 | 6 | 5 | 10 | 5 | 14 | 6 | 15 | 12 | 12 | 12 | 12 |  | 50 Ohms-3 | TOP=L2:L3=L2/L4:L6=L5/L7:BOTTOM=L7 |
| SD_LATCH_RELEASE | 50OHM_Y12MIL | BUS | 8 | 6.75 | 5 | 10 | 5 | 14 | 6 | 15 | 12 | 12 | 12 | 12 |  | 50 Ohms-3 | TOP=L2:L3=L2/L4:L6=L5/L7:BOTTOM=L7 |
| SD_LATCH_RELEASE_R | 50OHM_Y12MIL | BUS | 1 | 6.75 | 5 | 10 | 5 | 14 | 6 | 15 | 12 | 12 | 12 | 12 |  | 50 Ohms-3 | TOP=L2:L3=L2/L4:L6=L5/L7:BOTTOM=L7 |
| SD_LATCH_RELEASE_R | 50OHM_Y12MIL | BUS | 2 | 6 | 5 | 10 | 5 | 14 | 6 | 15 | 12 | 12 | 12 | 12 |  | 50 Ohms-3 | TOP=L2:L3=L2/L4:L6=L5/L7:BOTTOM=L7 |
| SD_LATCH_RELEASE_R | 50OHM_Y12MIL | BUS | 3 | 6 | 5 | 10 | 5 | 14 | 6 | 15 | 12 | 12 | 12 | 12 |  | 50 Ohms-3 | TOP=L2:L3=L2/L4:L6=L5/L7:BOTTOM=L7 |
| SD_LATCH_RELEASE_R | 50OHM_Y12MIL | BUS | 4 | 6 | 5 | 10 | 5 | 14 | 6 | 15 | 12 | 12 | 12 | 12 |  | 50 Ohms-3 | TOP=L2:L3=L2/L4:L6=L5/L7:BOTTOM=L7 |
| SD_LATCH_RELEASE_R | 50OHM_Y12MIL | BUS | 5 | 6 | 5 | 10 | 5 | 14 | 6 | 15 | 12 | 12 | 12 | 12 |  | 50 Ohms-3 | TOP=L2:L3=L2/L4:L6=L5/L7:BOTTOM=L7 |
| SD_LATCH_RELEASE_R | 50OHM_Y12MIL | BUS | 6 | 6 | 5 | 10 | 5 | 14 | 6 | 15 | 12 | 12 | 12 | 12 |  | 50 Ohms-3 | TOP=L2:L3=L2/L4:L6=L5/L7:BOTTOM=L7 |
| SD_LATCH_RELEASE_R | 50OHM_Y12MIL | BUS | 7 | 6 | 5 | 10 | 5 | 14 | 6 | 15 | 12 | 12 | 12 | 12 |  | 50 Ohms-3 | TOP=L2:L3=L2/L4:L6=L5/L7:BOTTOM=L7 |
| SD_LATCH_RELEASE_R | 50OHM_Y12MIL | BUS | 8 | 6.75 | 5 | 10 | 5 | 14 | 6 | 15 | 12 | 12 | 12 | 12 |  | 50 Ohms-3 | TOP=L2:L3=L2/L4:L6=L5/L7:BOTTOM=L7 |
| SELF_1A&2A_HB | 50OHM_Y12MIL | BUS | 1 | 6.75 | 5 | 10 | 5 | 14 | 6 | 15 | 12 | 12 | 12 | 12 |  | 50 Ohms-3 | TOP=L2:L3=L2/L4:L6=L5/L7:BOTTOM=L7 |
| SELF_1A&2A_HB | 50OHM_Y12MIL | BUS | 2 | 6 | 5 | 10 | 5 | 14 | 6 | 15 | 12 | 12 | 12 | 12 |  | 50 Ohms-3 | TOP=L2:L3=L2/L4:L6=L5/L7:BOTTOM=L7 |
| SELF_1A&2A_HB | 50OHM_Y12MIL | BUS | 3 | 6 | 5 | 10 | 5 | 14 | 6 | 15 | 12 | 12 | 12 | 12 |  | 50 Ohms-3 | TOP=L2:L3=L2/L4:L6=L5/L7:BOTTOM=L7 |
| SELF_1A&2A_HB | 50OHM_Y12MIL | BUS | 4 | 6 | 5 | 10 | 5 | 14 | 6 | 15 | 12 | 12 | 12 | 12 |  | 50 Ohms-3 | TOP=L2:L3=L2/L4:L6=L5/L7:BOTTOM=L7 |
| SELF_1A&2A_HB | 50OHM_Y12MIL | BUS | 5 | 6 | 5 | 10 | 5 | 14 | 6 | 15 | 12 | 12 | 12 | 12 |  | 50 Ohms-3 | TOP=L2:L3=L2/L4:L6=L5/L7:BOTTOM=L7 |
| SELF_1A&2A_HB | 50OHM_Y12MIL | BUS | 6 | 6 | 5 | 10 | 5 | 14 | 6 | 15 | 12 | 12 | 12 | 12 |  | 50 Ohms-3 | TOP=L2:L3=L2/L4:L6=L5/L7:BOTTOM=L7 |
| SELF_1A&2A_HB | 50OHM_Y12MIL | BUS | 7 | 6 | 5 | 10 | 5 | 14 | 6 | 15 | 12 | 12 | 12 | 12 |  | 50 Ohms-3 | TOP=L2:L3=L2/L4:L6=L5/L7:BOTTOM=L7 |
| SELF_1A&2A_HB | 50OHM_Y12MIL | BUS | 8 | 6.75 | 5 | 10 | 5 | 14 | 6 | 15 | 12 | 12 | 12 | 12 |  | 50 Ohms-3 | TOP=L2:L3=L2/L4:L6=L5/L7:BOTTOM=L7 |
| SELF_TRAY_PRESENT | 50OHM_Y12MIL | BUS | 1 | 6.75 | 5 | 10 | 5 | 14 | 6 | 15 | 12 | 12 | 12 | 12 |  | 50 Ohms-3 | TOP=L2:L3=L2/L4:L6=L5/L7:BOTTOM=L7 |
| SELF_TRAY_PRESENT | 50OHM_Y12MIL | BUS | 2 | 6 | 5 | 10 | 5 | 14 | 6 | 15 | 12 | 12 | 12 | 12 |  | 50 Ohms-3 | TOP=L2:L3=L2/L4:L6=L5/L7:BOTTOM=L7 |
| SELF_TRAY_PRESENT | 50OHM_Y12MIL | BUS | 3 | 6 | 5 | 10 | 5 | 14 | 6 | 15 | 12 | 12 | 12 | 12 |  | 50 Ohms-3 | TOP=L2:L3=L2/L4:L6=L5/L7:BOTTOM=L7 |
| SELF_TRAY_PRESENT | 50OHM_Y12MIL | BUS | 4 | 6 | 5 | 10 | 5 | 14 | 6 | 15 | 12 | 12 | 12 | 12 |  | 50 Ohms-3 | TOP=L2:L3=L2/L4:L6=L5/L7:BOTTOM=L7 |
| SELF_TRAY_PRESENT | 50OHM_Y12MIL | BUS | 5 | 6 | 5 | 10 | 5 | 14 | 6 | 15 | 12 | 12 | 12 | 12 |  | 50 Ohms-3 | TOP=L2:L3=L2/L4:L6=L5/L7:BOTTOM=L7 |
| SELF_TRAY_PRESENT | 50OHM_Y12MIL | BUS | 6 | 6 | 5 | 10 | 5 | 14 | 6 | 15 | 12 | 12 | 12 | 12 |  | 50 Ohms-3 | TOP=L2:L3=L2/L4:L6=L5/L7:BOTTOM=L7 |
| SELF_TRAY_PRESENT | 50OHM_Y12MIL | BUS | 7 | 6 | 5 | 10 | 5 | 14 | 6 | 15 | 12 | 12 | 12 | 12 |  | 50 Ohms-3 | TOP=L2:L3=L2/L4:L6=L5/L7:BOTTOM=L7 |
| SELF_TRAY_PRESENT | 50OHM_Y12MIL | BUS | 8 | 6.75 | 5 | 10 | 5 | 14 | 6 | 15 | 12 | 12 | 12 | 12 |  | 50 Ohms-3 | TOP=L2:L3=L2/L4:L6=L5/L7:BOTTOM=L7 |
| SELF_TRAY_PRESENT_R | 50OHM_Y12MIL | BUS | 1 | 6.75 | 5 | 10 | 5 | 14 | 6 | 15 | 12 | 12 | 12 | 12 |  | 50 Ohms-3 | TOP=L2:L3=L2/L4:L6=L5/L7:BOTTOM=L7 |
| SELF_TRAY_PRESENT_R | 50OHM_Y12MIL | BUS | 2 | 6 | 5 | 10 | 5 | 14 | 6 | 15 | 12 | 12 | 12 | 12 |  | 50 Ohms-3 | TOP=L2:L3=L2/L4:L6=L5/L7:BOTTOM=L7 |
| SELF_TRAY_PRESENT_R | 50OHM_Y12MIL | BUS | 3 | 6 | 5 | 10 | 5 | 14 | 6 | 15 | 12 | 12 | 12 | 12 |  | 50 Ohms-3 | TOP=L2:L3=L2/L4:L6=L5/L7:BOTTOM=L7 |
| SELF_TRAY_PRESENT_R | 50OHM_Y12MIL | BUS | 4 | 6 | 5 | 10 | 5 | 14 | 6 | 15 | 12 | 12 | 12 | 12 |  | 50 Ohms-3 | TOP=L2:L3=L2/L4:L6=L5/L7:BOTTOM=L7 |
| SELF_TRAY_PRESENT_R | 50OHM_Y12MIL | BUS | 5 | 6 | 5 | 10 | 5 | 14 | 6 | 15 | 12 | 12 | 12 | 12 |  | 50 Ohms-3 | TOP=L2:L3=L2/L4:L6=L5/L7:BOTTOM=L7 |
| SELF_TRAY_PRESENT_R | 50OHM_Y12MIL | BUS | 6 | 6 | 5 | 10 | 5 | 14 | 6 | 15 | 12 | 12 | 12 | 12 |  | 50 Ohms-3 | TOP=L2:L3=L2/L4:L6=L5/L7:BOTTOM=L7 |
| SELF_TRAY_PRESENT_R | 50OHM_Y12MIL | BUS | 7 | 6 | 5 | 10 | 5 | 14 | 6 | 15 | 12 | 12 | 12 | 12 |  | 50 Ohms-3 | TOP=L2:L3=L2/L4:L6=L5/L7:BOTTOM=L7 |
| SELF_TRAY_PRESENT_R | 50OHM_Y12MIL | BUS | 8 | 6.75 | 5 | 10 | 5 | 14 | 6 | 15 | 12 | 12 | 12 | 12 |  | 50 Ohms-3 | TOP=L2:L3=L2/L4:L6=L5/L7:BOTTOM=L7 |
| SSD_ACT_DR0 | 50OHM_Y12MIL | BUS | 1 | 6.75 | 5 | 10 | 5 | 14 | 6 | 15 | 12 | 12 | 12 | 12 |  | 50 Ohms-3 | TOP=L2:L3=L2/L4:L6=L5/L7:BOTTOM=L7 |
| SSD_ACT_DR0 | 50OHM_Y12MIL | BUS | 2 | 6 | 5 | 10 | 5 | 14 | 6 | 15 | 12 | 12 | 12 | 12 |  | 50 Ohms-3 | TOP=L2:L3=L2/L4:L6=L5/L7:BOTTOM=L7 |
| SSD_ACT_DR0 | 50OHM_Y12MIL | BUS | 3 | 6 | 5 | 10 | 5 | 14 | 6 | 15 | 12 | 12 | 12 | 12 |  | 50 Ohms-3 | TOP=L2:L3=L2/L4:L6=L5/L7:BOTTOM=L7 |
| SSD_ACT_DR0 | 50OHM_Y12MIL | BUS | 4 | 6 | 5 | 10 | 5 | 14 | 6 | 15 | 12 | 12 | 12 | 12 |  | 50 Ohms-3 | TOP=L2:L3=L2/L4:L6=L5/L7:BOTTOM=L7 |
| SSD_ACT_DR0 | 50OHM_Y12MIL | BUS | 5 | 6 | 5 | 10 | 5 | 14 | 6 | 15 | 12 | 12 | 12 | 12 |  | 50 Ohms-3 | TOP=L2:L3=L2/L4:L6=L5/L7:BOTTOM=L7 |
| SSD_ACT_DR0 | 50OHM_Y12MIL | BUS | 6 | 6 | 5 | 10 | 5 | 14 | 6 | 15 | 12 | 12 | 12 | 12 |  | 50 Ohms-3 | TOP=L2:L3=L2/L4:L6=L5/L7:BOTTOM=L7 |
| SSD_ACT_DR0 | 50OHM_Y12MIL | BUS | 7 | 6 | 5 | 10 | 5 | 14 | 6 | 15 | 12 | 12 | 12 | 12 |  | 50 Ohms-3 | TOP=L2:L3=L2/L4:L6=L5/L7:BOTTOM=L7 |
| SSD_ACT_DR0 | 50OHM_Y12MIL | BUS | 8 | 6.75 | 5 | 10 | 5 | 14 | 6 | 15 | 12 | 12 | 12 | 12 |  | 50 Ohms-3 | TOP=L2:L3=L2/L4:L6=L5/L7:BOTTOM=L7 |
| SSD_ACT_DR0_MOS_N | 50OHM_Y12MIL | BUS | 1 | 6.75 | 5 | 10 | 5 | 14 | 6 | 15 | 12 | 12 | 12 | 12 |  | 50 Ohms-3 | TOP=L2:L3=L2/L4:L6=L5/L7:BOTTOM=L7 |
| SSD_ACT_DR0_MOS_N | 50OHM_Y12MIL | BUS | 2 | 6 | 5 | 10 | 5 | 14 | 6 | 15 | 12 | 12 | 12 | 12 |  | 50 Ohms-3 | TOP=L2:L3=L2/L4:L6=L5/L7:BOTTOM=L7 |
| SSD_ACT_DR0_MOS_N | 50OHM_Y12MIL | BUS | 3 | 6 | 5 | 10 | 5 | 14 | 6 | 15 | 12 | 12 | 12 | 12 |  | 50 Ohms-3 | TOP=L2:L3=L2/L4:L6=L5/L7:BOTTOM=L7 |
| SSD_ACT_DR0_MOS_N | 50OHM_Y12MIL | BUS | 4 | 6 | 5 | 10 | 5 | 14 | 6 | 15 | 12 | 12 | 12 | 12 |  | 50 Ohms-3 | TOP=L2:L3=L2/L4:L6=L5/L7:BOTTOM=L7 |
| SSD_ACT_DR0_MOS_N | 50OHM_Y12MIL | BUS | 5 | 6 | 5 | 10 | 5 | 14 | 6 | 15 | 12 | 12 | 12 | 12 |  | 50 Ohms-3 | TOP=L2:L3=L2/L4:L6=L5/L7:BOTTOM=L7 |
| SSD_ACT_DR0_MOS_N | 50OHM_Y12MIL | BUS | 6 | 6 | 5 | 10 | 5 | 14 | 6 | 15 | 12 | 12 | 12 | 12 |  | 50 Ohms-3 | TOP=L2:L3=L2/L4:L6=L5/L7:BOTTOM=L7 |
| SSD_ACT_DR0_MOS_N | 50OHM_Y12MIL | BUS | 7 | 6 | 5 | 10 | 5 | 14 | 6 | 15 | 12 | 12 | 12 | 12 |  | 50 Ohms-3 | TOP=L2:L3=L2/L4:L6=L5/L7:BOTTOM=L7 |
| SSD_ACT_DR0_MOS_N | 50OHM_Y12MIL | BUS | 8 | 6.75 | 5 | 10 | 5 | 14 | 6 | 15 | 12 | 12 | 12 | 12 |  | 50 Ohms-3 | TOP=L2:L3=L2/L4:L6=L5/L7:BOTTOM=L7 |
| SSD_ACT_DR0_R | 50OHM_Y12MIL | BUS | 1 | 6.75 | 5 | 10 | 5 | 14 | 6 | 15 | 12 | 12 | 12 | 12 |  | 50 Ohms-3 | TOP=L2:L3=L2/L4:L6=L5/L7:BOTTOM=L7 |
| SSD_ACT_DR0_R | 50OHM_Y12MIL | BUS | 2 | 6 | 5 | 10 | 5 | 14 | 6 | 15 | 12 | 12 | 12 | 12 |  | 50 Ohms-3 | TOP=L2:L3=L2/L4:L6=L5/L7:BOTTOM=L7 |
| SSD_ACT_DR0_R | 50OHM_Y12MIL | BUS | 3 | 6 | 5 | 10 | 5 | 14 | 6 | 15 | 12 | 12 | 12 | 12 |  | 50 Ohms-3 | TOP=L2:L3=L2/L4:L6=L5/L7:BOTTOM=L7 |
| SSD_ACT_DR0_R | 50OHM_Y12MIL | BUS | 4 | 6 | 5 | 10 | 5 | 14 | 6 | 15 | 12 | 12 | 12 | 12 |  | 50 Ohms-3 | TOP=L2:L3=L2/L4:L6=L5/L7:BOTTOM=L7 |
| SSD_ACT_DR0_R | 50OHM_Y12MIL | BUS | 5 | 6 | 5 | 10 | 5 | 14 | 6 | 15 | 12 | 12 | 12 | 12 |  | 50 Ohms-3 | TOP=L2:L3=L2/L4:L6=L5/L7:BOTTOM=L7 |
| SSD_ACT_DR0_R | 50OHM_Y12MIL | BUS | 6 | 6 | 5 | 10 | 5 | 14 | 6 | 15 | 12 | 12 | 12 | 12 |  | 50 Ohms-3 | TOP=L2:L3=L2/L4:L6=L5/L7:BOTTOM=L7 |
| SSD_ACT_DR0_R | 50OHM_Y12MIL | BUS | 7 | 6 | 5 | 10 | 5 | 14 | 6 | 15 | 12 | 12 | 12 | 12 |  | 50 Ohms-3 | TOP=L2:L3=L2/L4:L6=L5/L7:BOTTOM=L7 |
| SSD_ACT_DR0_R | 50OHM_Y12MIL | BUS | 8 | 6.75 | 5 | 10 | 5 | 14 | 6 | 15 | 12 | 12 | 12 | 12 |  | 50 Ohms-3 | TOP=L2:L3=L2/L4:L6=L5/L7:BOTTOM=L7 |
| SSD_ACT_DR1 | 50OHM_Y12MIL | BUS | 1 | 6.75 | 5 | 10 | 5 | 14 | 6 | 15 | 12 | 12 | 12 | 12 |  | 50 Ohms-3 | TOP=L2:L3=L2/L4:L6=L5/L7:BOTTOM=L7 |
| SSD_ACT_DR1 | 50OHM_Y12MIL | BUS | 2 | 6 | 5 | 10 | 5 | 14 | 6 | 15 | 12 | 12 | 12 | 12 |  | 50 Ohms-3 | TOP=L2:L3=L2/L4:L6=L5/L7:BOTTOM=L7 |
| SSD_ACT_DR1 | 50OHM_Y12MIL | BUS | 3 | 6 | 5 | 10 | 5 | 14 | 6 | 15 | 12 | 12 | 12 | 12 |  | 50 Ohms-3 | TOP=L2:L3=L2/L4:L6=L5/L7:BOTTOM=L7 |
| SSD_ACT_DR1 | 50OHM_Y12MIL | BUS | 4 | 6 | 5 | 10 | 5 | 14 | 6 | 15 | 12 | 12 | 12 | 12 |  | 50 Ohms-3 | TOP=L2:L3=L2/L4:L6=L5/L7:BOTTOM=L7 |
| SSD_ACT_DR1 | 50OHM_Y12MIL | BUS | 5 | 6 | 5 | 10 | 5 | 14 | 6 | 15 | 12 | 12 | 12 | 12 |  | 50 Ohms-3 | TOP=L2:L3=L2/L4:L6=L5/L7:BOTTOM=L7 |
| SSD_ACT_DR1 | 50OHM_Y12MIL | BUS | 6 | 6 | 5 | 10 | 5 | 14 | 6 | 15 | 12 | 12 | 12 | 12 |  | 50 Ohms-3 | TOP=L2:L3=L2/L4:L6=L5/L7:BOTTOM=L7 |
| SSD_ACT_DR1 | 50OHM_Y12MIL | BUS | 7 | 6 | 5 | 10 | 5 | 14 | 6 | 15 | 12 | 12 | 12 | 12 |  | 50 Ohms-3 | TOP=L2:L3=L2/L4:L6=L5/L7:BOTTOM=L7 |
| SSD_ACT_DR1 | 50OHM_Y12MIL | BUS | 8 | 6.75 | 5 | 10 | 5 | 14 | 6 | 15 | 12 | 12 | 12 | 12 |  | 50 Ohms-3 | TOP=L2:L3=L2/L4:L6=L5/L7:BOTTOM=L7 |
| SSD_ACT_DR1_MOS_N | 50OHM_Y12MIL | BUS | 1 | 6.75 | 5 | 10 | 5 | 14 | 6 | 15 | 12 | 12 | 12 | 12 |  | 50 Ohms-3 | TOP=L2:L3=L2/L4:L6=L5/L7:BOTTOM=L7 |
| SSD_ACT_DR1_MOS_N | 50OHM_Y12MIL | BUS | 2 | 6 | 5 | 10 | 5 | 14 | 6 | 15 | 12 | 12 | 12 | 12 |  | 50 Ohms-3 | TOP=L2:L3=L2/L4:L6=L5/L7:BOTTOM=L7 |
| SSD_ACT_DR1_MOS_N | 50OHM_Y12MIL | BUS | 3 | 6 | 5 | 10 | 5 | 14 | 6 | 15 | 12 | 12 | 12 | 12 |  | 50 Ohms-3 | TOP=L2:L3=L2/L4:L6=L5/L7:BOTTOM=L7 |
| SSD_ACT_DR1_MOS_N | 50OHM_Y12MIL | BUS | 4 | 6 | 5 | 10 | 5 | 14 | 6 | 15 | 12 | 12 | 12 | 12 |  | 50 Ohms-3 | TOP=L2:L3=L2/L4:L6=L5/L7:BOTTOM=L7 |
| SSD_ACT_DR1_MOS_N | 50OHM_Y12MIL | BUS | 5 | 6 | 5 | 10 | 5 | 14 | 6 | 15 | 12 | 12 | 12 | 12 |  | 50 Ohms-3 | TOP=L2:L3=L2/L4:L6=L5/L7:BOTTOM=L7 |
| SSD_ACT_DR1_MOS_N | 50OHM_Y12MIL | BUS | 6 | 6 | 5 | 10 | 5 | 14 | 6 | 15 | 12 | 12 | 12 | 12 |  | 50 Ohms-3 | TOP=L2:L3=L2/L4:L6=L5/L7:BOTTOM=L7 |
| SSD_ACT_DR1_MOS_N | 50OHM_Y12MIL | BUS | 7 | 6 | 5 | 10 | 5 | 14 | 6 | 15 | 12 | 12 | 12 | 12 |  | 50 Ohms-3 | TOP=L2:L3=L2/L4:L6=L5/L7:BOTTOM=L7 |
| SSD_ACT_DR1_MOS_N | 50OHM_Y12MIL | BUS | 8 | 6.75 | 5 | 10 | 5 | 14 | 6 | 15 | 12 | 12 | 12 | 12 |  | 50 Ohms-3 | TOP=L2:L3=L2/L4:L6=L5/L7:BOTTOM=L7 |
| SSD_ACT_DR1_R | 50OHM_Y12MIL | BUS | 1 | 6.75 | 5 | 10 | 5 | 14 | 6 | 15 | 12 | 12 | 12 | 12 |  | 50 Ohms-3 | TOP=L2:L3=L2/L4:L6=L5/L7:BOTTOM=L7 |
| SSD_ACT_DR1_R | 50OHM_Y12MIL | BUS | 2 | 6 | 5 | 10 | 5 | 14 | 6 | 15 | 12 | 12 | 12 | 12 |  | 50 Ohms-3 | TOP=L2:L3=L2/L4:L6=L5/L7:BOTTOM=L7 |
| SSD_ACT_DR1_R | 50OHM_Y12MIL | BUS | 3 | 6 | 5 | 10 | 5 | 14 | 6 | 15 | 12 | 12 | 12 | 12 |  | 50 Ohms-3 | TOP=L2:L3=L2/L4:L6=L5/L7:BOTTOM=L7 |
| SSD_ACT_DR1_R | 50OHM_Y12MIL | BUS | 4 | 6 | 5 | 10 | 5 | 14 | 6 | 15 | 12 | 12 | 12 | 12 |  | 50 Ohms-3 | TOP=L2:L3=L2/L4:L6=L5/L7:BOTTOM=L7 |
| SSD_ACT_DR1_R | 50OHM_Y12MIL | BUS | 5 | 6 | 5 | 10 | 5 | 14 | 6 | 15 | 12 | 12 | 12 | 12 |  | 50 Ohms-3 | TOP=L2:L3=L2/L4:L6=L5/L7:BOTTOM=L7 |
| SSD_ACT_DR1_R | 50OHM_Y12MIL | BUS | 6 | 6 | 5 | 10 | 5 | 14 | 6 | 15 | 12 | 12 | 12 | 12 |  | 50 Ohms-3 | TOP=L2:L3=L2/L4:L6=L5/L7:BOTTOM=L7 |
| SSD_ACT_DR1_R | 50OHM_Y12MIL | BUS | 7 | 6 | 5 | 10 | 5 | 14 | 6 | 15 | 12 | 12 | 12 | 12 |  | 50 Ohms-3 | TOP=L2:L3=L2/L4:L6=L5/L7:BOTTOM=L7 |
| SSD_ACT_DR1_R | 50OHM_Y12MIL | BUS | 8 | 6.75 | 5 | 10 | 5 | 14 | 6 | 15 | 12 | 12 | 12 | 12 |  | 50 Ohms-3 | TOP=L2:L3=L2/L4:L6=L5/L7:BOTTOM=L7 |
| SSD_ACT_DR10 | 50OHM_Y12MIL | BUS | 1 | 6.75 | 5 | 10 | 5 | 14 | 6 | 15 | 12 | 12 | 12 | 12 |  | 50 Ohms-3 | TOP=L2:L3=L2/L4:L6=L5/L7:BOTTOM=L7 |
| SSD_ACT_DR10 | 50OHM_Y12MIL | BUS | 2 | 6 | 5 | 10 | 5 | 14 | 6 | 15 | 12 | 12 | 12 | 12 |  | 50 Ohms-3 | TOP=L2:L3=L2/L4:L6=L5/L7:BOTTOM=L7 |
| SSD_ACT_DR10 | 50OHM_Y12MIL | BUS | 3 | 6 | 5 | 10 | 5 | 14 | 6 | 15 | 12 | 12 | 12 | 12 |  | 50 Ohms-3 | TOP=L2:L3=L2/L4:L6=L5/L7:BOTTOM=L7 |
| SSD_ACT_DR10 | 50OHM_Y12MIL | BUS | 4 | 6 | 5 | 10 | 5 | 14 | 6 | 15 | 12 | 12 | 12 | 12 |  | 50 Ohms-3 | TOP=L2:L3=L2/L4:L6=L5/L7:BOTTOM=L7 |
| SSD_ACT_DR10 | 50OHM_Y12MIL | BUS | 5 | 6 | 5 | 10 | 5 | 14 | 6 | 15 | 12 | 12 | 12 | 12 |  | 50 Ohms-3 | TOP=L2:L3=L2/L4:L6=L5/L7:BOTTOM=L7 |
| SSD_ACT_DR10 | 50OHM_Y12MIL | BUS | 6 | 6 | 5 | 10 | 5 | 14 | 6 | 15 | 12 | 12 | 12 | 12 |  | 50 Ohms-3 | TOP=L2:L3=L2/L4:L6=L5/L7:BOTTOM=L7 |
| SSD_ACT_DR10 | 50OHM_Y12MIL | BUS | 7 | 6 | 5 | 10 | 5 | 14 | 6 | 15 | 12 | 12 | 12 | 12 |  | 50 Ohms-3 | TOP=L2:L3=L2/L4:L6=L5/L7:BOTTOM=L7 |
| SSD_ACT_DR10 | 50OHM_Y12MIL | BUS | 8 | 6.75 | 5 | 10 | 5 | 14 | 6 | 15 | 12 | 12 | 12 | 12 |  | 50 Ohms-3 | TOP=L2:L3=L2/L4:L6=L5/L7:BOTTOM=L7 |
| SSD_ACT_DR10_MOS_N | 50OHM_Y12MIL | BUS | 1 | 6.75 | 5 | 10 | 5 | 14 | 6 | 15 | 12 | 12 | 12 | 12 |  | 50 Ohms-3 | TOP=L2:L3=L2/L4:L6=L5/L7:BOTTOM=L7 |
| SSD_ACT_DR10_MOS_N | 50OHM_Y12MIL | BUS | 2 | 6 | 5 | 10 | 5 | 14 | 6 | 15 | 12 | 12 | 12 | 12 |  | 50 Ohms-3 | TOP=L2:L3=L2/L4:L6=L5/L7:BOTTOM=L7 |
| SSD_ACT_DR10_MOS_N | 50OHM_Y12MIL | BUS | 3 | 6 | 5 | 10 | 5 | 14 | 6 | 15 | 12 | 12 | 12 | 12 |  | 50 Ohms-3 | TOP=L2:L3=L2/L4:L6=L5/L7:BOTTOM=L7 |
| SSD_ACT_DR10_MOS_N | 50OHM_Y12MIL | BUS | 4 | 6 | 5 | 10 | 5 | 14 | 6 | 15 | 12 | 12 | 12 | 12 |  | 50 Ohms-3 | TOP=L2:L3=L2/L4:L6=L5/L7:BOTTOM=L7 |
| SSD_ACT_DR10_MOS_N | 50OHM_Y12MIL | BUS | 5 | 6 | 5 | 10 | 5 | 14 | 6 | 15 | 12 | 12 | 12 | 12 |  | 50 Ohms-3 | TOP=L2:L3=L2/L4:L6=L5/L7:BOTTOM=L7 |
| SSD_ACT_DR10_MOS_N | 50OHM_Y12MIL | BUS | 6 | 6 | 5 | 10 | 5 | 14 | 6 | 15 | 12 | 12 | 12 | 12 |  | 50 Ohms-3 | TOP=L2:L3=L2/L4:L6=L5/L7:BOTTOM=L7 |
| SSD_ACT_DR10_MOS_N | 50OHM_Y12MIL | BUS | 7 | 6 | 5 | 10 | 5 | 14 | 6 | 15 | 12 | 12 | 12 | 12 |  | 50 Ohms-3 | TOP=L2:L3=L2/L4:L6=L5/L7:BOTTOM=L7 |
| SSD_ACT_DR10_MOS_N | 50OHM_Y12MIL | BUS | 8 | 6.75 | 5 | 10 | 5 | 14 | 6 | 15 | 12 | 12 | 12 | 12 |  | 50 Ohms-3 | TOP=L2:L3=L2/L4:L6=L5/L7:BOTTOM=L7 |
| SSD_ACT_DR10_R | 50OHM_Y12MIL | BUS | 1 | 6.75 | 5 | 10 | 5 | 14 | 6 | 15 | 12 | 12 | 12 | 12 |  | 50 Ohms-3 | TOP=L2:L3=L2/L4:L6=L5/L7:BOTTOM=L7 |
| SSD_ACT_DR10_R | 50OHM_Y12MIL | BUS | 2 | 6 | 5 | 10 | 5 | 14 | 6 | 15 | 12 | 12 | 12 | 12 |  | 50 Ohms-3 | TOP=L2:L3=L2/L4:L6=L5/L7:BOTTOM=L7 |
| SSD_ACT_DR10_R | 50OHM_Y12MIL | BUS | 3 | 6 | 5 | 10 | 5 | 14 | 6 | 15 | 12 | 12 | 12 | 12 |  | 50 Ohms-3 | TOP=L2:L3=L2/L4:L6=L5/L7:BOTTOM=L7 |
| SSD_ACT_DR10_R | 50OHM_Y12MIL | BUS | 4 | 6 | 5 | 10 | 5 | 14 | 6 | 15 | 12 | 12 | 12 | 12 |  | 50 Ohms-3 | TOP=L2:L3=L2/L4:L6=L5/L7:BOTTOM=L7 |
| SSD_ACT_DR10_R | 50OHM_Y12MIL | BUS | 5 | 6 | 5 | 10 | 5 | 14 | 6 | 15 | 12 | 12 | 12 | 12 |  | 50 Ohms-3 | TOP=L2:L3=L2/L4:L6=L5/L7:BOTTOM=L7 |
| SSD_ACT_DR10_R | 50OHM_Y12MIL | BUS | 6 | 6 | 5 | 10 | 5 | 14 | 6 | 15 | 12 | 12 | 12 | 12 |  | 50 Ohms-3 | TOP=L2:L3=L2/L4:L6=L5/L7:BOTTOM=L7 |
| SSD_ACT_DR10_R | 50OHM_Y12MIL | BUS | 7 | 6 | 5 | 10 | 5 | 14 | 6 | 15 | 12 | 12 | 12 | 12 |  | 50 Ohms-3 | TOP=L2:L3=L2/L4:L6=L5/L7:BOTTOM=L7 |
| SSD_ACT_DR10_R | 50OHM_Y12MIL | BUS | 8 | 6.75 | 5 | 10 | 5 | 14 | 6 | 15 | 12 | 12 | 12 | 12 |  | 50 Ohms-3 | TOP=L2:L3=L2/L4:L6=L5/L7:BOTTOM=L7 |
| SSD_ACT_DR11 | 50OHM_Y12MIL | BUS | 1 | 6.75 | 5 | 10 | 5 | 14 | 6 | 15 | 12 | 12 | 12 | 12 |  | 50 Ohms-3 | TOP=L2:L3=L2/L4:L6=L5/L7:BOTTOM=L7 |
| SSD_ACT_DR11 | 50OHM_Y12MIL | BUS | 2 | 6 | 5 | 10 | 5 | 14 | 6 | 15 | 12 | 12 | 12 | 12 |  | 50 Ohms-3 | TOP=L2:L3=L2/L4:L6=L5/L7:BOTTOM=L7 |
| SSD_ACT_DR11 | 50OHM_Y12MIL | BUS | 3 | 6 | 5 | 10 | 5 | 14 | 6 | 15 | 12 | 12 | 12 | 12 |  | 50 Ohms-3 | TOP=L2:L3=L2/L4:L6=L5/L7:BOTTOM=L7 |
| SSD_ACT_DR11 | 50OHM_Y12MIL | BUS | 4 | 6 | 5 | 10 | 5 | 14 | 6 | 15 | 12 | 12 | 12 | 12 |  | 50 Ohms-3 | TOP=L2:L3=L2/L4:L6=L5/L7:BOTTOM=L7 |
| SSD_ACT_DR11 | 50OHM_Y12MIL | BUS | 5 | 6 | 5 | 10 | 5 | 14 | 6 | 15 | 12 | 12 | 12 | 12 |  | 50 Ohms-3 | TOP=L2:L3=L2/L4:L6=L5/L7:BOTTOM=L7 |
| SSD_ACT_DR11 | 50OHM_Y12MIL | BUS | 6 | 6 | 5 | 10 | 5 | 14 | 6 | 15 | 12 | 12 | 12 | 12 |  | 50 Ohms-3 | TOP=L2:L3=L2/L4:L6=L5/L7:BOTTOM=L7 |
| SSD_ACT_DR11 | 50OHM_Y12MIL | BUS | 7 | 6 | 5 | 10 | 5 | 14 | 6 | 15 | 12 | 12 | 12 | 12 |  | 50 Ohms-3 | TOP=L2:L3=L2/L4:L6=L5/L7:BOTTOM=L7 |
| SSD_ACT_DR11 | 50OHM_Y12MIL | BUS | 8 | 6.75 | 5 | 10 | 5 | 14 | 6 | 15 | 12 | 12 | 12 | 12 |  | 50 Ohms-3 | TOP=L2:L3=L2/L4:L6=L5/L7:BOTTOM=L7 |
| SSD_ACT_DR11_MOS_N | 50OHM_Y12MIL | BUS | 1 | 6.75 | 5 | 10 | 5 | 14 | 6 | 15 | 12 | 12 | 12 | 12 |  | 50 Ohms-3 | TOP=L2:L3=L2/L4:L6=L5/L7:BOTTOM=L7 |
| SSD_ACT_DR11_MOS_N | 50OHM_Y12MIL | BUS | 2 | 6 | 5 | 10 | 5 | 14 | 6 | 15 | 12 | 12 | 12 | 12 |  | 50 Ohms-3 | TOP=L2:L3=L2/L4:L6=L5/L7:BOTTOM=L7 |
| SSD_ACT_DR11_MOS_N | 50OHM_Y12MIL | BUS | 3 | 6 | 5 | 10 | 5 | 14 | 6 | 15 | 12 | 12 | 12 | 12 |  | 50 Ohms-3 | TOP=L2:L3=L2/L4:L6=L5/L7:BOTTOM=L7 |
| SSD_ACT_DR11_MOS_N | 50OHM_Y12MIL | BUS | 4 | 6 | 5 | 10 | 5 | 14 | 6 | 15 | 12 | 12 | 12 | 12 |  | 50 Ohms-3 | TOP=L2:L3=L2/L4:L6=L5/L7:BOTTOM=L7 |
| SSD_ACT_DR11_MOS_N | 50OHM_Y12MIL | BUS | 5 | 6 | 5 | 10 | 5 | 14 | 6 | 15 | 12 | 12 | 12 | 12 |  | 50 Ohms-3 | TOP=L2:L3=L2/L4:L6=L5/L7:BOTTOM=L7 |
| SSD_ACT_DR11_MOS_N | 50OHM_Y12MIL | BUS | 6 | 6 | 5 | 10 | 5 | 14 | 6 | 15 | 12 | 12 | 12 | 12 |  | 50 Ohms-3 | TOP=L2:L3=L2/L4:L6=L5/L7:BOTTOM=L7 |
| SSD_ACT_DR11_MOS_N | 50OHM_Y12MIL | BUS | 7 | 6 | 5 | 10 | 5 | 14 | 6 | 15 | 12 | 12 | 12 | 12 |  | 50 Ohms-3 | TOP=L2:L3=L2/L4:L6=L5/L7:BOTTOM=L7 |
| SSD_ACT_DR11_MOS_N | 50OHM_Y12MIL | BUS | 8 | 6.75 | 5 | 10 | 5 | 14 | 6 | 15 | 12 | 12 | 12 | 12 |  | 50 Ohms-3 | TOP=L2:L3=L2/L4:L6=L5/L7:BOTTOM=L7 |
| SSD_ACT_DR11_R | 50OHM_Y12MIL | BUS | 1 | 6.75 | 5 | 10 | 5 | 14 | 6 | 15 | 12 | 12 | 12 | 12 |  | 50 Ohms-3 | TOP=L2:L3=L2/L4:L6=L5/L7:BOTTOM=L7 |
| SSD_ACT_DR11_R | 50OHM_Y12MIL | BUS | 2 | 6 | 5 | 10 | 5 | 14 | 6 | 15 | 12 | 12 | 12 | 12 |  | 50 Ohms-3 | TOP=L2:L3=L2/L4:L6=L5/L7:BOTTOM=L7 |
| SSD_ACT_DR11_R | 50OHM_Y12MIL | BUS | 3 | 6 | 5 | 10 | 5 | 14 | 6 | 15 | 12 | 12 | 12 | 12 |  | 50 Ohms-3 | TOP=L2:L3=L2/L4:L6=L5/L7:BOTTOM=L7 |
| SSD_ACT_DR11_R | 50OHM_Y12MIL | BUS | 4 | 6 | 5 | 10 | 5 | 14 | 6 | 15 | 12 | 12 | 12 | 12 |  | 50 Ohms-3 | TOP=L2:L3=L2/L4:L6=L5/L7:BOTTOM=L7 |
| SSD_ACT_DR11_R | 50OHM_Y12MIL | BUS | 5 | 6 | 5 | 10 | 5 | 14 | 6 | 15 | 12 | 12 | 12 | 12 |  | 50 Ohms-3 | TOP=L2:L3=L2/L4:L6=L5/L7:BOTTOM=L7 |
| SSD_ACT_DR11_R | 50OHM_Y12MIL | BUS | 6 | 6 | 5 | 10 | 5 | 14 | 6 | 15 | 12 | 12 | 12 | 12 |  | 50 Ohms-3 | TOP=L2:L3=L2/L4:L6=L5/L7:BOTTOM=L7 |
| SSD_ACT_DR11_R | 50OHM_Y12MIL | BUS | 7 | 6 | 5 | 10 | 5 | 14 | 6 | 15 | 12 | 12 | 12 | 12 |  | 50 Ohms-3 | TOP=L2:L3=L2/L4:L6=L5/L7:BOTTOM=L7 |
| SSD_ACT_DR11_R | 50OHM_Y12MIL | BUS | 8 | 6.75 | 5 | 10 | 5 | 14 | 6 | 15 | 12 | 12 | 12 | 12 |  | 50 Ohms-3 | TOP=L2:L3=L2/L4:L6=L5/L7:BOTTOM=L7 |
| SSD_ACT_DR12 | 50OHM_Y12MIL | BUS | 1 | 6.75 | 5 | 10 | 5 | 14 | 6 | 15 | 12 | 12 | 12 | 12 |  | 50 Ohms-3 | TOP=L2:L3=L2/L4:L6=L5/L7:BOTTOM=L7 |
| SSD_ACT_DR12 | 50OHM_Y12MIL | BUS | 2 | 6 | 5 | 10 | 5 | 14 | 6 | 15 | 12 | 12 | 12 | 12 |  | 50 Ohms-3 | TOP=L2:L3=L2/L4:L6=L5/L7:BOTTOM=L7 |
| SSD_ACT_DR12 | 50OHM_Y12MIL | BUS | 3 | 6 | 5 | 10 | 5 | 14 | 6 | 15 | 12 | 12 | 12 | 12 |  | 50 Ohms-3 | TOP=L2:L3=L2/L4:L6=L5/L7:BOTTOM=L7 |
| SSD_ACT_DR12 | 50OHM_Y12MIL | BUS | 4 | 6 | 5 | 10 | 5 | 14 | 6 | 15 | 12 | 12 | 12 | 12 |  | 50 Ohms-3 | TOP=L2:L3=L2/L4:L6=L5/L7:BOTTOM=L7 |
| SSD_ACT_DR12 | 50OHM_Y12MIL | BUS | 5 | 6 | 5 | 10 | 5 | 14 | 6 | 15 | 12 | 12 | 12 | 12 |  | 50 Ohms-3 | TOP=L2:L3=L2/L4:L6=L5/L7:BOTTOM=L7 |
| SSD_ACT_DR12 | 50OHM_Y12MIL | BUS | 6 | 6 | 5 | 10 | 5 | 14 | 6 | 15 | 12 | 12 | 12 | 12 |  | 50 Ohms-3 | TOP=L2:L3=L2/L4:L6=L5/L7:BOTTOM=L7 |
| SSD_ACT_DR12 | 50OHM_Y12MIL | BUS | 7 | 6 | 5 | 10 | 5 | 14 | 6 | 15 | 12 | 12 | 12 | 12 |  | 50 Ohms-3 | TOP=L2:L3=L2/L4:L6=L5/L7:BOTTOM=L7 |
| SSD_ACT_DR12 | 50OHM_Y12MIL | BUS | 8 | 6.75 | 5 | 10 | 5 | 14 | 6 | 15 | 12 | 12 | 12 | 12 |  | 50 Ohms-3 | TOP=L2:L3=L2/L4:L6=L5/L7:BOTTOM=L7 |
| SSD_ACT_DR12_MOS_N | 50OHM_Y12MIL | BUS | 1 | 6.75 | 5 | 10 | 5 | 14 | 6 | 15 | 12 | 12 | 12 | 12 |  | 50 Ohms-3 | TOP=L2:L3=L2/L4:L6=L5/L7:BOTTOM=L7 |
| SSD_ACT_DR12_MOS_N | 50OHM_Y12MIL | BUS | 2 | 6 | 5 | 10 | 5 | 14 | 6 | 15 | 12 | 12 | 12 | 12 |  | 50 Ohms-3 | TOP=L2:L3=L2/L4:L6=L5/L7:BOTTOM=L7 |
| SSD_ACT_DR12_MOS_N | 50OHM_Y12MIL | BUS | 3 | 6 | 5 | 10 | 5 | 14 | 6 | 15 | 12 | 12 | 12 | 12 |  | 50 Ohms-3 | TOP=L2:L3=L2/L4:L6=L5/L7:BOTTOM=L7 |
| SSD_ACT_DR12_MOS_N | 50OHM_Y12MIL | BUS | 4 | 6 | 5 | 10 | 5 | 14 | 6 | 15 | 12 | 12 | 12 | 12 |  | 50 Ohms-3 | TOP=L2:L3=L2/L4:L6=L5/L7:BOTTOM=L7 |
| SSD_ACT_DR12_MOS_N | 50OHM_Y12MIL | BUS | 5 | 6 | 5 | 10 | 5 | 14 | 6 | 15 | 12 | 12 | 12 | 12 |  | 50 Ohms-3 | TOP=L2:L3=L2/L4:L6=L5/L7:BOTTOM=L7 |
| SSD_ACT_DR12_MOS_N | 50OHM_Y12MIL | BUS | 6 | 6 | 5 | 10 | 5 | 14 | 6 | 15 | 12 | 12 | 12 | 12 |  | 50 Ohms-3 | TOP=L2:L3=L2/L4:L6=L5/L7:BOTTOM=L7 |
| SSD_ACT_DR12_MOS_N | 50OHM_Y12MIL | BUS | 7 | 6 | 5 | 10 | 5 | 14 | 6 | 15 | 12 | 12 | 12 | 12 |  | 50 Ohms-3 | TOP=L2:L3=L2/L4:L6=L5/L7:BOTTOM=L7 |
| SSD_ACT_DR12_MOS_N | 50OHM_Y12MIL | BUS | 8 | 6.75 | 5 | 10 | 5 | 14 | 6 | 15 | 12 | 12 | 12 | 12 |  | 50 Ohms-3 | TOP=L2:L3=L2/L4:L6=L5/L7:BOTTOM=L7 |
| SSD_ACT_DR12_R | 50OHM_Y12MIL | BUS | 1 | 6.75 | 5 | 10 | 5 | 14 | 6 | 15 | 12 | 12 | 12 | 12 |  | 50 Ohms-3 | TOP=L2:L3=L2/L4:L6=L5/L7:BOTTOM=L7 |
| SSD_ACT_DR12_R | 50OHM_Y12MIL | BUS | 2 | 6 | 5 | 10 | 5 | 14 | 6 | 15 | 12 | 12 | 12 | 12 |  | 50 Ohms-3 | TOP=L2:L3=L2/L4:L6=L5/L7:BOTTOM=L7 |
| SSD_ACT_DR12_R | 50OHM_Y12MIL | BUS | 3 | 6 | 5 | 10 | 5 | 14 | 6 | 15 | 12 | 12 | 12 | 12 |  | 50 Ohms-3 | TOP=L2:L3=L2/L4:L6=L5/L7:BOTTOM=L7 |
| SSD_ACT_DR12_R | 50OHM_Y12MIL | BUS | 4 | 6 | 5 | 10 | 5 | 14 | 6 | 15 | 12 | 12 | 12 | 12 |  | 50 Ohms-3 | TOP=L2:L3=L2/L4:L6=L5/L7:BOTTOM=L7 |
| SSD_ACT_DR12_R | 50OHM_Y12MIL | BUS | 5 | 6 | 5 | 10 | 5 | 14 | 6 | 15 | 12 | 12 | 12 | 12 |  | 50 Ohms-3 | TOP=L2:L3=L2/L4:L6=L5/L7:BOTTOM=L7 |
| SSD_ACT_DR12_R | 50OHM_Y12MIL | BUS | 6 | 6 | 5 | 10 | 5 | 14 | 6 | 15 | 12 | 12 | 12 | 12 |  | 50 Ohms-3 | TOP=L2:L3=L2/L4:L6=L5/L7:BOTTOM=L7 |
| SSD_ACT_DR12_R | 50OHM_Y12MIL | BUS | 7 | 6 | 5 | 10 | 5 | 14 | 6 | 15 | 12 | 12 | 12 | 12 |  | 50 Ohms-3 | TOP=L2:L3=L2/L4:L6=L5/L7:BOTTOM=L7 |
| SSD_ACT_DR12_R | 50OHM_Y12MIL | BUS | 8 | 6.75 | 5 | 10 | 5 | 14 | 6 | 15 | 12 | 12 | 12 | 12 |  | 50 Ohms-3 | TOP=L2:L3=L2/L4:L6=L5/L7:BOTTOM=L7 |
| SSD_ACT_DR13 | 50OHM_Y12MIL | BUS | 1 | 6.75 | 5 | 10 | 5 | 14 | 6 | 15 | 12 | 12 | 12 | 12 |  | 50 Ohms-3 | TOP=L2:L3=L2/L4:L6=L5/L7:BOTTOM=L7 |
| SSD_ACT_DR13 | 50OHM_Y12MIL | BUS | 2 | 6 | 5 | 10 | 5 | 14 | 6 | 15 | 12 | 12 | 12 | 12 |  | 50 Ohms-3 | TOP=L2:L3=L2/L4:L6=L5/L7:BOTTOM=L7 |
| SSD_ACT_DR13 | 50OHM_Y12MIL | BUS | 3 | 6 | 5 | 10 | 5 | 14 | 6 | 15 | 12 | 12 | 12 | 12 |  | 50 Ohms-3 | TOP=L2:L3=L2/L4:L6=L5/L7:BOTTOM=L7 |
| SSD_ACT_DR13 | 50OHM_Y12MIL | BUS | 4 | 6 | 5 | 10 | 5 | 14 | 6 | 15 | 12 | 12 | 12 | 12 |  | 50 Ohms-3 | TOP=L2:L3=L2/L4:L6=L5/L7:BOTTOM=L7 |
| SSD_ACT_DR13 | 50OHM_Y12MIL | BUS | 5 | 6 | 5 | 10 | 5 | 14 | 6 | 15 | 12 | 12 | 12 | 12 |  | 50 Ohms-3 | TOP=L2:L3=L2/L4:L6=L5/L7:BOTTOM=L7 |
| SSD_ACT_DR13 | 50OHM_Y12MIL | BUS | 6 | 6 | 5 | 10 | 5 | 14 | 6 | 15 | 12 | 12 | 12 | 12 |  | 50 Ohms-3 | TOP=L2:L3=L2/L4:L6=L5/L7:BOTTOM=L7 |
| SSD_ACT_DR13 | 50OHM_Y12MIL | BUS | 7 | 6 | 5 | 10 | 5 | 14 | 6 | 15 | 12 | 12 | 12 | 12 |  | 50 Ohms-3 | TOP=L2:L3=L2/L4:L6=L5/L7:BOTTOM=L7 |
| SSD_ACT_DR13 | 50OHM_Y12MIL | BUS | 8 | 6.75 | 5 | 10 | 5 | 14 | 6 | 15 | 12 | 12 | 12 | 12 |  | 50 Ohms-3 | TOP=L2:L3=L2/L4:L6=L5/L7:BOTTOM=L7 |
| SSD_ACT_DR13_MOS_N | 50OHM_Y12MIL | BUS | 1 | 6.75 | 5 | 10 | 5 | 14 | 6 | 15 | 12 | 12 | 12 | 12 |  | 50 Ohms-3 | TOP=L2:L3=L2/L4:L6=L5/L7:BOTTOM=L7 |
| SSD_ACT_DR13_MOS_N | 50OHM_Y12MIL | BUS | 2 | 6 | 5 | 10 | 5 | 14 | 6 | 15 | 12 | 12 | 12 | 12 |  | 50 Ohms-3 | TOP=L2:L3=L2/L4:L6=L5/L7:BOTTOM=L7 |
| SSD_ACT_DR13_MOS_N | 50OHM_Y12MIL | BUS | 3 | 6 | 5 | 10 | 5 | 14 | 6 | 15 | 12 | 12 | 12 | 12 |  | 50 Ohms-3 | TOP=L2:L3=L2/L4:L6=L5/L7:BOTTOM=L7 |
| SSD_ACT_DR13_MOS_N | 50OHM_Y12MIL | BUS | 4 | 6 | 5 | 10 | 5 | 14 | 6 | 15 | 12 | 12 | 12 | 12 |  | 50 Ohms-3 | TOP=L2:L3=L2/L4:L6=L5/L7:BOTTOM=L7 |
| SSD_ACT_DR13_MOS_N | 50OHM_Y12MIL | BUS | 5 | 6 | 5 | 10 | 5 | 14 | 6 | 15 | 12 | 12 | 12 | 12 |  | 50 Ohms-3 | TOP=L2:L3=L2/L4:L6=L5/L7:BOTTOM=L7 |
| SSD_ACT_DR13_MOS_N | 50OHM_Y12MIL | BUS | 6 | 6 | 5 | 10 | 5 | 14 | 6 | 15 | 12 | 12 | 12 | 12 |  | 50 Ohms-3 | TOP=L2:L3=L2/L4:L6=L5/L7:BOTTOM=L7 |
| SSD_ACT_DR13_MOS_N | 50OHM_Y12MIL | BUS | 7 | 6 | 5 | 10 | 5 | 14 | 6 | 15 | 12 | 12 | 12 | 12 |  | 50 Ohms-3 | TOP=L2:L3=L2/L4:L6=L5/L7:BOTTOM=L7 |
| SSD_ACT_DR13_MOS_N | 50OHM_Y12MIL | BUS | 8 | 6.75 | 5 | 10 | 5 | 14 | 6 | 15 | 12 | 12 | 12 | 12 |  | 50 Ohms-3 | TOP=L2:L3=L2/L4:L6=L5/L7:BOTTOM=L7 |
| SSD_ACT_DR13_R | 50OHM_Y12MIL | BUS | 1 | 6.75 | 5 | 10 | 5 | 14 | 6 | 15 | 12 | 12 | 12 | 12 |  | 50 Ohms-3 | TOP=L2:L3=L2/L4:L6=L5/L7:BOTTOM=L7 |
| SSD_ACT_DR13_R | 50OHM_Y12MIL | BUS | 2 | 6 | 5 | 10 | 5 | 14 | 6 | 15 | 12 | 12 | 12 | 12 |  | 50 Ohms-3 | TOP=L2:L3=L2/L4:L6=L5/L7:BOTTOM=L7 |
| SSD_ACT_DR13_R | 50OHM_Y12MIL | BUS | 3 | 6 | 5 | 10 | 5 | 14 | 6 | 15 | 12 | 12 | 12 | 12 |  | 50 Ohms-3 | TOP=L2:L3=L2/L4:L6=L5/L7:BOTTOM=L7 |
| SSD_ACT_DR13_R | 50OHM_Y12MIL | BUS | 4 | 6 | 5 | 10 | 5 | 14 | 6 | 15 | 12 | 12 | 12 | 12 |  | 50 Ohms-3 | TOP=L2:L3=L2/L4:L6=L5/L7:BOTTOM=L7 |
| SSD_ACT_DR13_R | 50OHM_Y12MIL | BUS | 5 | 6 | 5 | 10 | 5 | 14 | 6 | 15 | 12 | 12 | 12 | 12 |  | 50 Ohms-3 | TOP=L2:L3=L2/L4:L6=L5/L7:BOTTOM=L7 |
| SSD_ACT_DR13_R | 50OHM_Y12MIL | BUS | 6 | 6 | 5 | 10 | 5 | 14 | 6 | 15 | 12 | 12 | 12 | 12 |  | 50 Ohms-3 | TOP=L2:L3=L2/L4:L6=L5/L7:BOTTOM=L7 |
| SSD_ACT_DR13_R | 50OHM_Y12MIL | BUS | 7 | 6 | 5 | 10 | 5 | 14 | 6 | 15 | 12 | 12 | 12 | 12 |  | 50 Ohms-3 | TOP=L2:L3=L2/L4:L6=L5/L7:BOTTOM=L7 |
| SSD_ACT_DR13_R | 50OHM_Y12MIL | BUS | 8 | 6.75 | 5 | 10 | 5 | 14 | 6 | 15 | 12 | 12 | 12 | 12 |  | 50 Ohms-3 | TOP=L2:L3=L2/L4:L6=L5/L7:BOTTOM=L7 |
| SSD_ACT_DR14 | 50OHM_Y12MIL | BUS | 1 | 6.75 | 5 | 10 | 5 | 14 | 6 | 15 | 12 | 12 | 12 | 12 |  | 50 Ohms-3 | TOP=L2:L3=L2/L4:L6=L5/L7:BOTTOM=L7 |
| SSD_ACT_DR14 | 50OHM_Y12MIL | BUS | 2 | 6 | 5 | 10 | 5 | 14 | 6 | 15 | 12 | 12 | 12 | 12 |  | 50 Ohms-3 | TOP=L2:L3=L2/L4:L6=L5/L7:BOTTOM=L7 |
| SSD_ACT_DR14 | 50OHM_Y12MIL | BUS | 3 | 6 | 5 | 10 | 5 | 14 | 6 | 15 | 12 | 12 | 12 | 12 |  | 50 Ohms-3 | TOP=L2:L3=L2/L4:L6=L5/L7:BOTTOM=L7 |
| SSD_ACT_DR14 | 50OHM_Y12MIL | BUS | 4 | 6 | 5 | 10 | 5 | 14 | 6 | 15 | 12 | 12 | 12 | 12 |  | 50 Ohms-3 | TOP=L2:L3=L2/L4:L6=L5/L7:BOTTOM=L7 |
| SSD_ACT_DR14 | 50OHM_Y12MIL | BUS | 5 | 6 | 5 | 10 | 5 | 14 | 6 | 15 | 12 | 12 | 12 | 12 |  | 50 Ohms-3 | TOP=L2:L3=L2/L4:L6=L5/L7:BOTTOM=L7 |
| SSD_ACT_DR14 | 50OHM_Y12MIL | BUS | 6 | 6 | 5 | 10 | 5 | 14 | 6 | 15 | 12 | 12 | 12 | 12 |  | 50 Ohms-3 | TOP=L2:L3=L2/L4:L6=L5/L7:BOTTOM=L7 |
| SSD_ACT_DR14 | 50OHM_Y12MIL | BUS | 7 | 6 | 5 | 10 | 5 | 14 | 6 | 15 | 12 | 12 | 12 | 12 |  | 50 Ohms-3 | TOP=L2:L3=L2/L4:L6=L5/L7:BOTTOM=L7 |
| SSD_ACT_DR14 | 50OHM_Y12MIL | BUS | 8 | 6.75 | 5 | 10 | 5 | 14 | 6 | 15 | 12 | 12 | 12 | 12 |  | 50 Ohms-3 | TOP=L2:L3=L2/L4:L6=L5/L7:BOTTOM=L7 |
| SSD_ACT_DR14_MOS_N | 50OHM_Y12MIL | BUS | 1 | 6.75 | 5 | 10 | 5 | 14 | 6 | 15 | 12 | 12 | 12 | 12 |  | 50 Ohms-3 | TOP=L2:L3=L2/L4:L6=L5/L7:BOTTOM=L7 |
| SSD_ACT_DR14_MOS_N | 50OHM_Y12MIL | BUS | 2 | 6 | 5 | 10 | 5 | 14 | 6 | 15 | 12 | 12 | 12 | 12 |  | 50 Ohms-3 | TOP=L2:L3=L2/L4:L6=L5/L7:BOTTOM=L7 |
| SSD_ACT_DR14_MOS_N | 50OHM_Y12MIL | BUS | 3 | 6 | 5 | 10 | 5 | 14 | 6 | 15 | 12 | 12 | 12 | 12 |  | 50 Ohms-3 | TOP=L2:L3=L2/L4:L6=L5/L7:BOTTOM=L7 |
| SSD_ACT_DR14_MOS_N | 50OHM_Y12MIL | BUS | 4 | 6 | 5 | 10 | 5 | 14 | 6 | 15 | 12 | 12 | 12 | 12 |  | 50 Ohms-3 | TOP=L2:L3=L2/L4:L6=L5/L7:BOTTOM=L7 |
| SSD_ACT_DR14_MOS_N | 50OHM_Y12MIL | BUS | 5 | 6 | 5 | 10 | 5 | 14 | 6 | 15 | 12 | 12 | 12 | 12 |  | 50 Ohms-3 | TOP=L2:L3=L2/L4:L6=L5/L7:BOTTOM=L7 |
| SSD_ACT_DR14_MOS_N | 50OHM_Y12MIL | BUS | 6 | 6 | 5 | 10 | 5 | 14 | 6 | 15 | 12 | 12 | 12 | 12 |  | 50 Ohms-3 | TOP=L2:L3=L2/L4:L6=L5/L7:BOTTOM=L7 |
| SSD_ACT_DR14_MOS_N | 50OHM_Y12MIL | BUS | 7 | 6 | 5 | 10 | 5 | 14 | 6 | 15 | 12 | 12 | 12 | 12 |  | 50 Ohms-3 | TOP=L2:L3=L2/L4:L6=L5/L7:BOTTOM=L7 |
| SSD_ACT_DR14_MOS_N | 50OHM_Y12MIL | BUS | 8 | 6.75 | 5 | 10 | 5 | 14 | 6 | 15 | 12 | 12 | 12 | 12 |  | 50 Ohms-3 | TOP=L2:L3=L2/L4:L6=L5/L7:BOTTOM=L7 |
| SSD_ACT_DR14_R | 50OHM_Y12MIL | BUS | 1 | 6.75 | 5 | 10 | 5 | 14 | 6 | 15 | 12 | 12 | 12 | 12 |  | 50 Ohms-3 | TOP=L2:L3=L2/L4:L6=L5/L7:BOTTOM=L7 |
| SSD_ACT_DR14_R | 50OHM_Y12MIL | BUS | 2 | 6 | 5 | 10 | 5 | 14 | 6 | 15 | 12 | 12 | 12 | 12 |  | 50 Ohms-3 | TOP=L2:L3=L2/L4:L6=L5/L7:BOTTOM=L7 |
| SSD_ACT_DR14_R | 50OHM_Y12MIL | BUS | 3 | 6 | 5 | 10 | 5 | 14 | 6 | 15 | 12 | 12 | 12 | 12 |  | 50 Ohms-3 | TOP=L2:L3=L2/L4:L6=L5/L7:BOTTOM=L7 |
| SSD_ACT_DR14_R | 50OHM_Y12MIL | BUS | 4 | 6 | 5 | 10 | 5 | 14 | 6 | 15 | 12 | 12 | 12 | 12 |  | 50 Ohms-3 | TOP=L2:L3=L2/L4:L6=L5/L7:BOTTOM=L7 |
| SSD_ACT_DR14_R | 50OHM_Y12MIL | BUS | 5 | 6 | 5 | 10 | 5 | 14 | 6 | 15 | 12 | 12 | 12 | 12 |  | 50 Ohms-3 | TOP=L2:L3=L2/L4:L6=L5/L7:BOTTOM=L7 |
| SSD_ACT_DR14_R | 50OHM_Y12MIL | BUS | 6 | 6 | 5 | 10 | 5 | 14 | 6 | 15 | 12 | 12 | 12 | 12 |  | 50 Ohms-3 | TOP=L2:L3=L2/L4:L6=L5/L7:BOTTOM=L7 |
| SSD_ACT_DR14_R | 50OHM_Y12MIL | BUS | 7 | 6 | 5 | 10 | 5 | 14 | 6 | 15 | 12 | 12 | 12 | 12 |  | 50 Ohms-3 | TOP=L2:L3=L2/L4:L6=L5/L7:BOTTOM=L7 |
| SSD_ACT_DR14_R | 50OHM_Y12MIL | BUS | 8 | 6.75 | 5 | 10 | 5 | 14 | 6 | 15 | 12 | 12 | 12 | 12 |  | 50 Ohms-3 | TOP=L2:L3=L2/L4:L6=L5/L7:BOTTOM=L7 |
| SSD_ACT_DR2 | 50OHM_Y12MIL | BUS | 1 | 6.75 | 5 | 10 | 5 | 14 | 6 | 15 | 12 | 12 | 12 | 12 |  | 50 Ohms-3 | TOP=L2:L3=L2/L4:L6=L5/L7:BOTTOM=L7 |
| SSD_ACT_DR2 | 50OHM_Y12MIL | BUS | 2 | 6 | 5 | 10 | 5 | 14 | 6 | 15 | 12 | 12 | 12 | 12 |  | 50 Ohms-3 | TOP=L2:L3=L2/L4:L6=L5/L7:BOTTOM=L7 |
| SSD_ACT_DR2 | 50OHM_Y12MIL | BUS | 3 | 6 | 5 | 10 | 5 | 14 | 6 | 15 | 12 | 12 | 12 | 12 |  | 50 Ohms-3 | TOP=L2:L3=L2/L4:L6=L5/L7:BOTTOM=L7 |
| SSD_ACT_DR2 | 50OHM_Y12MIL | BUS | 4 | 6 | 5 | 10 | 5 | 14 | 6 | 15 | 12 | 12 | 12 | 12 |  | 50 Ohms-3 | TOP=L2:L3=L2/L4:L6=L5/L7:BOTTOM=L7 |
| SSD_ACT_DR2 | 50OHM_Y12MIL | BUS | 5 | 6 | 5 | 10 | 5 | 14 | 6 | 15 | 12 | 12 | 12 | 12 |  | 50 Ohms-3 | TOP=L2:L3=L2/L4:L6=L5/L7:BOTTOM=L7 |
| SSD_ACT_DR2 | 50OHM_Y12MIL | BUS | 6 | 6 | 5 | 10 | 5 | 14 | 6 | 15 | 12 | 12 | 12 | 12 |  | 50 Ohms-3 | TOP=L2:L3=L2/L4:L6=L5/L7:BOTTOM=L7 |
| SSD_ACT_DR2 | 50OHM_Y12MIL | BUS | 7 | 6 | 5 | 10 | 5 | 14 | 6 | 15 | 12 | 12 | 12 | 12 |  | 50 Ohms-3 | TOP=L2:L3=L2/L4:L6=L5/L7:BOTTOM=L7 |
| SSD_ACT_DR2 | 50OHM_Y12MIL | BUS | 8 | 6.75 | 5 | 10 | 5 | 14 | 6 | 15 | 12 | 12 | 12 | 12 |  | 50 Ohms-3 | TOP=L2:L3=L2/L4:L6=L5/L7:BOTTOM=L7 |
| SSD_ACT_DR2_MOS_N | 50OHM_Y12MIL | BUS | 1 | 6.75 | 5 | 10 | 5 | 14 | 6 | 15 | 12 | 12 | 12 | 12 |  | 50 Ohms-3 | TOP=L2:L3=L2/L4:L6=L5/L7:BOTTOM=L7 |
| SSD_ACT_DR2_MOS_N | 50OHM_Y12MIL | BUS | 2 | 6 | 5 | 10 | 5 | 14 | 6 | 15 | 12 | 12 | 12 | 12 |  | 50 Ohms-3 | TOP=L2:L3=L2/L4:L6=L5/L7:BOTTOM=L7 |
| SSD_ACT_DR2_MOS_N | 50OHM_Y12MIL | BUS | 3 | 6 | 5 | 10 | 5 | 14 | 6 | 15 | 12 | 12 | 12 | 12 |  | 50 Ohms-3 | TOP=L2:L3=L2/L4:L6=L5/L7:BOTTOM=L7 |
| SSD_ACT_DR2_MOS_N | 50OHM_Y12MIL | BUS | 4 | 6 | 5 | 10 | 5 | 14 | 6 | 15 | 12 | 12 | 12 | 12 |  | 50 Ohms-3 | TOP=L2:L3=L2/L4:L6=L5/L7:BOTTOM=L7 |
| SSD_ACT_DR2_MOS_N | 50OHM_Y12MIL | BUS | 5 | 6 | 5 | 10 | 5 | 14 | 6 | 15 | 12 | 12 | 12 | 12 |  | 50 Ohms-3 | TOP=L2:L3=L2/L4:L6=L5/L7:BOTTOM=L7 |
| SSD_ACT_DR2_MOS_N | 50OHM_Y12MIL | BUS | 6 | 6 | 5 | 10 | 5 | 14 | 6 | 15 | 12 | 12 | 12 | 12 |  | 50 Ohms-3 | TOP=L2:L3=L2/L4:L6=L5/L7:BOTTOM=L7 |
| SSD_ACT_DR2_MOS_N | 50OHM_Y12MIL | BUS | 7 | 6 | 5 | 10 | 5 | 14 | 6 | 15 | 12 | 12 | 12 | 12 |  | 50 Ohms-3 | TOP=L2:L3=L2/L4:L6=L5/L7:BOTTOM=L7 |
| SSD_ACT_DR2_MOS_N | 50OHM_Y12MIL | BUS | 8 | 6.75 | 5 | 10 | 5 | 14 | 6 | 15 | 12 | 12 | 12 | 12 |  | 50 Ohms-3 | TOP=L2:L3=L2/L4:L6=L5/L7:BOTTOM=L7 |
| SSD_ACT_DR2_R | 50OHM_Y12MIL | BUS | 1 | 6.75 | 5 | 10 | 5 | 14 | 6 | 15 | 12 | 12 | 12 | 12 |  | 50 Ohms-3 | TOP=L2:L3=L2/L4:L6=L5/L7:BOTTOM=L7 |
| SSD_ACT_DR2_R | 50OHM_Y12MIL | BUS | 2 | 6 | 5 | 10 | 5 | 14 | 6 | 15 | 12 | 12 | 12 | 12 |  | 50 Ohms-3 | TOP=L2:L3=L2/L4:L6=L5/L7:BOTTOM=L7 |
| SSD_ACT_DR2_R | 50OHM_Y12MIL | BUS | 3 | 6 | 5 | 10 | 5 | 14 | 6 | 15 | 12 | 12 | 12 | 12 |  | 50 Ohms-3 | TOP=L2:L3=L2/L4:L6=L5/L7:BOTTOM=L7 |
| SSD_ACT_DR2_R | 50OHM_Y12MIL | BUS | 4 | 6 | 5 | 10 | 5 | 14 | 6 | 15 | 12 | 12 | 12 | 12 |  | 50 Ohms-3 | TOP=L2:L3=L2/L4:L6=L5/L7:BOTTOM=L7 |
| SSD_ACT_DR2_R | 50OHM_Y12MIL | BUS | 5 | 6 | 5 | 10 | 5 | 14 | 6 | 15 | 12 | 12 | 12 | 12 |  | 50 Ohms-3 | TOP=L2:L3=L2/L4:L6=L5/L7:BOTTOM=L7 |
| SSD_ACT_DR2_R | 50OHM_Y12MIL | BUS | 6 | 6 | 5 | 10 | 5 | 14 | 6 | 15 | 12 | 12 | 12 | 12 |  | 50 Ohms-3 | TOP=L2:L3=L2/L4:L6=L5/L7:BOTTOM=L7 |
| SSD_ACT_DR2_R | 50OHM_Y12MIL | BUS | 7 | 6 | 5 | 10 | 5 | 14 | 6 | 15 | 12 | 12 | 12 | 12 |  | 50 Ohms-3 | TOP=L2:L3=L2/L4:L6=L5/L7:BOTTOM=L7 |
| SSD_ACT_DR2_R | 50OHM_Y12MIL | BUS | 8 | 6.75 | 5 | 10 | 5 | 14 | 6 | 15 | 12 | 12 | 12 | 12 |  | 50 Ohms-3 | TOP=L2:L3=L2/L4:L6=L5/L7:BOTTOM=L7 |
| SSD_ACT_DR3 | 50OHM_Y12MIL | BUS | 1 | 6.75 | 5 | 10 | 5 | 14 | 6 | 15 | 12 | 12 | 12 | 12 |  | 50 Ohms-3 | TOP=L2:L3=L2/L4:L6=L5/L7:BOTTOM=L7 |
| SSD_ACT_DR3 | 50OHM_Y12MIL | BUS | 2 | 6 | 5 | 10 | 5 | 14 | 6 | 15 | 12 | 12 | 12 | 12 |  | 50 Ohms-3 | TOP=L2:L3=L2/L4:L6=L5/L7:BOTTOM=L7 |
| SSD_ACT_DR3 | 50OHM_Y12MIL | BUS | 3 | 6 | 5 | 10 | 5 | 14 | 6 | 15 | 12 | 12 | 12 | 12 |  | 50 Ohms-3 | TOP=L2:L3=L2/L4:L6=L5/L7:BOTTOM=L7 |
| SSD_ACT_DR3 | 50OHM_Y12MIL | BUS | 4 | 6 | 5 | 10 | 5 | 14 | 6 | 15 | 12 | 12 | 12 | 12 |  | 50 Ohms-3 | TOP=L2:L3=L2/L4:L6=L5/L7:BOTTOM=L7 |
| SSD_ACT_DR3 | 50OHM_Y12MIL | BUS | 5 | 6 | 5 | 10 | 5 | 14 | 6 | 15 | 12 | 12 | 12 | 12 |  | 50 Ohms-3 | TOP=L2:L3=L2/L4:L6=L5/L7:BOTTOM=L7 |
| SSD_ACT_DR3 | 50OHM_Y12MIL | BUS | 6 | 6 | 5 | 10 | 5 | 14 | 6 | 15 | 12 | 12 | 12 | 12 |  | 50 Ohms-3 | TOP=L2:L3=L2/L4:L6=L5/L7:BOTTOM=L7 |
| SSD_ACT_DR3 | 50OHM_Y12MIL | BUS | 7 | 6 | 5 | 10 | 5 | 14 | 6 | 15 | 12 | 12 | 12 | 12 |  | 50 Ohms-3 | TOP=L2:L3=L2/L4:L6=L5/L7:BOTTOM=L7 |
| SSD_ACT_DR3 | 50OHM_Y12MIL | BUS | 8 | 6.75 | 5 | 10 | 5 | 14 | 6 | 15 | 12 | 12 | 12 | 12 |  | 50 Ohms-3 | TOP=L2:L3=L2/L4:L6=L5/L7:BOTTOM=L7 |
| SSD_ACT_DR3_MOS_N | 50OHM_Y12MIL | BUS | 1 | 6.75 | 5 | 10 | 5 | 14 | 6 | 15 | 12 | 12 | 12 | 12 |  | 50 Ohms-3 | TOP=L2:L3=L2/L4:L6=L5/L7:BOTTOM=L7 |
| SSD_ACT_DR3_MOS_N | 50OHM_Y12MIL | BUS | 2 | 6 | 5 | 10 | 5 | 14 | 6 | 15 | 12 | 12 | 12 | 12 |  | 50 Ohms-3 | TOP=L2:L3=L2/L4:L6=L5/L7:BOTTOM=L7 |
| SSD_ACT_DR3_MOS_N | 50OHM_Y12MIL | BUS | 3 | 6 | 5 | 10 | 5 | 14 | 6 | 15 | 12 | 12 | 12 | 12 |  | 50 Ohms-3 | TOP=L2:L3=L2/L4:L6=L5/L7:BOTTOM=L7 |
| SSD_ACT_DR3_MOS_N | 50OHM_Y12MIL | BUS | 4 | 6 | 5 | 10 | 5 | 14 | 6 | 15 | 12 | 12 | 12 | 12 |  | 50 Ohms-3 | TOP=L2:L3=L2/L4:L6=L5/L7:BOTTOM=L7 |
| SSD_ACT_DR3_MOS_N | 50OHM_Y12MIL | BUS | 5 | 6 | 5 | 10 | 5 | 14 | 6 | 15 | 12 | 12 | 12 | 12 |  | 50 Ohms-3 | TOP=L2:L3=L2/L4:L6=L5/L7:BOTTOM=L7 |
| SSD_ACT_DR3_MOS_N | 50OHM_Y12MIL | BUS | 6 | 6 | 5 | 10 | 5 | 14 | 6 | 15 | 12 | 12 | 12 | 12 |  | 50 Ohms-3 | TOP=L2:L3=L2/L4:L6=L5/L7:BOTTOM=L7 |
| SSD_ACT_DR3_MOS_N | 50OHM_Y12MIL | BUS | 7 | 6 | 5 | 10 | 5 | 14 | 6 | 15 | 12 | 12 | 12 | 12 |  | 50 Ohms-3 | TOP=L2:L3=L2/L4:L6=L5/L7:BOTTOM=L7 |
| SSD_ACT_DR3_MOS_N | 50OHM_Y12MIL | BUS | 8 | 6.75 | 5 | 10 | 5 | 14 | 6 | 15 | 12 | 12 | 12 | 12 |  | 50 Ohms-3 | TOP=L2:L3=L2/L4:L6=L5/L7:BOTTOM=L7 |
| SSD_ACT_DR3_R | 50OHM_Y12MIL | BUS | 1 | 6.75 | 5 | 10 | 5 | 14 | 6 | 15 | 12 | 12 | 12 | 12 |  | 50 Ohms-3 | TOP=L2:L3=L2/L4:L6=L5/L7:BOTTOM=L7 |
| SSD_ACT_DR3_R | 50OHM_Y12MIL | BUS | 2 | 6 | 5 | 10 | 5 | 14 | 6 | 15 | 12 | 12 | 12 | 12 |  | 50 Ohms-3 | TOP=L2:L3=L2/L4:L6=L5/L7:BOTTOM=L7 |
| SSD_ACT_DR3_R | 50OHM_Y12MIL | BUS | 3 | 6 | 5 | 10 | 5 | 14 | 6 | 15 | 12 | 12 | 12 | 12 |  | 50 Ohms-3 | TOP=L2:L3=L2/L4:L6=L5/L7:BOTTOM=L7 |
| SSD_ACT_DR3_R | 50OHM_Y12MIL | BUS | 4 | 6 | 5 | 10 | 5 | 14 | 6 | 15 | 12 | 12 | 12 | 12 |  | 50 Ohms-3 | TOP=L2:L3=L2/L4:L6=L5/L7:BOTTOM=L7 |
| SSD_ACT_DR3_R | 50OHM_Y12MIL | BUS | 5 | 6 | 5 | 10 | 5 | 14 | 6 | 15 | 12 | 12 | 12 | 12 |  | 50 Ohms-3 | TOP=L2:L3=L2/L4:L6=L5/L7:BOTTOM=L7 |
| SSD_ACT_DR3_R | 50OHM_Y12MIL | BUS | 6 | 6 | 5 | 10 | 5 | 14 | 6 | 15 | 12 | 12 | 12 | 12 |  | 50 Ohms-3 | TOP=L2:L3=L2/L4:L6=L5/L7:BOTTOM=L7 |
| SSD_ACT_DR3_R | 50OHM_Y12MIL | BUS | 7 | 6 | 5 | 10 | 5 | 14 | 6 | 15 | 12 | 12 | 12 | 12 |  | 50 Ohms-3 | TOP=L2:L3=L2/L4:L6=L5/L7:BOTTOM=L7 |
| SSD_ACT_DR3_R | 50OHM_Y12MIL | BUS | 8 | 6.75 | 5 | 10 | 5 | 14 | 6 | 15 | 12 | 12 | 12 | 12 |  | 50 Ohms-3 | TOP=L2:L3=L2/L4:L6=L5/L7:BOTTOM=L7 |
| SSD_ACT_DR4 | 50OHM_Y12MIL | BUS | 1 | 6.75 | 5 | 10 | 5 | 14 | 6 | 15 | 12 | 12 | 12 | 12 |  | 50 Ohms-3 | TOP=L2:L3=L2/L4:L6=L5/L7:BOTTOM=L7 |
| SSD_ACT_DR4 | 50OHM_Y12MIL | BUS | 2 | 6 | 5 | 10 | 5 | 14 | 6 | 15 | 12 | 12 | 12 | 12 |  | 50 Ohms-3 | TOP=L2:L3=L2/L4:L6=L5/L7:BOTTOM=L7 |
| SSD_ACT_DR4 | 50OHM_Y12MIL | BUS | 3 | 6 | 5 | 10 | 5 | 14 | 6 | 15 | 12 | 12 | 12 | 12 |  | 50 Ohms-3 | TOP=L2:L3=L2/L4:L6=L5/L7:BOTTOM=L7 |
| SSD_ACT_DR4 | 50OHM_Y12MIL | BUS | 4 | 6 | 5 | 10 | 5 | 14 | 6 | 15 | 12 | 12 | 12 | 12 |  | 50 Ohms-3 | TOP=L2:L3=L2/L4:L6=L5/L7:BOTTOM=L7 |
| SSD_ACT_DR4 | 50OHM_Y12MIL | BUS | 5 | 6 | 5 | 10 | 5 | 14 | 6 | 15 | 12 | 12 | 12 | 12 |  | 50 Ohms-3 | TOP=L2:L3=L2/L4:L6=L5/L7:BOTTOM=L7 |
| SSD_ACT_DR4 | 50OHM_Y12MIL | BUS | 6 | 6 | 5 | 10 | 5 | 14 | 6 | 15 | 12 | 12 | 12 | 12 |  | 50 Ohms-3 | TOP=L2:L3=L2/L4:L6=L5/L7:BOTTOM=L7 |
| SSD_ACT_DR4 | 50OHM_Y12MIL | BUS | 7 | 6 | 5 | 10 | 5 | 14 | 6 | 15 | 12 | 12 | 12 | 12 |  | 50 Ohms-3 | TOP=L2:L3=L2/L4:L6=L5/L7:BOTTOM=L7 |
| SSD_ACT_DR4 | 50OHM_Y12MIL | BUS | 8 | 6.75 | 5 | 10 | 5 | 14 | 6 | 15 | 12 | 12 | 12 | 12 |  | 50 Ohms-3 | TOP=L2:L3=L2/L4:L6=L5/L7:BOTTOM=L7 |
| SSD_ACT_DR4_MOS_N | 50OHM_Y12MIL | BUS | 1 | 6.75 | 5 | 10 | 5 | 14 | 6 | 15 | 12 | 12 | 12 | 12 |  | 50 Ohms-3 | TOP=L2:L3=L2/L4:L6=L5/L7:BOTTOM=L7 |
| SSD_ACT_DR4_MOS_N | 50OHM_Y12MIL | BUS | 2 | 6 | 5 | 10 | 5 | 14 | 6 | 15 | 12 | 12 | 12 | 12 |  | 50 Ohms-3 | TOP=L2:L3=L2/L4:L6=L5/L7:BOTTOM=L7 |
| SSD_ACT_DR4_MOS_N | 50OHM_Y12MIL | BUS | 3 | 6 | 5 | 10 | 5 | 14 | 6 | 15 | 12 | 12 | 12 | 12 |  | 50 Ohms-3 | TOP=L2:L3=L2/L4:L6=L5/L7:BOTTOM=L7 |
| SSD_ACT_DR4_MOS_N | 50OHM_Y12MIL | BUS | 4 | 6 | 5 | 10 | 5 | 14 | 6 | 15 | 12 | 12 | 12 | 12 |  | 50 Ohms-3 | TOP=L2:L3=L2/L4:L6=L5/L7:BOTTOM=L7 |
| SSD_ACT_DR4_MOS_N | 50OHM_Y12MIL | BUS | 5 | 6 | 5 | 10 | 5 | 14 | 6 | 15 | 12 | 12 | 12 | 12 |  | 50 Ohms-3 | TOP=L2:L3=L2/L4:L6=L5/L7:BOTTOM=L7 |
| SSD_ACT_DR4_MOS_N | 50OHM_Y12MIL | BUS | 6 | 6 | 5 | 10 | 5 | 14 | 6 | 15 | 12 | 12 | 12 | 12 |  | 50 Ohms-3 | TOP=L2:L3=L2/L4:L6=L5/L7:BOTTOM=L7 |
| SSD_ACT_DR4_MOS_N | 50OHM_Y12MIL | BUS | 7 | 6 | 5 | 10 | 5 | 14 | 6 | 15 | 12 | 12 | 12 | 12 |  | 50 Ohms-3 | TOP=L2:L3=L2/L4:L6=L5/L7:BOTTOM=L7 |
| SSD_ACT_DR4_MOS_N | 50OHM_Y12MIL | BUS | 8 | 6.75 | 5 | 10 | 5 | 14 | 6 | 15 | 12 | 12 | 12 | 12 |  | 50 Ohms-3 | TOP=L2:L3=L2/L4:L6=L5/L7:BOTTOM=L7 |
| SSD_ACT_DR4_R | 50OHM_Y12MIL | BUS | 1 | 6.75 | 5 | 10 | 5 | 14 | 6 | 15 | 12 | 12 | 12 | 12 |  | 50 Ohms-3 | TOP=L2:L3=L2/L4:L6=L5/L7:BOTTOM=L7 |
| SSD_ACT_DR4_R | 50OHM_Y12MIL | BUS | 2 | 6 | 5 | 10 | 5 | 14 | 6 | 15 | 12 | 12 | 12 | 12 |  | 50 Ohms-3 | TOP=L2:L3=L2/L4:L6=L5/L7:BOTTOM=L7 |
| SSD_ACT_DR4_R | 50OHM_Y12MIL | BUS | 3 | 6 | 5 | 10 | 5 | 14 | 6 | 15 | 12 | 12 | 12 | 12 |  | 50 Ohms-3 | TOP=L2:L3=L2/L4:L6=L5/L7:BOTTOM=L7 |
| SSD_ACT_DR4_R | 50OHM_Y12MIL | BUS | 4 | 6 | 5 | 10 | 5 | 14 | 6 | 15 | 12 | 12 | 12 | 12 |  | 50 Ohms-3 | TOP=L2:L3=L2/L4:L6=L5/L7:BOTTOM=L7 |
| SSD_ACT_DR4_R | 50OHM_Y12MIL | BUS | 5 | 6 | 5 | 10 | 5 | 14 | 6 | 15 | 12 | 12 | 12 | 12 |  | 50 Ohms-3 | TOP=L2:L3=L2/L4:L6=L5/L7:BOTTOM=L7 |
| SSD_ACT_DR4_R | 50OHM_Y12MIL | BUS | 6 | 6 | 5 | 10 | 5 | 14 | 6 | 15 | 12 | 12 | 12 | 12 |  | 50 Ohms-3 | TOP=L2:L3=L2/L4:L6=L5/L7:BOTTOM=L7 |
| SSD_ACT_DR4_R | 50OHM_Y12MIL | BUS | 7 | 6 | 5 | 10 | 5 | 14 | 6 | 15 | 12 | 12 | 12 | 12 |  | 50 Ohms-3 | TOP=L2:L3=L2/L4:L6=L5/L7:BOTTOM=L7 |
| SSD_ACT_DR4_R | 50OHM_Y12MIL | BUS | 8 | 6.75 | 5 | 10 | 5 | 14 | 6 | 15 | 12 | 12 | 12 | 12 |  | 50 Ohms-3 | TOP=L2:L3=L2/L4:L6=L5/L7:BOTTOM=L7 |
| SSD_ACT_DR5 | 50OHM_Y12MIL | BUS | 1 | 6.75 | 5 | 10 | 5 | 14 | 6 | 15 | 12 | 12 | 12 | 12 |  | 50 Ohms-3 | TOP=L2:L3=L2/L4:L6=L5/L7:BOTTOM=L7 |
| SSD_ACT_DR5 | 50OHM_Y12MIL | BUS | 2 | 6 | 5 | 10 | 5 | 14 | 6 | 15 | 12 | 12 | 12 | 12 |  | 50 Ohms-3 | TOP=L2:L3=L2/L4:L6=L5/L7:BOTTOM=L7 |
| SSD_ACT_DR5 | 50OHM_Y12MIL | BUS | 3 | 6 | 5 | 10 | 5 | 14 | 6 | 15 | 12 | 12 | 12 | 12 |  | 50 Ohms-3 | TOP=L2:L3=L2/L4:L6=L5/L7:BOTTOM=L7 |
| SSD_ACT_DR5 | 50OHM_Y12MIL | BUS | 4 | 6 | 5 | 10 | 5 | 14 | 6 | 15 | 12 | 12 | 12 | 12 |  | 50 Ohms-3 | TOP=L2:L3=L2/L4:L6=L5/L7:BOTTOM=L7 |
| SSD_ACT_DR5 | 50OHM_Y12MIL | BUS | 5 | 6 | 5 | 10 | 5 | 14 | 6 | 15 | 12 | 12 | 12 | 12 |  | 50 Ohms-3 | TOP=L2:L3=L2/L4:L6=L5/L7:BOTTOM=L7 |
| SSD_ACT_DR5 | 50OHM_Y12MIL | BUS | 6 | 6 | 5 | 10 | 5 | 14 | 6 | 15 | 12 | 12 | 12 | 12 |  | 50 Ohms-3 | TOP=L2:L3=L2/L4:L6=L5/L7:BOTTOM=L7 |
| SSD_ACT_DR5 | 50OHM_Y12MIL | BUS | 7 | 6 | 5 | 10 | 5 | 14 | 6 | 15 | 12 | 12 | 12 | 12 |  | 50 Ohms-3 | TOP=L2:L3=L2/L4:L6=L5/L7:BOTTOM=L7 |
| SSD_ACT_DR5 | 50OHM_Y12MIL | BUS | 8 | 6.75 | 5 | 10 | 5 | 14 | 6 | 15 | 12 | 12 | 12 | 12 |  | 50 Ohms-3 | TOP=L2:L3=L2/L4:L6=L5/L7:BOTTOM=L7 |
| SSD_ACT_DR5_MOS_N | 50OHM_Y12MIL | BUS | 1 | 6.75 | 5 | 10 | 5 | 14 | 6 | 15 | 12 | 12 | 12 | 12 |  | 50 Ohms-3 | TOP=L2:L3=L2/L4:L6=L5/L7:BOTTOM=L7 |
| SSD_ACT_DR5_MOS_N | 50OHM_Y12MIL | BUS | 2 | 6 | 5 | 10 | 5 | 14 | 6 | 15 | 12 | 12 | 12 | 12 |  | 50 Ohms-3 | TOP=L2:L3=L2/L4:L6=L5/L7:BOTTOM=L7 |
| SSD_ACT_DR5_MOS_N | 50OHM_Y12MIL | BUS | 3 | 6 | 5 | 10 | 5 | 14 | 6 | 15 | 12 | 12 | 12 | 12 |  | 50 Ohms-3 | TOP=L2:L3=L2/L4:L6=L5/L7:BOTTOM=L7 |
| SSD_ACT_DR5_MOS_N | 50OHM_Y12MIL | BUS | 4 | 6 | 5 | 10 | 5 | 14 | 6 | 15 | 12 | 12 | 12 | 12 |  | 50 Ohms-3 | TOP=L2:L3=L2/L4:L6=L5/L7:BOTTOM=L7 |
| SSD_ACT_DR5_MOS_N | 50OHM_Y12MIL | BUS | 5 | 6 | 5 | 10 | 5 | 14 | 6 | 15 | 12 | 12 | 12 | 12 |  | 50 Ohms-3 | TOP=L2:L3=L2/L4:L6=L5/L7:BOTTOM=L7 |
| SSD_ACT_DR5_MOS_N | 50OHM_Y12MIL | BUS | 6 | 6 | 5 | 10 | 5 | 14 | 6 | 15 | 12 | 12 | 12 | 12 |  | 50 Ohms-3 | TOP=L2:L3=L2/L4:L6=L5/L7:BOTTOM=L7 |
| SSD_ACT_DR5_MOS_N | 50OHM_Y12MIL | BUS | 7 | 6 | 5 | 10 | 5 | 14 | 6 | 15 | 12 | 12 | 12 | 12 |  | 50 Ohms-3 | TOP=L2:L3=L2/L4:L6=L5/L7:BOTTOM=L7 |
| SSD_ACT_DR5_MOS_N | 50OHM_Y12MIL | BUS | 8 | 6.75 | 5 | 10 | 5 | 14 | 6 | 15 | 12 | 12 | 12 | 12 |  | 50 Ohms-3 | TOP=L2:L3=L2/L4:L6=L5/L7:BOTTOM=L7 |
| SSD_ACT_DR5_R | 50OHM_Y12MIL | BUS | 1 | 6.75 | 5 | 10 | 5 | 14 | 6 | 15 | 12 | 12 | 12 | 12 |  | 50 Ohms-3 | TOP=L2:L3=L2/L4:L6=L5/L7:BOTTOM=L7 |
| SSD_ACT_DR5_R | 50OHM_Y12MIL | BUS | 2 | 6 | 5 | 10 | 5 | 14 | 6 | 15 | 12 | 12 | 12 | 12 |  | 50 Ohms-3 | TOP=L2:L3=L2/L4:L6=L5/L7:BOTTOM=L7 |
| SSD_ACT_DR5_R | 50OHM_Y12MIL | BUS | 3 | 6 | 5 | 10 | 5 | 14 | 6 | 15 | 12 | 12 | 12 | 12 |  | 50 Ohms-3 | TOP=L2:L3=L2/L4:L6=L5/L7:BOTTOM=L7 |
| SSD_ACT_DR5_R | 50OHM_Y12MIL | BUS | 4 | 6 | 5 | 10 | 5 | 14 | 6 | 15 | 12 | 12 | 12 | 12 |  | 50 Ohms-3 | TOP=L2:L3=L2/L4:L6=L5/L7:BOTTOM=L7 |
| SSD_ACT_DR5_R | 50OHM_Y12MIL | BUS | 5 | 6 | 5 | 10 | 5 | 14 | 6 | 15 | 12 | 12 | 12 | 12 |  | 50 Ohms-3 | TOP=L2:L3=L2/L4:L6=L5/L7:BOTTOM=L7 |
| SSD_ACT_DR5_R | 50OHM_Y12MIL | BUS | 6 | 6 | 5 | 10 | 5 | 14 | 6 | 15 | 12 | 12 | 12 | 12 |  | 50 Ohms-3 | TOP=L2:L3=L2/L4:L6=L5/L7:BOTTOM=L7 |
| SSD_ACT_DR5_R | 50OHM_Y12MIL | BUS | 7 | 6 | 5 | 10 | 5 | 14 | 6 | 15 | 12 | 12 | 12 | 12 |  | 50 Ohms-3 | TOP=L2:L3=L2/L4:L6=L5/L7:BOTTOM=L7 |
| SSD_ACT_DR5_R | 50OHM_Y12MIL | BUS | 8 | 6.75 | 5 | 10 | 5 | 14 | 6 | 15 | 12 | 12 | 12 | 12 |  | 50 Ohms-3 | TOP=L2:L3=L2/L4:L6=L5/L7:BOTTOM=L7 |
| SSD_ACT_DR6 | 50OHM_Y12MIL | BUS | 1 | 6.75 | 5 | 10 | 5 | 14 | 6 | 15 | 12 | 12 | 12 | 12 |  | 50 Ohms-3 | TOP=L2:L3=L2/L4:L6=L5/L7:BOTTOM=L7 |
| SSD_ACT_DR6 | 50OHM_Y12MIL | BUS | 2 | 6 | 5 | 10 | 5 | 14 | 6 | 15 | 12 | 12 | 12 | 12 |  | 50 Ohms-3 | TOP=L2:L3=L2/L4:L6=L5/L7:BOTTOM=L7 |
| SSD_ACT_DR6 | 50OHM_Y12MIL | BUS | 3 | 6 | 5 | 10 | 5 | 14 | 6 | 15 | 12 | 12 | 12 | 12 |  | 50 Ohms-3 | TOP=L2:L3=L2/L4:L6=L5/L7:BOTTOM=L7 |
| SSD_ACT_DR6 | 50OHM_Y12MIL | BUS | 4 | 6 | 5 | 10 | 5 | 14 | 6 | 15 | 12 | 12 | 12 | 12 |  | 50 Ohms-3 | TOP=L2:L3=L2/L4:L6=L5/L7:BOTTOM=L7 |
| SSD_ACT_DR6 | 50OHM_Y12MIL | BUS | 5 | 6 | 5 | 10 | 5 | 14 | 6 | 15 | 12 | 12 | 12 | 12 |  | 50 Ohms-3 | TOP=L2:L3=L2/L4:L6=L5/L7:BOTTOM=L7 |
| SSD_ACT_DR6 | 50OHM_Y12MIL | BUS | 6 | 6 | 5 | 10 | 5 | 14 | 6 | 15 | 12 | 12 | 12 | 12 |  | 50 Ohms-3 | TOP=L2:L3=L2/L4:L6=L5/L7:BOTTOM=L7 |
| SSD_ACT_DR6 | 50OHM_Y12MIL | BUS | 7 | 6 | 5 | 10 | 5 | 14 | 6 | 15 | 12 | 12 | 12 | 12 |  | 50 Ohms-3 | TOP=L2:L3=L2/L4:L6=L5/L7:BOTTOM=L7 |
| SSD_ACT_DR6 | 50OHM_Y12MIL | BUS | 8 | 6.75 | 5 | 10 | 5 | 14 | 6 | 15 | 12 | 12 | 12 | 12 |  | 50 Ohms-3 | TOP=L2:L3=L2/L4:L6=L5/L7:BOTTOM=L7 |
| SSD_ACT_DR6_MOS_N | 50OHM_Y12MIL | BUS | 1 | 6.75 | 5 | 10 | 5 | 14 | 6 | 15 | 12 | 12 | 12 | 12 |  | 50 Ohms-3 | TOP=L2:L3=L2/L4:L6=L5/L7:BOTTOM=L7 |
| SSD_ACT_DR6_MOS_N | 50OHM_Y12MIL | BUS | 2 | 6 | 5 | 10 | 5 | 14 | 6 | 15 | 12 | 12 | 12 | 12 |  | 50 Ohms-3 | TOP=L2:L3=L2/L4:L6=L5/L7:BOTTOM=L7 |
| SSD_ACT_DR6_MOS_N | 50OHM_Y12MIL | BUS | 3 | 6 | 5 | 10 | 5 | 14 | 6 | 15 | 12 | 12 | 12 | 12 |  | 50 Ohms-3 | TOP=L2:L3=L2/L4:L6=L5/L7:BOTTOM=L7 |
| SSD_ACT_DR6_MOS_N | 50OHM_Y12MIL | BUS | 4 | 6 | 5 | 10 | 5 | 14 | 6 | 15 | 12 | 12 | 12 | 12 |  | 50 Ohms-3 | TOP=L2:L3=L2/L4:L6=L5/L7:BOTTOM=L7 |
| SSD_ACT_DR6_MOS_N | 50OHM_Y12MIL | BUS | 5 | 6 | 5 | 10 | 5 | 14 | 6 | 15 | 12 | 12 | 12 | 12 |  | 50 Ohms-3 | TOP=L2:L3=L2/L4:L6=L5/L7:BOTTOM=L7 |
| SSD_ACT_DR6_MOS_N | 50OHM_Y12MIL | BUS | 6 | 6 | 5 | 10 | 5 | 14 | 6 | 15 | 12 | 12 | 12 | 12 |  | 50 Ohms-3 | TOP=L2:L3=L2/L4:L6=L5/L7:BOTTOM=L7 |
| SSD_ACT_DR6_MOS_N | 50OHM_Y12MIL | BUS | 7 | 6 | 5 | 10 | 5 | 14 | 6 | 15 | 12 | 12 | 12 | 12 |  | 50 Ohms-3 | TOP=L2:L3=L2/L4:L6=L5/L7:BOTTOM=L7 |
| SSD_ACT_DR6_MOS_N | 50OHM_Y12MIL | BUS | 8 | 6.75 | 5 | 10 | 5 | 14 | 6 | 15 | 12 | 12 | 12 | 12 |  | 50 Ohms-3 | TOP=L2:L3=L2/L4:L6=L5/L7:BOTTOM=L7 |
| SSD_ACT_DR6_R | 50OHM_Y12MIL | BUS | 1 | 6.75 | 5 | 10 | 5 | 14 | 6 | 15 | 12 | 12 | 12 | 12 |  | 50 Ohms-3 | TOP=L2:L3=L2/L4:L6=L5/L7:BOTTOM=L7 |
| SSD_ACT_DR6_R | 50OHM_Y12MIL | BUS | 2 | 6 | 5 | 10 | 5 | 14 | 6 | 15 | 12 | 12 | 12 | 12 |  | 50 Ohms-3 | TOP=L2:L3=L2/L4:L6=L5/L7:BOTTOM=L7 |
| SSD_ACT_DR6_R | 50OHM_Y12MIL | BUS | 3 | 6 | 5 | 10 | 5 | 14 | 6 | 15 | 12 | 12 | 12 | 12 |  | 50 Ohms-3 | TOP=L2:L3=L2/L4:L6=L5/L7:BOTTOM=L7 |
| SSD_ACT_DR6_R | 50OHM_Y12MIL | BUS | 4 | 6 | 5 | 10 | 5 | 14 | 6 | 15 | 12 | 12 | 12 | 12 |  | 50 Ohms-3 | TOP=L2:L3=L2/L4:L6=L5/L7:BOTTOM=L7 |
| SSD_ACT_DR6_R | 50OHM_Y12MIL | BUS | 5 | 6 | 5 | 10 | 5 | 14 | 6 | 15 | 12 | 12 | 12 | 12 |  | 50 Ohms-3 | TOP=L2:L3=L2/L4:L6=L5/L7:BOTTOM=L7 |
| SSD_ACT_DR6_R | 50OHM_Y12MIL | BUS | 6 | 6 | 5 | 10 | 5 | 14 | 6 | 15 | 12 | 12 | 12 | 12 |  | 50 Ohms-3 | TOP=L2:L3=L2/L4:L6=L5/L7:BOTTOM=L7 |
| SSD_ACT_DR6_R | 50OHM_Y12MIL | BUS | 7 | 6 | 5 | 10 | 5 | 14 | 6 | 15 | 12 | 12 | 12 | 12 |  | 50 Ohms-3 | TOP=L2:L3=L2/L4:L6=L5/L7:BOTTOM=L7 |
| SSD_ACT_DR6_R | 50OHM_Y12MIL | BUS | 8 | 6.75 | 5 | 10 | 5 | 14 | 6 | 15 | 12 | 12 | 12 | 12 |  | 50 Ohms-3 | TOP=L2:L3=L2/L4:L6=L5/L7:BOTTOM=L7 |
| SSD_ACT_DR7 | 50OHM_Y12MIL | BUS | 1 | 6.75 | 5 | 10 | 5 | 14 | 6 | 15 | 12 | 12 | 12 | 12 |  | 50 Ohms-3 | TOP=L2:L3=L2/L4:L6=L5/L7:BOTTOM=L7 |
| SSD_ACT_DR7 | 50OHM_Y12MIL | BUS | 2 | 6 | 5 | 10 | 5 | 14 | 6 | 15 | 12 | 12 | 12 | 12 |  | 50 Ohms-3 | TOP=L2:L3=L2/L4:L6=L5/L7:BOTTOM=L7 |
| SSD_ACT_DR7 | 50OHM_Y12MIL | BUS | 3 | 6 | 5 | 10 | 5 | 14 | 6 | 15 | 12 | 12 | 12 | 12 |  | 50 Ohms-3 | TOP=L2:L3=L2/L4:L6=L5/L7:BOTTOM=L7 |
| SSD_ACT_DR7 | 50OHM_Y12MIL | BUS | 4 | 6 | 5 | 10 | 5 | 14 | 6 | 15 | 12 | 12 | 12 | 12 |  | 50 Ohms-3 | TOP=L2:L3=L2/L4:L6=L5/L7:BOTTOM=L7 |
| SSD_ACT_DR7 | 50OHM_Y12MIL | BUS | 5 | 6 | 5 | 10 | 5 | 14 | 6 | 15 | 12 | 12 | 12 | 12 |  | 50 Ohms-3 | TOP=L2:L3=L2/L4:L6=L5/L7:BOTTOM=L7 |
| SSD_ACT_DR7 | 50OHM_Y12MIL | BUS | 6 | 6 | 5 | 10 | 5 | 14 | 6 | 15 | 12 | 12 | 12 | 12 |  | 50 Ohms-3 | TOP=L2:L3=L2/L4:L6=L5/L7:BOTTOM=L7 |
| SSD_ACT_DR7 | 50OHM_Y12MIL | BUS | 7 | 6 | 5 | 10 | 5 | 14 | 6 | 15 | 12 | 12 | 12 | 12 |  | 50 Ohms-3 | TOP=L2:L3=L2/L4:L6=L5/L7:BOTTOM=L7 |
| SSD_ACT_DR7 | 50OHM_Y12MIL | BUS | 8 | 6.75 | 5 | 10 | 5 | 14 | 6 | 15 | 12 | 12 | 12 | 12 |  | 50 Ohms-3 | TOP=L2:L3=L2/L4:L6=L5/L7:BOTTOM=L7 |
| SSD_ACT_DR7_MOS_N | 50OHM_Y12MIL | BUS | 1 | 6.75 | 5 | 10 | 5 | 14 | 6 | 15 | 12 | 12 | 12 | 12 |  | 50 Ohms-3 | TOP=L2:L3=L2/L4:L6=L5/L7:BOTTOM=L7 |
| SSD_ACT_DR7_MOS_N | 50OHM_Y12MIL | BUS | 2 | 6 | 5 | 10 | 5 | 14 | 6 | 15 | 12 | 12 | 12 | 12 |  | 50 Ohms-3 | TOP=L2:L3=L2/L4:L6=L5/L7:BOTTOM=L7 |
| SSD_ACT_DR7_MOS_N | 50OHM_Y12MIL | BUS | 3 | 6 | 5 | 10 | 5 | 14 | 6 | 15 | 12 | 12 | 12 | 12 |  | 50 Ohms-3 | TOP=L2:L3=L2/L4:L6=L5/L7:BOTTOM=L7 |
| SSD_ACT_DR7_MOS_N | 50OHM_Y12MIL | BUS | 4 | 6 | 5 | 10 | 5 | 14 | 6 | 15 | 12 | 12 | 12 | 12 |  | 50 Ohms-3 | TOP=L2:L3=L2/L4:L6=L5/L7:BOTTOM=L7 |
| SSD_ACT_DR7_MOS_N | 50OHM_Y12MIL | BUS | 5 | 6 | 5 | 10 | 5 | 14 | 6 | 15 | 12 | 12 | 12 | 12 |  | 50 Ohms-3 | TOP=L2:L3=L2/L4:L6=L5/L7:BOTTOM=L7 |
| SSD_ACT_DR7_MOS_N | 50OHM_Y12MIL | BUS | 6 | 6 | 5 | 10 | 5 | 14 | 6 | 15 | 12 | 12 | 12 | 12 |  | 50 Ohms-3 | TOP=L2:L3=L2/L4:L6=L5/L7:BOTTOM=L7 |
| SSD_ACT_DR7_MOS_N | 50OHM_Y12MIL | BUS | 7 | 6 | 5 | 10 | 5 | 14 | 6 | 15 | 12 | 12 | 12 | 12 |  | 50 Ohms-3 | TOP=L2:L3=L2/L4:L6=L5/L7:BOTTOM=L7 |
| SSD_ACT_DR7_MOS_N | 50OHM_Y12MIL | BUS | 8 | 6.75 | 5 | 10 | 5 | 14 | 6 | 15 | 12 | 12 | 12 | 12 |  | 50 Ohms-3 | TOP=L2:L3=L2/L4:L6=L5/L7:BOTTOM=L7 |
| SSD_ACT_DR7_R | 50OHM_Y12MIL | BUS | 1 | 6.75 | 5 | 10 | 5 | 14 | 6 | 15 | 12 | 12 | 12 | 12 |  | 50 Ohms-3 | TOP=L2:L3=L2/L4:L6=L5/L7:BOTTOM=L7 |
| SSD_ACT_DR7_R | 50OHM_Y12MIL | BUS | 2 | 6 | 5 | 10 | 5 | 14 | 6 | 15 | 12 | 12 | 12 | 12 |  | 50 Ohms-3 | TOP=L2:L3=L2/L4:L6=L5/L7:BOTTOM=L7 |
| SSD_ACT_DR7_R | 50OHM_Y12MIL | BUS | 3 | 6 | 5 | 10 | 5 | 14 | 6 | 15 | 12 | 12 | 12 | 12 |  | 50 Ohms-3 | TOP=L2:L3=L2/L4:L6=L5/L7:BOTTOM=L7 |
| SSD_ACT_DR7_R | 50OHM_Y12MIL | BUS | 4 | 6 | 5 | 10 | 5 | 14 | 6 | 15 | 12 | 12 | 12 | 12 |  | 50 Ohms-3 | TOP=L2:L3=L2/L4:L6=L5/L7:BOTTOM=L7 |
| SSD_ACT_DR7_R | 50OHM_Y12MIL | BUS | 5 | 6 | 5 | 10 | 5 | 14 | 6 | 15 | 12 | 12 | 12 | 12 |  | 50 Ohms-3 | TOP=L2:L3=L2/L4:L6=L5/L7:BOTTOM=L7 |
| SSD_ACT_DR7_R | 50OHM_Y12MIL | BUS | 6 | 6 | 5 | 10 | 5 | 14 | 6 | 15 | 12 | 12 | 12 | 12 |  | 50 Ohms-3 | TOP=L2:L3=L2/L4:L6=L5/L7:BOTTOM=L7 |
| SSD_ACT_DR7_R | 50OHM_Y12MIL | BUS | 7 | 6 | 5 | 10 | 5 | 14 | 6 | 15 | 12 | 12 | 12 | 12 |  | 50 Ohms-3 | TOP=L2:L3=L2/L4:L6=L5/L7:BOTTOM=L7 |
| SSD_ACT_DR7_R | 50OHM_Y12MIL | BUS | 8 | 6.75 | 5 | 10 | 5 | 14 | 6 | 15 | 12 | 12 | 12 | 12 |  | 50 Ohms-3 | TOP=L2:L3=L2/L4:L6=L5/L7:BOTTOM=L7 |
| SSD_ACT_DR8 | 50OHM_Y12MIL | BUS | 1 | 6.75 | 5 | 10 | 5 | 14 | 6 | 15 | 12 | 12 | 12 | 12 |  | 50 Ohms-3 | TOP=L2:L3=L2/L4:L6=L5/L7:BOTTOM=L7 |
| SSD_ACT_DR8 | 50OHM_Y12MIL | BUS | 2 | 6 | 5 | 10 | 5 | 14 | 6 | 15 | 12 | 12 | 12 | 12 |  | 50 Ohms-3 | TOP=L2:L3=L2/L4:L6=L5/L7:BOTTOM=L7 |
| SSD_ACT_DR8 | 50OHM_Y12MIL | BUS | 3 | 6 | 5 | 10 | 5 | 14 | 6 | 15 | 12 | 12 | 12 | 12 |  | 50 Ohms-3 | TOP=L2:L3=L2/L4:L6=L5/L7:BOTTOM=L7 |
| SSD_ACT_DR8 | 50OHM_Y12MIL | BUS | 4 | 6 | 5 | 10 | 5 | 14 | 6 | 15 | 12 | 12 | 12 | 12 |  | 50 Ohms-3 | TOP=L2:L3=L2/L4:L6=L5/L7:BOTTOM=L7 |
| SSD_ACT_DR8 | 50OHM_Y12MIL | BUS | 5 | 6 | 5 | 10 | 5 | 14 | 6 | 15 | 12 | 12 | 12 | 12 |  | 50 Ohms-3 | TOP=L2:L3=L2/L4:L6=L5/L7:BOTTOM=L7 |
| SSD_ACT_DR8 | 50OHM_Y12MIL | BUS | 6 | 6 | 5 | 10 | 5 | 14 | 6 | 15 | 12 | 12 | 12 | 12 |  | 50 Ohms-3 | TOP=L2:L3=L2/L4:L6=L5/L7:BOTTOM=L7 |
| SSD_ACT_DR8 | 50OHM_Y12MIL | BUS | 7 | 6 | 5 | 10 | 5 | 14 | 6 | 15 | 12 | 12 | 12 | 12 |  | 50 Ohms-3 | TOP=L2:L3=L2/L4:L6=L5/L7:BOTTOM=L7 |
| SSD_ACT_DR8 | 50OHM_Y12MIL | BUS | 8 | 6.75 | 5 | 10 | 5 | 14 | 6 | 15 | 12 | 12 | 12 | 12 |  | 50 Ohms-3 | TOP=L2:L3=L2/L4:L6=L5/L7:BOTTOM=L7 |
| SSD_ACT_DR8_MOS_N | 50OHM_Y12MIL | BUS | 1 | 6.75 | 5 | 10 | 5 | 14 | 6 | 15 | 12 | 12 | 12 | 12 |  | 50 Ohms-3 | TOP=L2:L3=L2/L4:L6=L5/L7:BOTTOM=L7 |
| SSD_ACT_DR8_MOS_N | 50OHM_Y12MIL | BUS | 2 | 6 | 5 | 10 | 5 | 14 | 6 | 15 | 12 | 12 | 12 | 12 |  | 50 Ohms-3 | TOP=L2:L3=L2/L4:L6=L5/L7:BOTTOM=L7 |
| SSD_ACT_DR8_MOS_N | 50OHM_Y12MIL | BUS | 3 | 6 | 5 | 10 | 5 | 14 | 6 | 15 | 12 | 12 | 12 | 12 |  | 50 Ohms-3 | TOP=L2:L3=L2/L4:L6=L5/L7:BOTTOM=L7 |
| SSD_ACT_DR8_MOS_N | 50OHM_Y12MIL | BUS | 4 | 6 | 5 | 10 | 5 | 14 | 6 | 15 | 12 | 12 | 12 | 12 |  | 50 Ohms-3 | TOP=L2:L3=L2/L4:L6=L5/L7:BOTTOM=L7 |
| SSD_ACT_DR8_MOS_N | 50OHM_Y12MIL | BUS | 5 | 6 | 5 | 10 | 5 | 14 | 6 | 15 | 12 | 12 | 12 | 12 |  | 50 Ohms-3 | TOP=L2:L3=L2/L4:L6=L5/L7:BOTTOM=L7 |
| SSD_ACT_DR8_MOS_N | 50OHM_Y12MIL | BUS | 6 | 6 | 5 | 10 | 5 | 14 | 6 | 15 | 12 | 12 | 12 | 12 |  | 50 Ohms-3 | TOP=L2:L3=L2/L4:L6=L5/L7:BOTTOM=L7 |
| SSD_ACT_DR8_MOS_N | 50OHM_Y12MIL | BUS | 7 | 6 | 5 | 10 | 5 | 14 | 6 | 15 | 12 | 12 | 12 | 12 |  | 50 Ohms-3 | TOP=L2:L3=L2/L4:L6=L5/L7:BOTTOM=L7 |
| SSD_ACT_DR8_MOS_N | 50OHM_Y12MIL | BUS | 8 | 6.75 | 5 | 10 | 5 | 14 | 6 | 15 | 12 | 12 | 12 | 12 |  | 50 Ohms-3 | TOP=L2:L3=L2/L4:L6=L5/L7:BOTTOM=L7 |
| SSD_ACT_DR8_R | 50OHM_Y12MIL | BUS | 1 | 6.75 | 5 | 10 | 5 | 14 | 6 | 15 | 12 | 12 | 12 | 12 |  | 50 Ohms-3 | TOP=L2:L3=L2/L4:L6=L5/L7:BOTTOM=L7 |
| SSD_ACT_DR8_R | 50OHM_Y12MIL | BUS | 2 | 6 | 5 | 10 | 5 | 14 | 6 | 15 | 12 | 12 | 12 | 12 |  | 50 Ohms-3 | TOP=L2:L3=L2/L4:L6=L5/L7:BOTTOM=L7 |
| SSD_ACT_DR8_R | 50OHM_Y12MIL | BUS | 3 | 6 | 5 | 10 | 5 | 14 | 6 | 15 | 12 | 12 | 12 | 12 |  | 50 Ohms-3 | TOP=L2:L3=L2/L4:L6=L5/L7:BOTTOM=L7 |
| SSD_ACT_DR8_R | 50OHM_Y12MIL | BUS | 4 | 6 | 5 | 10 | 5 | 14 | 6 | 15 | 12 | 12 | 12 | 12 |  | 50 Ohms-3 | TOP=L2:L3=L2/L4:L6=L5/L7:BOTTOM=L7 |
| SSD_ACT_DR8_R | 50OHM_Y12MIL | BUS | 5 | 6 | 5 | 10 | 5 | 14 | 6 | 15 | 12 | 12 | 12 | 12 |  | 50 Ohms-3 | TOP=L2:L3=L2/L4:L6=L5/L7:BOTTOM=L7 |
| SSD_ACT_DR8_R | 50OHM_Y12MIL | BUS | 6 | 6 | 5 | 10 | 5 | 14 | 6 | 15 | 12 | 12 | 12 | 12 |  | 50 Ohms-3 | TOP=L2:L3=L2/L4:L6=L5/L7:BOTTOM=L7 |
| SSD_ACT_DR8_R | 50OHM_Y12MIL | BUS | 7 | 6 | 5 | 10 | 5 | 14 | 6 | 15 | 12 | 12 | 12 | 12 |  | 50 Ohms-3 | TOP=L2:L3=L2/L4:L6=L5/L7:BOTTOM=L7 |
| SSD_ACT_DR8_R | 50OHM_Y12MIL | BUS | 8 | 6.75 | 5 | 10 | 5 | 14 | 6 | 15 | 12 | 12 | 12 | 12 |  | 50 Ohms-3 | TOP=L2:L3=L2/L4:L6=L5/L7:BOTTOM=L7 |
| SSD_ACT_DR9 | 50OHM_Y12MIL | BUS | 1 | 6.75 | 5 | 10 | 5 | 14 | 6 | 15 | 12 | 12 | 12 | 12 |  | 50 Ohms-3 | TOP=L2:L3=L2/L4:L6=L5/L7:BOTTOM=L7 |
| SSD_ACT_DR9 | 50OHM_Y12MIL | BUS | 2 | 6 | 5 | 10 | 5 | 14 | 6 | 15 | 12 | 12 | 12 | 12 |  | 50 Ohms-3 | TOP=L2:L3=L2/L4:L6=L5/L7:BOTTOM=L7 |
| SSD_ACT_DR9 | 50OHM_Y12MIL | BUS | 3 | 6 | 5 | 10 | 5 | 14 | 6 | 15 | 12 | 12 | 12 | 12 |  | 50 Ohms-3 | TOP=L2:L3=L2/L4:L6=L5/L7:BOTTOM=L7 |
| SSD_ACT_DR9 | 50OHM_Y12MIL | BUS | 4 | 6 | 5 | 10 | 5 | 14 | 6 | 15 | 12 | 12 | 12 | 12 |  | 50 Ohms-3 | TOP=L2:L3=L2/L4:L6=L5/L7:BOTTOM=L7 |
| SSD_ACT_DR9 | 50OHM_Y12MIL | BUS | 5 | 6 | 5 | 10 | 5 | 14 | 6 | 15 | 12 | 12 | 12 | 12 |  | 50 Ohms-3 | TOP=L2:L3=L2/L4:L6=L5/L7:BOTTOM=L7 |
| SSD_ACT_DR9 | 50OHM_Y12MIL | BUS | 6 | 6 | 5 | 10 | 5 | 14 | 6 | 15 | 12 | 12 | 12 | 12 |  | 50 Ohms-3 | TOP=L2:L3=L2/L4:L6=L5/L7:BOTTOM=L7 |
| SSD_ACT_DR9 | 50OHM_Y12MIL | BUS | 7 | 6 | 5 | 10 | 5 | 14 | 6 | 15 | 12 | 12 | 12 | 12 |  | 50 Ohms-3 | TOP=L2:L3=L2/L4:L6=L5/L7:BOTTOM=L7 |
| SSD_ACT_DR9 | 50OHM_Y12MIL | BUS | 8 | 6.75 | 5 | 10 | 5 | 14 | 6 | 15 | 12 | 12 | 12 | 12 |  | 50 Ohms-3 | TOP=L2:L3=L2/L4:L6=L5/L7:BOTTOM=L7 |
| SSD_ACT_DR9_MOS_N | 50OHM_Y12MIL | BUS | 1 | 6.75 | 5 | 10 | 5 | 14 | 6 | 15 | 12 | 12 | 12 | 12 |  | 50 Ohms-3 | TOP=L2:L3=L2/L4:L6=L5/L7:BOTTOM=L7 |
| SSD_ACT_DR9_MOS_N | 50OHM_Y12MIL | BUS | 2 | 6 | 5 | 10 | 5 | 14 | 6 | 15 | 12 | 12 | 12 | 12 |  | 50 Ohms-3 | TOP=L2:L3=L2/L4:L6=L5/L7:BOTTOM=L7 |
| SSD_ACT_DR9_MOS_N | 50OHM_Y12MIL | BUS | 3 | 6 | 5 | 10 | 5 | 14 | 6 | 15 | 12 | 12 | 12 | 12 |  | 50 Ohms-3 | TOP=L2:L3=L2/L4:L6=L5/L7:BOTTOM=L7 |
| SSD_ACT_DR9_MOS_N | 50OHM_Y12MIL | BUS | 4 | 6 | 5 | 10 | 5 | 14 | 6 | 15 | 12 | 12 | 12 | 12 |  | 50 Ohms-3 | TOP=L2:L3=L2/L4:L6=L5/L7:BOTTOM=L7 |
| SSD_ACT_DR9_MOS_N | 50OHM_Y12MIL | BUS | 5 | 6 | 5 | 10 | 5 | 14 | 6 | 15 | 12 | 12 | 12 | 12 |  | 50 Ohms-3 | TOP=L2:L3=L2/L4:L6=L5/L7:BOTTOM=L7 |
| SSD_ACT_DR9_MOS_N | 50OHM_Y12MIL | BUS | 6 | 6 | 5 | 10 | 5 | 14 | 6 | 15 | 12 | 12 | 12 | 12 |  | 50 Ohms-3 | TOP=L2:L3=L2/L4:L6=L5/L7:BOTTOM=L7 |
| SSD_ACT_DR9_MOS_N | 50OHM_Y12MIL | BUS | 7 | 6 | 5 | 10 | 5 | 14 | 6 | 15 | 12 | 12 | 12 | 12 |  | 50 Ohms-3 | TOP=L2:L3=L2/L4:L6=L5/L7:BOTTOM=L7 |
| SSD_ACT_DR9_MOS_N | 50OHM_Y12MIL | BUS | 8 | 6.75 | 5 | 10 | 5 | 14 | 6 | 15 | 12 | 12 | 12 | 12 |  | 50 Ohms-3 | TOP=L2:L3=L2/L4:L6=L5/L7:BOTTOM=L7 |
| SSD_ACT_DR9_R | 50OHM_Y12MIL | BUS | 1 | 6.75 | 5 | 10 | 5 | 14 | 6 | 15 | 12 | 12 | 12 | 12 |  | 50 Ohms-3 | TOP=L2:L3=L2/L4:L6=L5/L7:BOTTOM=L7 |
| SSD_ACT_DR9_R | 50OHM_Y12MIL | BUS | 2 | 6 | 5 | 10 | 5 | 14 | 6 | 15 | 12 | 12 | 12 | 12 |  | 50 Ohms-3 | TOP=L2:L3=L2/L4:L6=L5/L7:BOTTOM=L7 |
| SSD_ACT_DR9_R | 50OHM_Y12MIL | BUS | 3 | 6 | 5 | 10 | 5 | 14 | 6 | 15 | 12 | 12 | 12 | 12 |  | 50 Ohms-3 | TOP=L2:L3=L2/L4:L6=L5/L7:BOTTOM=L7 |
| SSD_ACT_DR9_R | 50OHM_Y12MIL | BUS | 4 | 6 | 5 | 10 | 5 | 14 | 6 | 15 | 12 | 12 | 12 | 12 |  | 50 Ohms-3 | TOP=L2:L3=L2/L4:L6=L5/L7:BOTTOM=L7 |
| SSD_ACT_DR9_R | 50OHM_Y12MIL | BUS | 5 | 6 | 5 | 10 | 5 | 14 | 6 | 15 | 12 | 12 | 12 | 12 |  | 50 Ohms-3 | TOP=L2:L3=L2/L4:L6=L5/L7:BOTTOM=L7 |
| SSD_ACT_DR9_R | 50OHM_Y12MIL | BUS | 6 | 6 | 5 | 10 | 5 | 14 | 6 | 15 | 12 | 12 | 12 | 12 |  | 50 Ohms-3 | TOP=L2:L3=L2/L4:L6=L5/L7:BOTTOM=L7 |
| SSD_ACT_DR9_R | 50OHM_Y12MIL | BUS | 7 | 6 | 5 | 10 | 5 | 14 | 6 | 15 | 12 | 12 | 12 | 12 |  | 50 Ohms-3 | TOP=L2:L3=L2/L4:L6=L5/L7:BOTTOM=L7 |
| SSD_ACT_DR9_R | 50OHM_Y12MIL | BUS | 8 | 6.75 | 5 | 10 | 5 | 14 | 6 | 15 | 12 | 12 | 12 | 12 |  | 50 Ohms-3 | TOP=L2:L3=L2/L4:L6=L5/L7:BOTTOM=L7 |
| SSD_PRSNT_NET0 | 50OHM_Y12MIL | BUS | 1 | 6.75 | 5 | 10 | 5 | 14 | 6 | 15 | 12 | 12 | 12 | 12 |  | 50 Ohms-3 | TOP=L2:L3=L2/L4:L6=L5/L7:BOTTOM=L7 |
| SSD_PRSNT_NET0 | 50OHM_Y12MIL | BUS | 2 | 6 | 5 | 10 | 5 | 14 | 6 | 15 | 12 | 12 | 12 | 12 |  | 50 Ohms-3 | TOP=L2:L3=L2/L4:L6=L5/L7:BOTTOM=L7 |
| SSD_PRSNT_NET0 | 50OHM_Y12MIL | BUS | 3 | 6 | 5 | 10 | 5 | 14 | 6 | 15 | 12 | 12 | 12 | 12 |  | 50 Ohms-3 | TOP=L2:L3=L2/L4:L6=L5/L7:BOTTOM=L7 |
| SSD_PRSNT_NET0 | 50OHM_Y12MIL | BUS | 4 | 6 | 5 | 10 | 5 | 14 | 6 | 15 | 12 | 12 | 12 | 12 |  | 50 Ohms-3 | TOP=L2:L3=L2/L4:L6=L5/L7:BOTTOM=L7 |
| SSD_PRSNT_NET0 | 50OHM_Y12MIL | BUS | 5 | 6 | 5 | 10 | 5 | 14 | 6 | 15 | 12 | 12 | 12 | 12 |  | 50 Ohms-3 | TOP=L2:L3=L2/L4:L6=L5/L7:BOTTOM=L7 |
| SSD_PRSNT_NET0 | 50OHM_Y12MIL | BUS | 6 | 6 | 5 | 10 | 5 | 14 | 6 | 15 | 12 | 12 | 12 | 12 |  | 50 Ohms-3 | TOP=L2:L3=L2/L4:L6=L5/L7:BOTTOM=L7 |
| SSD_PRSNT_NET0 | 50OHM_Y12MIL | BUS | 7 | 6 | 5 | 10 | 5 | 14 | 6 | 15 | 12 | 12 | 12 | 12 |  | 50 Ohms-3 | TOP=L2:L3=L2/L4:L6=L5/L7:BOTTOM=L7 |
| SSD_PRSNT_NET0 | 50OHM_Y12MIL | BUS | 8 | 6.75 | 5 | 10 | 5 | 14 | 6 | 15 | 12 | 12 | 12 | 12 |  | 50 Ohms-3 | TOP=L2:L3=L2/L4:L6=L5/L7:BOTTOM=L7 |
| SSD_PRSNT_NET1 | 50OHM_Y12MIL | BUS | 1 | 6.75 | 5 | 10 | 5 | 14 | 6 | 15 | 12 | 12 | 12 | 12 |  | 50 Ohms-3 | TOP=L2:L3=L2/L4:L6=L5/L7:BOTTOM=L7 |
| SSD_PRSNT_NET1 | 50OHM_Y12MIL | BUS | 2 | 6 | 5 | 10 | 5 | 14 | 6 | 15 | 12 | 12 | 12 | 12 |  | 50 Ohms-3 | TOP=L2:L3=L2/L4:L6=L5/L7:BOTTOM=L7 |
| SSD_PRSNT_NET1 | 50OHM_Y12MIL | BUS | 3 | 6 | 5 | 10 | 5 | 14 | 6 | 15 | 12 | 12 | 12 | 12 |  | 50 Ohms-3 | TOP=L2:L3=L2/L4:L6=L5/L7:BOTTOM=L7 |
| SSD_PRSNT_NET1 | 50OHM_Y12MIL | BUS | 4 | 6 | 5 | 10 | 5 | 14 | 6 | 15 | 12 | 12 | 12 | 12 |  | 50 Ohms-3 | TOP=L2:L3=L2/L4:L6=L5/L7:BOTTOM=L7 |
| SSD_PRSNT_NET1 | 50OHM_Y12MIL | BUS | 5 | 6 | 5 | 10 | 5 | 14 | 6 | 15 | 12 | 12 | 12 | 12 |  | 50 Ohms-3 | TOP=L2:L3=L2/L4:L6=L5/L7:BOTTOM=L7 |
| SSD_PRSNT_NET1 | 50OHM_Y12MIL | BUS | 6 | 6 | 5 | 10 | 5 | 14 | 6 | 15 | 12 | 12 | 12 | 12 |  | 50 Ohms-3 | TOP=L2:L3=L2/L4:L6=L5/L7:BOTTOM=L7 |
| SSD_PRSNT_NET1 | 50OHM_Y12MIL | BUS | 7 | 6 | 5 | 10 | 5 | 14 | 6 | 15 | 12 | 12 | 12 | 12 |  | 50 Ohms-3 | TOP=L2:L3=L2/L4:L6=L5/L7:BOTTOM=L7 |
| SSD_PRSNT_NET1 | 50OHM_Y12MIL | BUS | 8 | 6.75 | 5 | 10 | 5 | 14 | 6 | 15 | 12 | 12 | 12 | 12 |  | 50 Ohms-3 | TOP=L2:L3=L2/L4:L6=L5/L7:BOTTOM=L7 |
| SSD_PRSNT_NET10 | 50OHM_Y12MIL | BUS | 1 | 6.75 | 5 | 10 | 5 | 14 | 6 | 15 | 12 | 12 | 12 | 12 |  | 50 Ohms-3 | TOP=L2:L3=L2/L4:L6=L5/L7:BOTTOM=L7 |
| SSD_PRSNT_NET10 | 50OHM_Y12MIL | BUS | 2 | 6 | 5 | 10 | 5 | 14 | 6 | 15 | 12 | 12 | 12 | 12 |  | 50 Ohms-3 | TOP=L2:L3=L2/L4:L6=L5/L7:BOTTOM=L7 |
| SSD_PRSNT_NET10 | 50OHM_Y12MIL | BUS | 3 | 6 | 5 | 10 | 5 | 14 | 6 | 15 | 12 | 12 | 12 | 12 |  | 50 Ohms-3 | TOP=L2:L3=L2/L4:L6=L5/L7:BOTTOM=L7 |
| SSD_PRSNT_NET10 | 50OHM_Y12MIL | BUS | 4 | 6 | 5 | 10 | 5 | 14 | 6 | 15 | 12 | 12 | 12 | 12 |  | 50 Ohms-3 | TOP=L2:L3=L2/L4:L6=L5/L7:BOTTOM=L7 |
| SSD_PRSNT_NET10 | 50OHM_Y12MIL | BUS | 5 | 6 | 5 | 10 | 5 | 14 | 6 | 15 | 12 | 12 | 12 | 12 |  | 50 Ohms-3 | TOP=L2:L3=L2/L4:L6=L5/L7:BOTTOM=L7 |
| SSD_PRSNT_NET10 | 50OHM_Y12MIL | BUS | 6 | 6 | 5 | 10 | 5 | 14 | 6 | 15 | 12 | 12 | 12 | 12 |  | 50 Ohms-3 | TOP=L2:L3=L2/L4:L6=L5/L7:BOTTOM=L7 |
| SSD_PRSNT_NET10 | 50OHM_Y12MIL | BUS | 7 | 6 | 5 | 10 | 5 | 14 | 6 | 15 | 12 | 12 | 12 | 12 |  | 50 Ohms-3 | TOP=L2:L3=L2/L4:L6=L5/L7:BOTTOM=L7 |
| SSD_PRSNT_NET10 | 50OHM_Y12MIL | BUS | 8 | 6.75 | 5 | 10 | 5 | 14 | 6 | 15 | 12 | 12 | 12 | 12 |  | 50 Ohms-3 | TOP=L2:L3=L2/L4:L6=L5/L7:BOTTOM=L7 |
| SSD_PRSNT_NET11 | 50OHM_Y12MIL | BUS | 1 | 6.75 | 5 | 10 | 5 | 14 | 6 | 15 | 12 | 12 | 12 | 12 |  | 50 Ohms-3 | TOP=L2:L3=L2/L4:L6=L5/L7:BOTTOM=L7 |
| SSD_PRSNT_NET11 | 50OHM_Y12MIL | BUS | 2 | 6 | 5 | 10 | 5 | 14 | 6 | 15 | 12 | 12 | 12 | 12 |  | 50 Ohms-3 | TOP=L2:L3=L2/L4:L6=L5/L7:BOTTOM=L7 |
| SSD_PRSNT_NET11 | 50OHM_Y12MIL | BUS | 3 | 6 | 5 | 10 | 5 | 14 | 6 | 15 | 12 | 12 | 12 | 12 |  | 50 Ohms-3 | TOP=L2:L3=L2/L4:L6=L5/L7:BOTTOM=L7 |
| SSD_PRSNT_NET11 | 50OHM_Y12MIL | BUS | 4 | 6 | 5 | 10 | 5 | 14 | 6 | 15 | 12 | 12 | 12 | 12 |  | 50 Ohms-3 | TOP=L2:L3=L2/L4:L6=L5/L7:BOTTOM=L7 |
| SSD_PRSNT_NET11 | 50OHM_Y12MIL | BUS | 5 | 6 | 5 | 10 | 5 | 14 | 6 | 15 | 12 | 12 | 12 | 12 |  | 50 Ohms-3 | TOP=L2:L3=L2/L4:L6=L5/L7:BOTTOM=L7 |
| SSD_PRSNT_NET11 | 50OHM_Y12MIL | BUS | 6 | 6 | 5 | 10 | 5 | 14 | 6 | 15 | 12 | 12 | 12 | 12 |  | 50 Ohms-3 | TOP=L2:L3=L2/L4:L6=L5/L7:BOTTOM=L7 |
| SSD_PRSNT_NET11 | 50OHM_Y12MIL | BUS | 7 | 6 | 5 | 10 | 5 | 14 | 6 | 15 | 12 | 12 | 12 | 12 |  | 50 Ohms-3 | TOP=L2:L3=L2/L4:L6=L5/L7:BOTTOM=L7 |
| SSD_PRSNT_NET11 | 50OHM_Y12MIL | BUS | 8 | 6.75 | 5 | 10 | 5 | 14 | 6 | 15 | 12 | 12 | 12 | 12 |  | 50 Ohms-3 | TOP=L2:L3=L2/L4:L6=L5/L7:BOTTOM=L7 |
| SSD_PRSNT_NET12 | 50OHM_Y12MIL | BUS | 1 | 6.75 | 5 | 10 | 5 | 14 | 6 | 15 | 12 | 12 | 12 | 12 |  | 50 Ohms-3 | TOP=L2:L3=L2/L4:L6=L5/L7:BOTTOM=L7 |
| SSD_PRSNT_NET12 | 50OHM_Y12MIL | BUS | 2 | 6 | 5 | 10 | 5 | 14 | 6 | 15 | 12 | 12 | 12 | 12 |  | 50 Ohms-3 | TOP=L2:L3=L2/L4:L6=L5/L7:BOTTOM=L7 |
| SSD_PRSNT_NET12 | 50OHM_Y12MIL | BUS | 3 | 6 | 5 | 10 | 5 | 14 | 6 | 15 | 12 | 12 | 12 | 12 |  | 50 Ohms-3 | TOP=L2:L3=L2/L4:L6=L5/L7:BOTTOM=L7 |
| SSD_PRSNT_NET12 | 50OHM_Y12MIL | BUS | 4 | 6 | 5 | 10 | 5 | 14 | 6 | 15 | 12 | 12 | 12 | 12 |  | 50 Ohms-3 | TOP=L2:L3=L2/L4:L6=L5/L7:BOTTOM=L7 |
| SSD_PRSNT_NET12 | 50OHM_Y12MIL | BUS | 5 | 6 | 5 | 10 | 5 | 14 | 6 | 15 | 12 | 12 | 12 | 12 |  | 50 Ohms-3 | TOP=L2:L3=L2/L4:L6=L5/L7:BOTTOM=L7 |
| SSD_PRSNT_NET12 | 50OHM_Y12MIL | BUS | 6 | 6 | 5 | 10 | 5 | 14 | 6 | 15 | 12 | 12 | 12 | 12 |  | 50 Ohms-3 | TOP=L2:L3=L2/L4:L6=L5/L7:BOTTOM=L7 |
| SSD_PRSNT_NET12 | 50OHM_Y12MIL | BUS | 7 | 6 | 5 | 10 | 5 | 14 | 6 | 15 | 12 | 12 | 12 | 12 |  | 50 Ohms-3 | TOP=L2:L3=L2/L4:L6=L5/L7:BOTTOM=L7 |
| SSD_PRSNT_NET12 | 50OHM_Y12MIL | BUS | 8 | 6.75 | 5 | 10 | 5 | 14 | 6 | 15 | 12 | 12 | 12 | 12 |  | 50 Ohms-3 | TOP=L2:L3=L2/L4:L6=L5/L7:BOTTOM=L7 |
| SSD_PRSNT_NET13 | 50OHM_Y12MIL | BUS | 1 | 6.75 | 5 | 10 | 5 | 14 | 6 | 15 | 12 | 12 | 12 | 12 |  | 50 Ohms-3 | TOP=L2:L3=L2/L4:L6=L5/L7:BOTTOM=L7 |
| SSD_PRSNT_NET13 | 50OHM_Y12MIL | BUS | 2 | 6 | 5 | 10 | 5 | 14 | 6 | 15 | 12 | 12 | 12 | 12 |  | 50 Ohms-3 | TOP=L2:L3=L2/L4:L6=L5/L7:BOTTOM=L7 |
| SSD_PRSNT_NET13 | 50OHM_Y12MIL | BUS | 3 | 6 | 5 | 10 | 5 | 14 | 6 | 15 | 12 | 12 | 12 | 12 |  | 50 Ohms-3 | TOP=L2:L3=L2/L4:L6=L5/L7:BOTTOM=L7 |
| SSD_PRSNT_NET13 | 50OHM_Y12MIL | BUS | 4 | 6 | 5 | 10 | 5 | 14 | 6 | 15 | 12 | 12 | 12 | 12 |  | 50 Ohms-3 | TOP=L2:L3=L2/L4:L6=L5/L7:BOTTOM=L7 |
| SSD_PRSNT_NET13 | 50OHM_Y12MIL | BUS | 5 | 6 | 5 | 10 | 5 | 14 | 6 | 15 | 12 | 12 | 12 | 12 |  | 50 Ohms-3 | TOP=L2:L3=L2/L4:L6=L5/L7:BOTTOM=L7 |
| SSD_PRSNT_NET13 | 50OHM_Y12MIL | BUS | 6 | 6 | 5 | 10 | 5 | 14 | 6 | 15 | 12 | 12 | 12 | 12 |  | 50 Ohms-3 | TOP=L2:L3=L2/L4:L6=L5/L7:BOTTOM=L7 |
| SSD_PRSNT_NET13 | 50OHM_Y12MIL | BUS | 7 | 6 | 5 | 10 | 5 | 14 | 6 | 15 | 12 | 12 | 12 | 12 |  | 50 Ohms-3 | TOP=L2:L3=L2/L4:L6=L5/L7:BOTTOM=L7 |
| SSD_PRSNT_NET13 | 50OHM_Y12MIL | BUS | 8 | 6.75 | 5 | 10 | 5 | 14 | 6 | 15 | 12 | 12 | 12 | 12 |  | 50 Ohms-3 | TOP=L2:L3=L2/L4:L6=L5/L7:BOTTOM=L7 |
| SSD_PRSNT_NET14 | 50OHM_Y12MIL | BUS | 1 | 6.75 | 5 | 10 | 5 | 14 | 6 | 15 | 12 | 12 | 12 | 12 |  | 50 Ohms-3 | TOP=L2:L3=L2/L4:L6=L5/L7:BOTTOM=L7 |
| SSD_PRSNT_NET14 | 50OHM_Y12MIL | BUS | 2 | 6 | 5 | 10 | 5 | 14 | 6 | 15 | 12 | 12 | 12 | 12 |  | 50 Ohms-3 | TOP=L2:L3=L2/L4:L6=L5/L7:BOTTOM=L7 |
| SSD_PRSNT_NET14 | 50OHM_Y12MIL | BUS | 3 | 6 | 5 | 10 | 5 | 14 | 6 | 15 | 12 | 12 | 12 | 12 |  | 50 Ohms-3 | TOP=L2:L3=L2/L4:L6=L5/L7:BOTTOM=L7 |
| SSD_PRSNT_NET14 | 50OHM_Y12MIL | BUS | 4 | 6 | 5 | 10 | 5 | 14 | 6 | 15 | 12 | 12 | 12 | 12 |  | 50 Ohms-3 | TOP=L2:L3=L2/L4:L6=L5/L7:BOTTOM=L7 |
| SSD_PRSNT_NET14 | 50OHM_Y12MIL | BUS | 5 | 6 | 5 | 10 | 5 | 14 | 6 | 15 | 12 | 12 | 12 | 12 |  | 50 Ohms-3 | TOP=L2:L3=L2/L4:L6=L5/L7:BOTTOM=L7 |
| SSD_PRSNT_NET14 | 50OHM_Y12MIL | BUS | 6 | 6 | 5 | 10 | 5 | 14 | 6 | 15 | 12 | 12 | 12 | 12 |  | 50 Ohms-3 | TOP=L2:L3=L2/L4:L6=L5/L7:BOTTOM=L7 |
| SSD_PRSNT_NET14 | 50OHM_Y12MIL | BUS | 7 | 6 | 5 | 10 | 5 | 14 | 6 | 15 | 12 | 12 | 12 | 12 |  | 50 Ohms-3 | TOP=L2:L3=L2/L4:L6=L5/L7:BOTTOM=L7 |
| SSD_PRSNT_NET14 | 50OHM_Y12MIL | BUS | 8 | 6.75 | 5 | 10 | 5 | 14 | 6 | 15 | 12 | 12 | 12 | 12 |  | 50 Ohms-3 | TOP=L2:L3=L2/L4:L6=L5/L7:BOTTOM=L7 |
| SSD_PRSNT_NET2 | 50OHM_Y12MIL | BUS | 1 | 6.75 | 5 | 10 | 5 | 14 | 6 | 15 | 12 | 12 | 12 | 12 |  | 50 Ohms-3 | TOP=L2:L3=L2/L4:L6=L5/L7:BOTTOM=L7 |
| SSD_PRSNT_NET2 | 50OHM_Y12MIL | BUS | 2 | 6 | 5 | 10 | 5 | 14 | 6 | 15 | 12 | 12 | 12 | 12 |  | 50 Ohms-3 | TOP=L2:L3=L2/L4:L6=L5/L7:BOTTOM=L7 |
| SSD_PRSNT_NET2 | 50OHM_Y12MIL | BUS | 3 | 6 | 5 | 10 | 5 | 14 | 6 | 15 | 12 | 12 | 12 | 12 |  | 50 Ohms-3 | TOP=L2:L3=L2/L4:L6=L5/L7:BOTTOM=L7 |
| SSD_PRSNT_NET2 | 50OHM_Y12MIL | BUS | 4 | 6 | 5 | 10 | 5 | 14 | 6 | 15 | 12 | 12 | 12 | 12 |  | 50 Ohms-3 | TOP=L2:L3=L2/L4:L6=L5/L7:BOTTOM=L7 |
| SSD_PRSNT_NET2 | 50OHM_Y12MIL | BUS | 5 | 6 | 5 | 10 | 5 | 14 | 6 | 15 | 12 | 12 | 12 | 12 |  | 50 Ohms-3 | TOP=L2:L3=L2/L4:L6=L5/L7:BOTTOM=L7 |
| SSD_PRSNT_NET2 | 50OHM_Y12MIL | BUS | 6 | 6 | 5 | 10 | 5 | 14 | 6 | 15 | 12 | 12 | 12 | 12 |  | 50 Ohms-3 | TOP=L2:L3=L2/L4:L6=L5/L7:BOTTOM=L7 |
| SSD_PRSNT_NET2 | 50OHM_Y12MIL | BUS | 7 | 6 | 5 | 10 | 5 | 14 | 6 | 15 | 12 | 12 | 12 | 12 |  | 50 Ohms-3 | TOP=L2:L3=L2/L4:L6=L5/L7:BOTTOM=L7 |
| SSD_PRSNT_NET2 | 50OHM_Y12MIL | BUS | 8 | 6.75 | 5 | 10 | 5 | 14 | 6 | 15 | 12 | 12 | 12 | 12 |  | 50 Ohms-3 | TOP=L2:L3=L2/L4:L6=L5/L7:BOTTOM=L7 |
| SSD_PRSNT_NET3 | 50OHM_Y12MIL | BUS | 1 | 6.75 | 5 | 10 | 5 | 14 | 6 | 15 | 12 | 12 | 12 | 12 |  | 50 Ohms-3 | TOP=L2:L3=L2/L4:L6=L5/L7:BOTTOM=L7 |
| SSD_PRSNT_NET3 | 50OHM_Y12MIL | BUS | 2 | 6 | 5 | 10 | 5 | 14 | 6 | 15 | 12 | 12 | 12 | 12 |  | 50 Ohms-3 | TOP=L2:L3=L2/L4:L6=L5/L7:BOTTOM=L7 |
| SSD_PRSNT_NET3 | 50OHM_Y12MIL | BUS | 3 | 6 | 5 | 10 | 5 | 14 | 6 | 15 | 12 | 12 | 12 | 12 |  | 50 Ohms-3 | TOP=L2:L3=L2/L4:L6=L5/L7:BOTTOM=L7 |
| SSD_PRSNT_NET3 | 50OHM_Y12MIL | BUS | 4 | 6 | 5 | 10 | 5 | 14 | 6 | 15 | 12 | 12 | 12 | 12 |  | 50 Ohms-3 | TOP=L2:L3=L2/L4:L6=L5/L7:BOTTOM=L7 |
| SSD_PRSNT_NET3 | 50OHM_Y12MIL | BUS | 5 | 6 | 5 | 10 | 5 | 14 | 6 | 15 | 12 | 12 | 12 | 12 |  | 50 Ohms-3 | TOP=L2:L3=L2/L4:L6=L5/L7:BOTTOM=L7 |
| SSD_PRSNT_NET3 | 50OHM_Y12MIL | BUS | 6 | 6 | 5 | 10 | 5 | 14 | 6 | 15 | 12 | 12 | 12 | 12 |  | 50 Ohms-3 | TOP=L2:L3=L2/L4:L6=L5/L7:BOTTOM=L7 |
| SSD_PRSNT_NET3 | 50OHM_Y12MIL | BUS | 7 | 6 | 5 | 10 | 5 | 14 | 6 | 15 | 12 | 12 | 12 | 12 |  | 50 Ohms-3 | TOP=L2:L3=L2/L4:L6=L5/L7:BOTTOM=L7 |
| SSD_PRSNT_NET3 | 50OHM_Y12MIL | BUS | 8 | 6.75 | 5 | 10 | 5 | 14 | 6 | 15 | 12 | 12 | 12 | 12 |  | 50 Ohms-3 | TOP=L2:L3=L2/L4:L6=L5/L7:BOTTOM=L7 |
| SSD_PRSNT_NET4 | 50OHM_Y12MIL | BUS | 1 | 6.75 | 5 | 10 | 5 | 14 | 6 | 15 | 12 | 12 | 12 | 12 |  | 50 Ohms-3 | TOP=L2:L3=L2/L4:L6=L5/L7:BOTTOM=L7 |
| SSD_PRSNT_NET4 | 50OHM_Y12MIL | BUS | 2 | 6 | 5 | 10 | 5 | 14 | 6 | 15 | 12 | 12 | 12 | 12 |  | 50 Ohms-3 | TOP=L2:L3=L2/L4:L6=L5/L7:BOTTOM=L7 |
| SSD_PRSNT_NET4 | 50OHM_Y12MIL | BUS | 3 | 6 | 5 | 10 | 5 | 14 | 6 | 15 | 12 | 12 | 12 | 12 |  | 50 Ohms-3 | TOP=L2:L3=L2/L4:L6=L5/L7:BOTTOM=L7 |
| SSD_PRSNT_NET4 | 50OHM_Y12MIL | BUS | 4 | 6 | 5 | 10 | 5 | 14 | 6 | 15 | 12 | 12 | 12 | 12 |  | 50 Ohms-3 | TOP=L2:L3=L2/L4:L6=L5/L7:BOTTOM=L7 |
| SSD_PRSNT_NET4 | 50OHM_Y12MIL | BUS | 5 | 6 | 5 | 10 | 5 | 14 | 6 | 15 | 12 | 12 | 12 | 12 |  | 50 Ohms-3 | TOP=L2:L3=L2/L4:L6=L5/L7:BOTTOM=L7 |
| SSD_PRSNT_NET4 | 50OHM_Y12MIL | BUS | 6 | 6 | 5 | 10 | 5 | 14 | 6 | 15 | 12 | 12 | 12 | 12 |  | 50 Ohms-3 | TOP=L2:L3=L2/L4:L6=L5/L7:BOTTOM=L7 |
| SSD_PRSNT_NET4 | 50OHM_Y12MIL | BUS | 7 | 6 | 5 | 10 | 5 | 14 | 6 | 15 | 12 | 12 | 12 | 12 |  | 50 Ohms-3 | TOP=L2:L3=L2/L4:L6=L5/L7:BOTTOM=L7 |
| SSD_PRSNT_NET4 | 50OHM_Y12MIL | BUS | 8 | 6.75 | 5 | 10 | 5 | 14 | 6 | 15 | 12 | 12 | 12 | 12 |  | 50 Ohms-3 | TOP=L2:L3=L2/L4:L6=L5/L7:BOTTOM=L7 |
| SSD_PRSNT_NET5 | 50OHM_Y12MIL | BUS | 1 | 6.75 | 5 | 10 | 5 | 14 | 6 | 15 | 12 | 12 | 12 | 12 |  | 50 Ohms-3 | TOP=L2:L3=L2/L4:L6=L5/L7:BOTTOM=L7 |
| SSD_PRSNT_NET5 | 50OHM_Y12MIL | BUS | 2 | 6 | 5 | 10 | 5 | 14 | 6 | 15 | 12 | 12 | 12 | 12 |  | 50 Ohms-3 | TOP=L2:L3=L2/L4:L6=L5/L7:BOTTOM=L7 |
| SSD_PRSNT_NET5 | 50OHM_Y12MIL | BUS | 3 | 6 | 5 | 10 | 5 | 14 | 6 | 15 | 12 | 12 | 12 | 12 |  | 50 Ohms-3 | TOP=L2:L3=L2/L4:L6=L5/L7:BOTTOM=L7 |
| SSD_PRSNT_NET5 | 50OHM_Y12MIL | BUS | 4 | 6 | 5 | 10 | 5 | 14 | 6 | 15 | 12 | 12 | 12 | 12 |  | 50 Ohms-3 | TOP=L2:L3=L2/L4:L6=L5/L7:BOTTOM=L7 |
| SSD_PRSNT_NET5 | 50OHM_Y12MIL | BUS | 5 | 6 | 5 | 10 | 5 | 14 | 6 | 15 | 12 | 12 | 12 | 12 |  | 50 Ohms-3 | TOP=L2:L3=L2/L4:L6=L5/L7:BOTTOM=L7 |
| SSD_PRSNT_NET5 | 50OHM_Y12MIL | BUS | 6 | 6 | 5 | 10 | 5 | 14 | 6 | 15 | 12 | 12 | 12 | 12 |  | 50 Ohms-3 | TOP=L2:L3=L2/L4:L6=L5/L7:BOTTOM=L7 |
| SSD_PRSNT_NET5 | 50OHM_Y12MIL | BUS | 7 | 6 | 5 | 10 | 5 | 14 | 6 | 15 | 12 | 12 | 12 | 12 |  | 50 Ohms-3 | TOP=L2:L3=L2/L4:L6=L5/L7:BOTTOM=L7 |
| SSD_PRSNT_NET5 | 50OHM_Y12MIL | BUS | 8 | 6.75 | 5 | 10 | 5 | 14 | 6 | 15 | 12 | 12 | 12 | 12 |  | 50 Ohms-3 | TOP=L2:L3=L2/L4:L6=L5/L7:BOTTOM=L7 |
| SSD_PRSNT_NET6 | 50OHM_Y12MIL | BUS | 1 | 6.75 | 5 | 10 | 5 | 14 | 6 | 15 | 12 | 12 | 12 | 12 |  | 50 Ohms-3 | TOP=L2:L3=L2/L4:L6=L5/L7:BOTTOM=L7 |
| SSD_PRSNT_NET6 | 50OHM_Y12MIL | BUS | 2 | 6 | 5 | 10 | 5 | 14 | 6 | 15 | 12 | 12 | 12 | 12 |  | 50 Ohms-3 | TOP=L2:L3=L2/L4:L6=L5/L7:BOTTOM=L7 |
| SSD_PRSNT_NET6 | 50OHM_Y12MIL | BUS | 3 | 6 | 5 | 10 | 5 | 14 | 6 | 15 | 12 | 12 | 12 | 12 |  | 50 Ohms-3 | TOP=L2:L3=L2/L4:L6=L5/L7:BOTTOM=L7 |
| SSD_PRSNT_NET6 | 50OHM_Y12MIL | BUS | 4 | 6 | 5 | 10 | 5 | 14 | 6 | 15 | 12 | 12 | 12 | 12 |  | 50 Ohms-3 | TOP=L2:L3=L2/L4:L6=L5/L7:BOTTOM=L7 |
| SSD_PRSNT_NET6 | 50OHM_Y12MIL | BUS | 5 | 6 | 5 | 10 | 5 | 14 | 6 | 15 | 12 | 12 | 12 | 12 |  | 50 Ohms-3 | TOP=L2:L3=L2/L4:L6=L5/L7:BOTTOM=L7 |
| SSD_PRSNT_NET6 | 50OHM_Y12MIL | BUS | 6 | 6 | 5 | 10 | 5 | 14 | 6 | 15 | 12 | 12 | 12 | 12 |  | 50 Ohms-3 | TOP=L2:L3=L2/L4:L6=L5/L7:BOTTOM=L7 |
| SSD_PRSNT_NET6 | 50OHM_Y12MIL | BUS | 7 | 6 | 5 | 10 | 5 | 14 | 6 | 15 | 12 | 12 | 12 | 12 |  | 50 Ohms-3 | TOP=L2:L3=L2/L4:L6=L5/L7:BOTTOM=L7 |
| SSD_PRSNT_NET6 | 50OHM_Y12MIL | BUS | 8 | 6.75 | 5 | 10 | 5 | 14 | 6 | 15 | 12 | 12 | 12 | 12 |  | 50 Ohms-3 | TOP=L2:L3=L2/L4:L6=L5/L7:BOTTOM=L7 |
| SSD_PRSNT_NET7 | 50OHM_Y12MIL | BUS | 1 | 6.75 | 5 | 10 | 5 | 14 | 6 | 15 | 12 | 12 | 12 | 12 |  | 50 Ohms-3 | TOP=L2:L3=L2/L4:L6=L5/L7:BOTTOM=L7 |
| SSD_PRSNT_NET7 | 50OHM_Y12MIL | BUS | 2 | 6 | 5 | 10 | 5 | 14 | 6 | 15 | 12 | 12 | 12 | 12 |  | 50 Ohms-3 | TOP=L2:L3=L2/L4:L6=L5/L7:BOTTOM=L7 |
| SSD_PRSNT_NET7 | 50OHM_Y12MIL | BUS | 3 | 6 | 5 | 10 | 5 | 14 | 6 | 15 | 12 | 12 | 12 | 12 |  | 50 Ohms-3 | TOP=L2:L3=L2/L4:L6=L5/L7:BOTTOM=L7 |
| SSD_PRSNT_NET7 | 50OHM_Y12MIL | BUS | 4 | 6 | 5 | 10 | 5 | 14 | 6 | 15 | 12 | 12 | 12 | 12 |  | 50 Ohms-3 | TOP=L2:L3=L2/L4:L6=L5/L7:BOTTOM=L7 |
| SSD_PRSNT_NET7 | 50OHM_Y12MIL | BUS | 5 | 6 | 5 | 10 | 5 | 14 | 6 | 15 | 12 | 12 | 12 | 12 |  | 50 Ohms-3 | TOP=L2:L3=L2/L4:L6=L5/L7:BOTTOM=L7 |
| SSD_PRSNT_NET7 | 50OHM_Y12MIL | BUS | 6 | 6 | 5 | 10 | 5 | 14 | 6 | 15 | 12 | 12 | 12 | 12 |  | 50 Ohms-3 | TOP=L2:L3=L2/L4:L6=L5/L7:BOTTOM=L7 |
| SSD_PRSNT_NET7 | 50OHM_Y12MIL | BUS | 7 | 6 | 5 | 10 | 5 | 14 | 6 | 15 | 12 | 12 | 12 | 12 |  | 50 Ohms-3 | TOP=L2:L3=L2/L4:L6=L5/L7:BOTTOM=L7 |
| SSD_PRSNT_NET7 | 50OHM_Y12MIL | BUS | 8 | 6.75 | 5 | 10 | 5 | 14 | 6 | 15 | 12 | 12 | 12 | 12 |  | 50 Ohms-3 | TOP=L2:L3=L2/L4:L6=L5/L7:BOTTOM=L7 |
| SSD_PRSNT_NET8 | 50OHM_Y12MIL | BUS | 1 | 6.75 | 5 | 10 | 5 | 14 | 6 | 15 | 12 | 12 | 12 | 12 |  | 50 Ohms-3 | TOP=L2:L3=L2/L4:L6=L5/L7:BOTTOM=L7 |
| SSD_PRSNT_NET8 | 50OHM_Y12MIL | BUS | 2 | 6 | 5 | 10 | 5 | 14 | 6 | 15 | 12 | 12 | 12 | 12 |  | 50 Ohms-3 | TOP=L2:L3=L2/L4:L6=L5/L7:BOTTOM=L7 |
| SSD_PRSNT_NET8 | 50OHM_Y12MIL | BUS | 3 | 6 | 5 | 10 | 5 | 14 | 6 | 15 | 12 | 12 | 12 | 12 |  | 50 Ohms-3 | TOP=L2:L3=L2/L4:L6=L5/L7:BOTTOM=L7 |
| SSD_PRSNT_NET8 | 50OHM_Y12MIL | BUS | 4 | 6 | 5 | 10 | 5 | 14 | 6 | 15 | 12 | 12 | 12 | 12 |  | 50 Ohms-3 | TOP=L2:L3=L2/L4:L6=L5/L7:BOTTOM=L7 |
| SSD_PRSNT_NET8 | 50OHM_Y12MIL | BUS | 5 | 6 | 5 | 10 | 5 | 14 | 6 | 15 | 12 | 12 | 12 | 12 |  | 50 Ohms-3 | TOP=L2:L3=L2/L4:L6=L5/L7:BOTTOM=L7 |
| SSD_PRSNT_NET8 | 50OHM_Y12MIL | BUS | 6 | 6 | 5 | 10 | 5 | 14 | 6 | 15 | 12 | 12 | 12 | 12 |  | 50 Ohms-3 | TOP=L2:L3=L2/L4:L6=L5/L7:BOTTOM=L7 |
| SSD_PRSNT_NET8 | 50OHM_Y12MIL | BUS | 7 | 6 | 5 | 10 | 5 | 14 | 6 | 15 | 12 | 12 | 12 | 12 |  | 50 Ohms-3 | TOP=L2:L3=L2/L4:L6=L5/L7:BOTTOM=L7 |
| SSD_PRSNT_NET8 | 50OHM_Y12MIL | BUS | 8 | 6.75 | 5 | 10 | 5 | 14 | 6 | 15 | 12 | 12 | 12 | 12 |  | 50 Ohms-3 | TOP=L2:L3=L2/L4:L6=L5/L7:BOTTOM=L7 |
| SSD_PRSNT_NET9 | 50OHM_Y12MIL | BUS | 1 | 6.75 | 5 | 10 | 5 | 14 | 6 | 15 | 12 | 12 | 12 | 12 |  | 50 Ohms-3 | TOP=L2:L3=L2/L4:L6=L5/L7:BOTTOM=L7 |
| SSD_PRSNT_NET9 | 50OHM_Y12MIL | BUS | 2 | 6 | 5 | 10 | 5 | 14 | 6 | 15 | 12 | 12 | 12 | 12 |  | 50 Ohms-3 | TOP=L2:L3=L2/L4:L6=L5/L7:BOTTOM=L7 |
| SSD_PRSNT_NET9 | 50OHM_Y12MIL | BUS | 3 | 6 | 5 | 10 | 5 | 14 | 6 | 15 | 12 | 12 | 12 | 12 |  | 50 Ohms-3 | TOP=L2:L3=L2/L4:L6=L5/L7:BOTTOM=L7 |
| SSD_PRSNT_NET9 | 50OHM_Y12MIL | BUS | 4 | 6 | 5 | 10 | 5 | 14 | 6 | 15 | 12 | 12 | 12 | 12 |  | 50 Ohms-3 | TOP=L2:L3=L2/L4:L6=L5/L7:BOTTOM=L7 |
| SSD_PRSNT_NET9 | 50OHM_Y12MIL | BUS | 5 | 6 | 5 | 10 | 5 | 14 | 6 | 15 | 12 | 12 | 12 | 12 |  | 50 Ohms-3 | TOP=L2:L3=L2/L4:L6=L5/L7:BOTTOM=L7 |
| SSD_PRSNT_NET9 | 50OHM_Y12MIL | BUS | 6 | 6 | 5 | 10 | 5 | 14 | 6 | 15 | 12 | 12 | 12 | 12 |  | 50 Ohms-3 | TOP=L2:L3=L2/L4:L6=L5/L7:BOTTOM=L7 |
| SSD_PRSNT_NET9 | 50OHM_Y12MIL | BUS | 7 | 6 | 5 | 10 | 5 | 14 | 6 | 15 | 12 | 12 | 12 | 12 |  | 50 Ohms-3 | TOP=L2:L3=L2/L4:L6=L5/L7:BOTTOM=L7 |
| SSD_PRSNT_NET9 | 50OHM_Y12MIL | BUS | 8 | 6.75 | 5 | 10 | 5 | 14 | 6 | 15 | 12 | 12 | 12 | 12 |  | 50 Ohms-3 | TOP=L2:L3=L2/L4:L6=L5/L7:BOTTOM=L7 |
| SSD_PRSNT0 | 50OHM_Y12MIL | BUS | 1 | 6.75 | 5 | 10 | 5 | 14 | 6 | 15 | 12 | 12 | 12 | 12 |  | 50 Ohms-3 | TOP=L2:L3=L2/L4:L6=L5/L7:BOTTOM=L7 |
| SSD_PRSNT0 | 50OHM_Y12MIL | BUS | 2 | 6 | 5 | 10 | 5 | 14 | 6 | 15 | 12 | 12 | 12 | 12 |  | 50 Ohms-3 | TOP=L2:L3=L2/L4:L6=L5/L7:BOTTOM=L7 |
| SSD_PRSNT0 | 50OHM_Y12MIL | BUS | 3 | 6 | 5 | 10 | 5 | 14 | 6 | 15 | 12 | 12 | 12 | 12 |  | 50 Ohms-3 | TOP=L2:L3=L2/L4:L6=L5/L7:BOTTOM=L7 |
| SSD_PRSNT0 | 50OHM_Y12MIL | BUS | 4 | 6 | 5 | 10 | 5 | 14 | 6 | 15 | 12 | 12 | 12 | 12 |  | 50 Ohms-3 | TOP=L2:L3=L2/L4:L6=L5/L7:BOTTOM=L7 |
| SSD_PRSNT0 | 50OHM_Y12MIL | BUS | 5 | 6 | 5 | 10 | 5 | 14 | 6 | 15 | 12 | 12 | 12 | 12 |  | 50 Ohms-3 | TOP=L2:L3=L2/L4:L6=L5/L7:BOTTOM=L7 |
| SSD_PRSNT0 | 50OHM_Y12MIL | BUS | 6 | 6 | 5 | 10 | 5 | 14 | 6 | 15 | 12 | 12 | 12 | 12 |  | 50 Ohms-3 | TOP=L2:L3=L2/L4:L6=L5/L7:BOTTOM=L7 |
| SSD_PRSNT0 | 50OHM_Y12MIL | BUS | 7 | 6 | 5 | 10 | 5 | 14 | 6 | 15 | 12 | 12 | 12 | 12 |  | 50 Ohms-3 | TOP=L2:L3=L2/L4:L6=L5/L7:BOTTOM=L7 |
| SSD_PRSNT0 | 50OHM_Y12MIL | BUS | 8 | 6.75 | 5 | 10 | 5 | 14 | 6 | 15 | 12 | 12 | 12 | 12 |  | 50 Ohms-3 | TOP=L2:L3=L2/L4:L6=L5/L7:BOTTOM=L7 |
| SSD_PRSNT1 | 50OHM_Y12MIL | BUS | 1 | 6.75 | 5 | 10 | 5 | 14 | 6 | 15 | 12 | 12 | 12 | 12 |  | 50 Ohms-3 | TOP=L2:L3=L2/L4:L6=L5/L7:BOTTOM=L7 |
| SSD_PRSNT1 | 50OHM_Y12MIL | BUS | 2 | 6 | 5 | 10 | 5 | 14 | 6 | 15 | 12 | 12 | 12 | 12 |  | 50 Ohms-3 | TOP=L2:L3=L2/L4:L6=L5/L7:BOTTOM=L7 |
| SSD_PRSNT1 | 50OHM_Y12MIL | BUS | 3 | 6 | 5 | 10 | 5 | 14 | 6 | 15 | 12 | 12 | 12 | 12 |  | 50 Ohms-3 | TOP=L2:L3=L2/L4:L6=L5/L7:BOTTOM=L7 |
| SSD_PRSNT1 | 50OHM_Y12MIL | BUS | 4 | 6 | 5 | 10 | 5 | 14 | 6 | 15 | 12 | 12 | 12 | 12 |  | 50 Ohms-3 | TOP=L2:L3=L2/L4:L6=L5/L7:BOTTOM=L7 |
| SSD_PRSNT1 | 50OHM_Y12MIL | BUS | 5 | 6 | 5 | 10 | 5 | 14 | 6 | 15 | 12 | 12 | 12 | 12 |  | 50 Ohms-3 | TOP=L2:L3=L2/L4:L6=L5/L7:BOTTOM=L7 |
| SSD_PRSNT1 | 50OHM_Y12MIL | BUS | 6 | 6 | 5 | 10 | 5 | 14 | 6 | 15 | 12 | 12 | 12 | 12 |  | 50 Ohms-3 | TOP=L2:L3=L2/L4:L6=L5/L7:BOTTOM=L7 |
| SSD_PRSNT1 | 50OHM_Y12MIL | BUS | 7 | 6 | 5 | 10 | 5 | 14 | 6 | 15 | 12 | 12 | 12 | 12 |  | 50 Ohms-3 | TOP=L2:L3=L2/L4:L6=L5/L7:BOTTOM=L7 |
| SSD_PRSNT1 | 50OHM_Y12MIL | BUS | 8 | 6.75 | 5 | 10 | 5 | 14 | 6 | 15 | 12 | 12 | 12 | 12 |  | 50 Ohms-3 | TOP=L2:L3=L2/L4:L6=L5/L7:BOTTOM=L7 |
| SSD_PRSNT10 | 50OHM_Y12MIL | BUS | 1 | 6.75 | 5 | 10 | 5 | 14 | 6 | 15 | 12 | 12 | 12 | 12 |  | 50 Ohms-3 | TOP=L2:L3=L2/L4:L6=L5/L7:BOTTOM=L7 |
| SSD_PRSNT10 | 50OHM_Y12MIL | BUS | 2 | 6 | 5 | 10 | 5 | 14 | 6 | 15 | 12 | 12 | 12 | 12 |  | 50 Ohms-3 | TOP=L2:L3=L2/L4:L6=L5/L7:BOTTOM=L7 |
| SSD_PRSNT10 | 50OHM_Y12MIL | BUS | 3 | 6 | 5 | 10 | 5 | 14 | 6 | 15 | 12 | 12 | 12 | 12 |  | 50 Ohms-3 | TOP=L2:L3=L2/L4:L6=L5/L7:BOTTOM=L7 |
| SSD_PRSNT10 | 50OHM_Y12MIL | BUS | 4 | 6 | 5 | 10 | 5 | 14 | 6 | 15 | 12 | 12 | 12 | 12 |  | 50 Ohms-3 | TOP=L2:L3=L2/L4:L6=L5/L7:BOTTOM=L7 |
| SSD_PRSNT10 | 50OHM_Y12MIL | BUS | 5 | 6 | 5 | 10 | 5 | 14 | 6 | 15 | 12 | 12 | 12 | 12 |  | 50 Ohms-3 | TOP=L2:L3=L2/L4:L6=L5/L7:BOTTOM=L7 |
| SSD_PRSNT10 | 50OHM_Y12MIL | BUS | 6 | 6 | 5 | 10 | 5 | 14 | 6 | 15 | 12 | 12 | 12 | 12 |  | 50 Ohms-3 | TOP=L2:L3=L2/L4:L6=L5/L7:BOTTOM=L7 |
| SSD_PRSNT10 | 50OHM_Y12MIL | BUS | 7 | 6 | 5 | 10 | 5 | 14 | 6 | 15 | 12 | 12 | 12 | 12 |  | 50 Ohms-3 | TOP=L2:L3=L2/L4:L6=L5/L7:BOTTOM=L7 |
| SSD_PRSNT10 | 50OHM_Y12MIL | BUS | 8 | 6.75 | 5 | 10 | 5 | 14 | 6 | 15 | 12 | 12 | 12 | 12 |  | 50 Ohms-3 | TOP=L2:L3=L2/L4:L6=L5/L7:BOTTOM=L7 |
| SSD_PRSNT11 | 50OHM_Y12MIL | BUS | 1 | 6.75 | 5 | 10 | 5 | 14 | 6 | 15 | 12 | 12 | 12 | 12 |  | 50 Ohms-3 | TOP=L2:L3=L2/L4:L6=L5/L7:BOTTOM=L7 |
| SSD_PRSNT11 | 50OHM_Y12MIL | BUS | 2 | 6 | 5 | 10 | 5 | 14 | 6 | 15 | 12 | 12 | 12 | 12 |  | 50 Ohms-3 | TOP=L2:L3=L2/L4:L6=L5/L7:BOTTOM=L7 |
| SSD_PRSNT11 | 50OHM_Y12MIL | BUS | 3 | 6 | 5 | 10 | 5 | 14 | 6 | 15 | 12 | 12 | 12 | 12 |  | 50 Ohms-3 | TOP=L2:L3=L2/L4:L6=L5/L7:BOTTOM=L7 |
| SSD_PRSNT11 | 50OHM_Y12MIL | BUS | 4 | 6 | 5 | 10 | 5 | 14 | 6 | 15 | 12 | 12 | 12 | 12 |  | 50 Ohms-3 | TOP=L2:L3=L2/L4:L6=L5/L7:BOTTOM=L7 |
| SSD_PRSNT11 | 50OHM_Y12MIL | BUS | 5 | 6 | 5 | 10 | 5 | 14 | 6 | 15 | 12 | 12 | 12 | 12 |  | 50 Ohms-3 | TOP=L2:L3=L2/L4:L6=L5/L7:BOTTOM=L7 |
| SSD_PRSNT11 | 50OHM_Y12MIL | BUS | 6 | 6 | 5 | 10 | 5 | 14 | 6 | 15 | 12 | 12 | 12 | 12 |  | 50 Ohms-3 | TOP=L2:L3=L2/L4:L6=L5/L7:BOTTOM=L7 |
| SSD_PRSNT11 | 50OHM_Y12MIL | BUS | 7 | 6 | 5 | 10 | 5 | 14 | 6 | 15 | 12 | 12 | 12 | 12 |  | 50 Ohms-3 | TOP=L2:L3=L2/L4:L6=L5/L7:BOTTOM=L7 |
| SSD_PRSNT11 | 50OHM_Y12MIL | BUS | 8 | 6.75 | 5 | 10 | 5 | 14 | 6 | 15 | 12 | 12 | 12 | 12 |  | 50 Ohms-3 | TOP=L2:L3=L2/L4:L6=L5/L7:BOTTOM=L7 |
| SSD_PRSNT12 | 50OHM_Y12MIL | BUS | 1 | 6.75 | 5 | 10 | 5 | 14 | 6 | 15 | 12 | 12 | 12 | 12 |  | 50 Ohms-3 | TOP=L2:L3=L2/L4:L6=L5/L7:BOTTOM=L7 |
| SSD_PRSNT12 | 50OHM_Y12MIL | BUS | 2 | 6 | 5 | 10 | 5 | 14 | 6 | 15 | 12 | 12 | 12 | 12 |  | 50 Ohms-3 | TOP=L2:L3=L2/L4:L6=L5/L7:BOTTOM=L7 |
| SSD_PRSNT12 | 50OHM_Y12MIL | BUS | 3 | 6 | 5 | 10 | 5 | 14 | 6 | 15 | 12 | 12 | 12 | 12 |  | 50 Ohms-3 | TOP=L2:L3=L2/L4:L6=L5/L7:BOTTOM=L7 |
| SSD_PRSNT12 | 50OHM_Y12MIL | BUS | 4 | 6 | 5 | 10 | 5 | 14 | 6 | 15 | 12 | 12 | 12 | 12 |  | 50 Ohms-3 | TOP=L2:L3=L2/L4:L6=L5/L7:BOTTOM=L7 |
| SSD_PRSNT12 | 50OHM_Y12MIL | BUS | 5 | 6 | 5 | 10 | 5 | 14 | 6 | 15 | 12 | 12 | 12 | 12 |  | 50 Ohms-3 | TOP=L2:L3=L2/L4:L6=L5/L7:BOTTOM=L7 |
| SSD_PRSNT12 | 50OHM_Y12MIL | BUS | 6 | 6 | 5 | 10 | 5 | 14 | 6 | 15 | 12 | 12 | 12 | 12 |  | 50 Ohms-3 | TOP=L2:L3=L2/L4:L6=L5/L7:BOTTOM=L7 |
| SSD_PRSNT12 | 50OHM_Y12MIL | BUS | 7 | 6 | 5 | 10 | 5 | 14 | 6 | 15 | 12 | 12 | 12 | 12 |  | 50 Ohms-3 | TOP=L2:L3=L2/L4:L6=L5/L7:BOTTOM=L7 |
| SSD_PRSNT12 | 50OHM_Y12MIL | BUS | 8 | 6.75 | 5 | 10 | 5 | 14 | 6 | 15 | 12 | 12 | 12 | 12 |  | 50 Ohms-3 | TOP=L2:L3=L2/L4:L6=L5/L7:BOTTOM=L7 |
| SSD_PRSNT13 | 50OHM_Y12MIL | BUS | 1 | 6.75 | 5 | 10 | 5 | 14 | 6 | 15 | 12 | 12 | 12 | 12 |  | 50 Ohms-3 | TOP=L2:L3=L2/L4:L6=L5/L7:BOTTOM=L7 |
| SSD_PRSNT13 | 50OHM_Y12MIL | BUS | 2 | 6 | 5 | 10 | 5 | 14 | 6 | 15 | 12 | 12 | 12 | 12 |  | 50 Ohms-3 | TOP=L2:L3=L2/L4:L6=L5/L7:BOTTOM=L7 |
| SSD_PRSNT13 | 50OHM_Y12MIL | BUS | 3 | 6 | 5 | 10 | 5 | 14 | 6 | 15 | 12 | 12 | 12 | 12 |  | 50 Ohms-3 | TOP=L2:L3=L2/L4:L6=L5/L7:BOTTOM=L7 |
| SSD_PRSNT13 | 50OHM_Y12MIL | BUS | 4 | 6 | 5 | 10 | 5 | 14 | 6 | 15 | 12 | 12 | 12 | 12 |  | 50 Ohms-3 | TOP=L2:L3=L2/L4:L6=L5/L7:BOTTOM=L7 |
| SSD_PRSNT13 | 50OHM_Y12MIL | BUS | 5 | 6 | 5 | 10 | 5 | 14 | 6 | 15 | 12 | 12 | 12 | 12 |  | 50 Ohms-3 | TOP=L2:L3=L2/L4:L6=L5/L7:BOTTOM=L7 |
| SSD_PRSNT13 | 50OHM_Y12MIL | BUS | 6 | 6 | 5 | 10 | 5 | 14 | 6 | 15 | 12 | 12 | 12 | 12 |  | 50 Ohms-3 | TOP=L2:L3=L2/L4:L6=L5/L7:BOTTOM=L7 |
| SSD_PRSNT13 | 50OHM_Y12MIL | BUS | 7 | 6 | 5 | 10 | 5 | 14 | 6 | 15 | 12 | 12 | 12 | 12 |  | 50 Ohms-3 | TOP=L2:L3=L2/L4:L6=L5/L7:BOTTOM=L7 |
| SSD_PRSNT13 | 50OHM_Y12MIL | BUS | 8 | 6.75 | 5 | 10 | 5 | 14 | 6 | 15 | 12 | 12 | 12 | 12 |  | 50 Ohms-3 | TOP=L2:L3=L2/L4:L6=L5/L7:BOTTOM=L7 |
| SSD_PRSNT14 | 50OHM_Y12MIL | BUS | 1 | 6.75 | 5 | 10 | 5 | 14 | 6 | 15 | 12 | 12 | 12 | 12 |  | 50 Ohms-3 | TOP=L2:L3=L2/L4:L6=L5/L7:BOTTOM=L7 |
| SSD_PRSNT14 | 50OHM_Y12MIL | BUS | 2 | 6 | 5 | 10 | 5 | 14 | 6 | 15 | 12 | 12 | 12 | 12 |  | 50 Ohms-3 | TOP=L2:L3=L2/L4:L6=L5/L7:BOTTOM=L7 |
| SSD_PRSNT14 | 50OHM_Y12MIL | BUS | 3 | 6 | 5 | 10 | 5 | 14 | 6 | 15 | 12 | 12 | 12 | 12 |  | 50 Ohms-3 | TOP=L2:L3=L2/L4:L6=L5/L7:BOTTOM=L7 |
| SSD_PRSNT14 | 50OHM_Y12MIL | BUS | 4 | 6 | 5 | 10 | 5 | 14 | 6 | 15 | 12 | 12 | 12 | 12 |  | 50 Ohms-3 | TOP=L2:L3=L2/L4:L6=L5/L7:BOTTOM=L7 |
| SSD_PRSNT14 | 50OHM_Y12MIL | BUS | 5 | 6 | 5 | 10 | 5 | 14 | 6 | 15 | 12 | 12 | 12 | 12 |  | 50 Ohms-3 | TOP=L2:L3=L2/L4:L6=L5/L7:BOTTOM=L7 |
| SSD_PRSNT14 | 50OHM_Y12MIL | BUS | 6 | 6 | 5 | 10 | 5 | 14 | 6 | 15 | 12 | 12 | 12 | 12 |  | 50 Ohms-3 | TOP=L2:L3=L2/L4:L6=L5/L7:BOTTOM=L7 |
| SSD_PRSNT14 | 50OHM_Y12MIL | BUS | 7 | 6 | 5 | 10 | 5 | 14 | 6 | 15 | 12 | 12 | 12 | 12 |  | 50 Ohms-3 | TOP=L2:L3=L2/L4:L6=L5/L7:BOTTOM=L7 |
| SSD_PRSNT14 | 50OHM_Y12MIL | BUS | 8 | 6.75 | 5 | 10 | 5 | 14 | 6 | 15 | 12 | 12 | 12 | 12 |  | 50 Ohms-3 | TOP=L2:L3=L2/L4:L6=L5/L7:BOTTOM=L7 |
| SSD_PRSNT2 | 50OHM_Y12MIL | BUS | 1 | 6.75 | 5 | 10 | 5 | 14 | 6 | 15 | 12 | 12 | 12 | 12 |  | 50 Ohms-3 | TOP=L2:L3=L2/L4:L6=L5/L7:BOTTOM=L7 |
| SSD_PRSNT2 | 50OHM_Y12MIL | BUS | 2 | 6 | 5 | 10 | 5 | 14 | 6 | 15 | 12 | 12 | 12 | 12 |  | 50 Ohms-3 | TOP=L2:L3=L2/L4:L6=L5/L7:BOTTOM=L7 |
| SSD_PRSNT2 | 50OHM_Y12MIL | BUS | 3 | 6 | 5 | 10 | 5 | 14 | 6 | 15 | 12 | 12 | 12 | 12 |  | 50 Ohms-3 | TOP=L2:L3=L2/L4:L6=L5/L7:BOTTOM=L7 |
| SSD_PRSNT2 | 50OHM_Y12MIL | BUS | 4 | 6 | 5 | 10 | 5 | 14 | 6 | 15 | 12 | 12 | 12 | 12 |  | 50 Ohms-3 | TOP=L2:L3=L2/L4:L6=L5/L7:BOTTOM=L7 |
| SSD_PRSNT2 | 50OHM_Y12MIL | BUS | 5 | 6 | 5 | 10 | 5 | 14 | 6 | 15 | 12 | 12 | 12 | 12 |  | 50 Ohms-3 | TOP=L2:L3=L2/L4:L6=L5/L7:BOTTOM=L7 |
| SSD_PRSNT2 | 50OHM_Y12MIL | BUS | 6 | 6 | 5 | 10 | 5 | 14 | 6 | 15 | 12 | 12 | 12 | 12 |  | 50 Ohms-3 | TOP=L2:L3=L2/L4:L6=L5/L7:BOTTOM=L7 |
| SSD_PRSNT2 | 50OHM_Y12MIL | BUS | 7 | 6 | 5 | 10 | 5 | 14 | 6 | 15 | 12 | 12 | 12 | 12 |  | 50 Ohms-3 | TOP=L2:L3=L2/L4:L6=L5/L7:BOTTOM=L7 |
| SSD_PRSNT2 | 50OHM_Y12MIL | BUS | 8 | 6.75 | 5 | 10 | 5 | 14 | 6 | 15 | 12 | 12 | 12 | 12 |  | 50 Ohms-3 | TOP=L2:L3=L2/L4:L6=L5/L7:BOTTOM=L7 |
| SSD_PRSNT3 | 50OHM_Y12MIL | BUS | 1 | 6.75 | 5 | 10 | 5 | 14 | 6 | 15 | 12 | 12 | 12 | 12 |  | 50 Ohms-3 | TOP=L2:L3=L2/L4:L6=L5/L7:BOTTOM=L7 |
| SSD_PRSNT3 | 50OHM_Y12MIL | BUS | 2 | 6 | 5 | 10 | 5 | 14 | 6 | 15 | 12 | 12 | 12 | 12 |  | 50 Ohms-3 | TOP=L2:L3=L2/L4:L6=L5/L7:BOTTOM=L7 |
| SSD_PRSNT3 | 50OHM_Y12MIL | BUS | 3 | 6 | 5 | 10 | 5 | 14 | 6 | 15 | 12 | 12 | 12 | 12 |  | 50 Ohms-3 | TOP=L2:L3=L2/L4:L6=L5/L7:BOTTOM=L7 |
| SSD_PRSNT3 | 50OHM_Y12MIL | BUS | 4 | 6 | 5 | 10 | 5 | 14 | 6 | 15 | 12 | 12 | 12 | 12 |  | 50 Ohms-3 | TOP=L2:L3=L2/L4:L6=L5/L7:BOTTOM=L7 |
| SSD_PRSNT3 | 50OHM_Y12MIL | BUS | 5 | 6 | 5 | 10 | 5 | 14 | 6 | 15 | 12 | 12 | 12 | 12 |  | 50 Ohms-3 | TOP=L2:L3=L2/L4:L6=L5/L7:BOTTOM=L7 |
| SSD_PRSNT3 | 50OHM_Y12MIL | BUS | 6 | 6 | 5 | 10 | 5 | 14 | 6 | 15 | 12 | 12 | 12 | 12 |  | 50 Ohms-3 | TOP=L2:L3=L2/L4:L6=L5/L7:BOTTOM=L7 |
| SSD_PRSNT3 | 50OHM_Y12MIL | BUS | 7 | 6 | 5 | 10 | 5 | 14 | 6 | 15 | 12 | 12 | 12 | 12 |  | 50 Ohms-3 | TOP=L2:L3=L2/L4:L6=L5/L7:BOTTOM=L7 |
| SSD_PRSNT3 | 50OHM_Y12MIL | BUS | 8 | 6.75 | 5 | 10 | 5 | 14 | 6 | 15 | 12 | 12 | 12 | 12 |  | 50 Ohms-3 | TOP=L2:L3=L2/L4:L6=L5/L7:BOTTOM=L7 |
| SSD_PRSNT4 | 50OHM_Y12MIL | BUS | 1 | 6.75 | 5 | 10 | 5 | 14 | 6 | 15 | 12 | 12 | 12 | 12 |  | 50 Ohms-3 | TOP=L2:L3=L2/L4:L6=L5/L7:BOTTOM=L7 |
| SSD_PRSNT4 | 50OHM_Y12MIL | BUS | 2 | 6 | 5 | 10 | 5 | 14 | 6 | 15 | 12 | 12 | 12 | 12 |  | 50 Ohms-3 | TOP=L2:L3=L2/L4:L6=L5/L7:BOTTOM=L7 |
| SSD_PRSNT4 | 50OHM_Y12MIL | BUS | 3 | 6 | 5 | 10 | 5 | 14 | 6 | 15 | 12 | 12 | 12 | 12 |  | 50 Ohms-3 | TOP=L2:L3=L2/L4:L6=L5/L7:BOTTOM=L7 |
| SSD_PRSNT4 | 50OHM_Y12MIL | BUS | 4 | 6 | 5 | 10 | 5 | 14 | 6 | 15 | 12 | 12 | 12 | 12 |  | 50 Ohms-3 | TOP=L2:L3=L2/L4:L6=L5/L7:BOTTOM=L7 |
| SSD_PRSNT4 | 50OHM_Y12MIL | BUS | 5 | 6 | 5 | 10 | 5 | 14 | 6 | 15 | 12 | 12 | 12 | 12 |  | 50 Ohms-3 | TOP=L2:L3=L2/L4:L6=L5/L7:BOTTOM=L7 |
| SSD_PRSNT4 | 50OHM_Y12MIL | BUS | 6 | 6 | 5 | 10 | 5 | 14 | 6 | 15 | 12 | 12 | 12 | 12 |  | 50 Ohms-3 | TOP=L2:L3=L2/L4:L6=L5/L7:BOTTOM=L7 |
| SSD_PRSNT4 | 50OHM_Y12MIL | BUS | 7 | 6 | 5 | 10 | 5 | 14 | 6 | 15 | 12 | 12 | 12 | 12 |  | 50 Ohms-3 | TOP=L2:L3=L2/L4:L6=L5/L7:BOTTOM=L7 |
| SSD_PRSNT4 | 50OHM_Y12MIL | BUS | 8 | 6.75 | 5 | 10 | 5 | 14 | 6 | 15 | 12 | 12 | 12 | 12 |  | 50 Ohms-3 | TOP=L2:L3=L2/L4:L6=L5/L7:BOTTOM=L7 |
| SSD_PRSNT5 | 50OHM_Y12MIL | BUS | 1 | 6.75 | 5 | 10 | 5 | 14 | 6 | 15 | 12 | 12 | 12 | 12 |  | 50 Ohms-3 | TOP=L2:L3=L2/L4:L6=L5/L7:BOTTOM=L7 |
| SSD_PRSNT5 | 50OHM_Y12MIL | BUS | 2 | 6 | 5 | 10 | 5 | 14 | 6 | 15 | 12 | 12 | 12 | 12 |  | 50 Ohms-3 | TOP=L2:L3=L2/L4:L6=L5/L7:BOTTOM=L7 |
| SSD_PRSNT5 | 50OHM_Y12MIL | BUS | 3 | 6 | 5 | 10 | 5 | 14 | 6 | 15 | 12 | 12 | 12 | 12 |  | 50 Ohms-3 | TOP=L2:L3=L2/L4:L6=L5/L7:BOTTOM=L7 |
| SSD_PRSNT5 | 50OHM_Y12MIL | BUS | 4 | 6 | 5 | 10 | 5 | 14 | 6 | 15 | 12 | 12 | 12 | 12 |  | 50 Ohms-3 | TOP=L2:L3=L2/L4:L6=L5/L7:BOTTOM=L7 |
| SSD_PRSNT5 | 50OHM_Y12MIL | BUS | 5 | 6 | 5 | 10 | 5 | 14 | 6 | 15 | 12 | 12 | 12 | 12 |  | 50 Ohms-3 | TOP=L2:L3=L2/L4:L6=L5/L7:BOTTOM=L7 |
| SSD_PRSNT5 | 50OHM_Y12MIL | BUS | 6 | 6 | 5 | 10 | 5 | 14 | 6 | 15 | 12 | 12 | 12 | 12 |  | 50 Ohms-3 | TOP=L2:L3=L2/L4:L6=L5/L7:BOTTOM=L7 |
| SSD_PRSNT5 | 50OHM_Y12MIL | BUS | 7 | 6 | 5 | 10 | 5 | 14 | 6 | 15 | 12 | 12 | 12 | 12 |  | 50 Ohms-3 | TOP=L2:L3=L2/L4:L6=L5/L7:BOTTOM=L7 |
| SSD_PRSNT5 | 50OHM_Y12MIL | BUS | 8 | 6.75 | 5 | 10 | 5 | 14 | 6 | 15 | 12 | 12 | 12 | 12 |  | 50 Ohms-3 | TOP=L2:L3=L2/L4:L6=L5/L7:BOTTOM=L7 |
| SSD_PRSNT6 | 50OHM_Y12MIL | BUS | 1 | 6.75 | 5 | 10 | 5 | 14 | 6 | 15 | 12 | 12 | 12 | 12 |  | 50 Ohms-3 | TOP=L2:L3=L2/L4:L6=L5/L7:BOTTOM=L7 |
| SSD_PRSNT6 | 50OHM_Y12MIL | BUS | 2 | 6 | 5 | 10 | 5 | 14 | 6 | 15 | 12 | 12 | 12 | 12 |  | 50 Ohms-3 | TOP=L2:L3=L2/L4:L6=L5/L7:BOTTOM=L7 |
| SSD_PRSNT6 | 50OHM_Y12MIL | BUS | 3 | 6 | 5 | 10 | 5 | 14 | 6 | 15 | 12 | 12 | 12 | 12 |  | 50 Ohms-3 | TOP=L2:L3=L2/L4:L6=L5/L7:BOTTOM=L7 |
| SSD_PRSNT6 | 50OHM_Y12MIL | BUS | 4 | 6 | 5 | 10 | 5 | 14 | 6 | 15 | 12 | 12 | 12 | 12 |  | 50 Ohms-3 | TOP=L2:L3=L2/L4:L6=L5/L7:BOTTOM=L7 |
| SSD_PRSNT6 | 50OHM_Y12MIL | BUS | 5 | 6 | 5 | 10 | 5 | 14 | 6 | 15 | 12 | 12 | 12 | 12 |  | 50 Ohms-3 | TOP=L2:L3=L2/L4:L6=L5/L7:BOTTOM=L7 |
| SSD_PRSNT6 | 50OHM_Y12MIL | BUS | 6 | 6 | 5 | 10 | 5 | 14 | 6 | 15 | 12 | 12 | 12 | 12 |  | 50 Ohms-3 | TOP=L2:L3=L2/L4:L6=L5/L7:BOTTOM=L7 |
| SSD_PRSNT6 | 50OHM_Y12MIL | BUS | 7 | 6 | 5 | 10 | 5 | 14 | 6 | 15 | 12 | 12 | 12 | 12 |  | 50 Ohms-3 | TOP=L2:L3=L2/L4:L6=L5/L7:BOTTOM=L7 |
| SSD_PRSNT6 | 50OHM_Y12MIL | BUS | 8 | 6.75 | 5 | 10 | 5 | 14 | 6 | 15 | 12 | 12 | 12 | 12 |  | 50 Ohms-3 | TOP=L2:L3=L2/L4:L6=L5/L7:BOTTOM=L7 |
| SSD_PRSNT7 | 50OHM_Y12MIL | BUS | 1 | 6.75 | 5 | 10 | 5 | 14 | 6 | 15 | 12 | 12 | 12 | 12 |  | 50 Ohms-3 | TOP=L2:L3=L2/L4:L6=L5/L7:BOTTOM=L7 |
| SSD_PRSNT7 | 50OHM_Y12MIL | BUS | 2 | 6 | 5 | 10 | 5 | 14 | 6 | 15 | 12 | 12 | 12 | 12 |  | 50 Ohms-3 | TOP=L2:L3=L2/L4:L6=L5/L7:BOTTOM=L7 |
| SSD_PRSNT7 | 50OHM_Y12MIL | BUS | 3 | 6 | 5 | 10 | 5 | 14 | 6 | 15 | 12 | 12 | 12 | 12 |  | 50 Ohms-3 | TOP=L2:L3=L2/L4:L6=L5/L7:BOTTOM=L7 |
| SSD_PRSNT7 | 50OHM_Y12MIL | BUS | 4 | 6 | 5 | 10 | 5 | 14 | 6 | 15 | 12 | 12 | 12 | 12 |  | 50 Ohms-3 | TOP=L2:L3=L2/L4:L6=L5/L7:BOTTOM=L7 |
| SSD_PRSNT7 | 50OHM_Y12MIL | BUS | 5 | 6 | 5 | 10 | 5 | 14 | 6 | 15 | 12 | 12 | 12 | 12 |  | 50 Ohms-3 | TOP=L2:L3=L2/L4:L6=L5/L7:BOTTOM=L7 |
| SSD_PRSNT7 | 50OHM_Y12MIL | BUS | 6 | 6 | 5 | 10 | 5 | 14 | 6 | 15 | 12 | 12 | 12 | 12 |  | 50 Ohms-3 | TOP=L2:L3=L2/L4:L6=L5/L7:BOTTOM=L7 |
| SSD_PRSNT7 | 50OHM_Y12MIL | BUS | 7 | 6 | 5 | 10 | 5 | 14 | 6 | 15 | 12 | 12 | 12 | 12 |  | 50 Ohms-3 | TOP=L2:L3=L2/L4:L6=L5/L7:BOTTOM=L7 |
| SSD_PRSNT7 | 50OHM_Y12MIL | BUS | 8 | 6.75 | 5 | 10 | 5 | 14 | 6 | 15 | 12 | 12 | 12 | 12 |  | 50 Ohms-3 | TOP=L2:L3=L2/L4:L6=L5/L7:BOTTOM=L7 |
| SSD_PRSNT8 | 50OHM_Y12MIL | BUS | 1 | 6.75 | 5 | 10 | 5 | 14 | 6 | 15 | 12 | 12 | 12 | 12 |  | 50 Ohms-3 | TOP=L2:L3=L2/L4:L6=L5/L7:BOTTOM=L7 |
| SSD_PRSNT8 | 50OHM_Y12MIL | BUS | 2 | 6 | 5 | 10 | 5 | 14 | 6 | 15 | 12 | 12 | 12 | 12 |  | 50 Ohms-3 | TOP=L2:L3=L2/L4:L6=L5/L7:BOTTOM=L7 |
| SSD_PRSNT8 | 50OHM_Y12MIL | BUS | 3 | 6 | 5 | 10 | 5 | 14 | 6 | 15 | 12 | 12 | 12 | 12 |  | 50 Ohms-3 | TOP=L2:L3=L2/L4:L6=L5/L7:BOTTOM=L7 |
| SSD_PRSNT8 | 50OHM_Y12MIL | BUS | 4 | 6 | 5 | 10 | 5 | 14 | 6 | 15 | 12 | 12 | 12 | 12 |  | 50 Ohms-3 | TOP=L2:L3=L2/L4:L6=L5/L7:BOTTOM=L7 |
| SSD_PRSNT8 | 50OHM_Y12MIL | BUS | 5 | 6 | 5 | 10 | 5 | 14 | 6 | 15 | 12 | 12 | 12 | 12 |  | 50 Ohms-3 | TOP=L2:L3=L2/L4:L6=L5/L7:BOTTOM=L7 |
| SSD_PRSNT8 | 50OHM_Y12MIL | BUS | 6 | 6 | 5 | 10 | 5 | 14 | 6 | 15 | 12 | 12 | 12 | 12 |  | 50 Ohms-3 | TOP=L2:L3=L2/L4:L6=L5/L7:BOTTOM=L7 |
| SSD_PRSNT8 | 50OHM_Y12MIL | BUS | 7 | 6 | 5 | 10 | 5 | 14 | 6 | 15 | 12 | 12 | 12 | 12 |  | 50 Ohms-3 | TOP=L2:L3=L2/L4:L6=L5/L7:BOTTOM=L7 |
| SSD_PRSNT8 | 50OHM_Y12MIL | BUS | 8 | 6.75 | 5 | 10 | 5 | 14 | 6 | 15 | 12 | 12 | 12 | 12 |  | 50 Ohms-3 | TOP=L2:L3=L2/L4:L6=L5/L7:BOTTOM=L7 |
| SSD_PRSNT9 | 50OHM_Y12MIL | BUS | 1 | 6.75 | 5 | 10 | 5 | 14 | 6 | 15 | 12 | 12 | 12 | 12 |  | 50 Ohms-3 | TOP=L2:L3=L2/L4:L6=L5/L7:BOTTOM=L7 |
| SSD_PRSNT9 | 50OHM_Y12MIL | BUS | 2 | 6 | 5 | 10 | 5 | 14 | 6 | 15 | 12 | 12 | 12 | 12 |  | 50 Ohms-3 | TOP=L2:L3=L2/L4:L6=L5/L7:BOTTOM=L7 |
| SSD_PRSNT9 | 50OHM_Y12MIL | BUS | 3 | 6 | 5 | 10 | 5 | 14 | 6 | 15 | 12 | 12 | 12 | 12 |  | 50 Ohms-3 | TOP=L2:L3=L2/L4:L6=L5/L7:BOTTOM=L7 |
| SSD_PRSNT9 | 50OHM_Y12MIL | BUS | 4 | 6 | 5 | 10 | 5 | 14 | 6 | 15 | 12 | 12 | 12 | 12 |  | 50 Ohms-3 | TOP=L2:L3=L2/L4:L6=L5/L7:BOTTOM=L7 |
| SSD_PRSNT9 | 50OHM_Y12MIL | BUS | 5 | 6 | 5 | 10 | 5 | 14 | 6 | 15 | 12 | 12 | 12 | 12 |  | 50 Ohms-3 | TOP=L2:L3=L2/L4:L6=L5/L7:BOTTOM=L7 |
| SSD_PRSNT9 | 50OHM_Y12MIL | BUS | 6 | 6 | 5 | 10 | 5 | 14 | 6 | 15 | 12 | 12 | 12 | 12 |  | 50 Ohms-3 | TOP=L2:L3=L2/L4:L6=L5/L7:BOTTOM=L7 |
| SSD_PRSNT9 | 50OHM_Y12MIL | BUS | 7 | 6 | 5 | 10 | 5 | 14 | 6 | 15 | 12 | 12 | 12 | 12 |  | 50 Ohms-3 | TOP=L2:L3=L2/L4:L6=L5/L7:BOTTOM=L7 |
| SSD_PRSNT9 | 50OHM_Y12MIL | BUS | 8 | 6.75 | 5 | 10 | 5 | 14 | 6 | 15 | 12 | 12 | 12 | 12 |  | 50 Ohms-3 | TOP=L2:L3=L2/L4:L6=L5/L7:BOTTOM=L7 |
| SSD0_CLK0_OE_MOS_N | 50OHM_Y12MIL | BUS | 1 | 6.75 | 5 | 10 | 5 | 14 | 6 | 15 | 12 | 12 | 12 | 12 |  | 50 Ohms-3 | TOP=L2:L3=L2/L4:L6=L5/L7:BOTTOM=L7 |
| SSD0_CLK0_OE_MOS_N | 50OHM_Y12MIL | BUS | 2 | 6 | 5 | 10 | 5 | 14 | 6 | 15 | 12 | 12 | 12 | 12 |  | 50 Ohms-3 | TOP=L2:L3=L2/L4:L6=L5/L7:BOTTOM=L7 |
| SSD0_CLK0_OE_MOS_N | 50OHM_Y12MIL | BUS | 3 | 6 | 5 | 10 | 5 | 14 | 6 | 15 | 12 | 12 | 12 | 12 |  | 50 Ohms-3 | TOP=L2:L3=L2/L4:L6=L5/L7:BOTTOM=L7 |
| SSD0_CLK0_OE_MOS_N | 50OHM_Y12MIL | BUS | 4 | 6 | 5 | 10 | 5 | 14 | 6 | 15 | 12 | 12 | 12 | 12 |  | 50 Ohms-3 | TOP=L2:L3=L2/L4:L6=L5/L7:BOTTOM=L7 |
| SSD0_CLK0_OE_MOS_N | 50OHM_Y12MIL | BUS | 5 | 6 | 5 | 10 | 5 | 14 | 6 | 15 | 12 | 12 | 12 | 12 |  | 50 Ohms-3 | TOP=L2:L3=L2/L4:L6=L5/L7:BOTTOM=L7 |
| SSD0_CLK0_OE_MOS_N | 50OHM_Y12MIL | BUS | 6 | 6 | 5 | 10 | 5 | 14 | 6 | 15 | 12 | 12 | 12 | 12 |  | 50 Ohms-3 | TOP=L2:L3=L2/L4:L6=L5/L7:BOTTOM=L7 |
| SSD0_CLK0_OE_MOS_N | 50OHM_Y12MIL | BUS | 7 | 6 | 5 | 10 | 5 | 14 | 6 | 15 | 12 | 12 | 12 | 12 |  | 50 Ohms-3 | TOP=L2:L3=L2/L4:L6=L5/L7:BOTTOM=L7 |
| SSD0_CLK0_OE_MOS_N | 50OHM_Y12MIL | BUS | 8 | 6.75 | 5 | 10 | 5 | 14 | 6 | 15 | 12 | 12 | 12 | 12 |  | 50 Ohms-3 | TOP=L2:L3=L2/L4:L6=L5/L7:BOTTOM=L7 |
| SSD0_CLK0_OE_N | 50OHM_Y12MIL | BUS | 1 | 6.75 | 5 | 10 | 5 | 14 | 6 | 15 | 12 | 12 | 12 | 12 |  | 50 Ohms-3 | TOP=L2:L3=L2/L4:L6=L5/L7:BOTTOM=L7 |
| SSD0_CLK0_OE_N | 50OHM_Y12MIL | BUS | 2 | 6 | 5 | 10 | 5 | 14 | 6 | 15 | 12 | 12 | 12 | 12 |  | 50 Ohms-3 | TOP=L2:L3=L2/L4:L6=L5/L7:BOTTOM=L7 |
| SSD0_CLK0_OE_N | 50OHM_Y12MIL | BUS | 3 | 6 | 5 | 10 | 5 | 14 | 6 | 15 | 12 | 12 | 12 | 12 |  | 50 Ohms-3 | TOP=L2:L3=L2/L4:L6=L5/L7:BOTTOM=L7 |
| SSD0_CLK0_OE_N | 50OHM_Y12MIL | BUS | 4 | 6 | 5 | 10 | 5 | 14 | 6 | 15 | 12 | 12 | 12 | 12 |  | 50 Ohms-3 | TOP=L2:L3=L2/L4:L6=L5/L7:BOTTOM=L7 |
| SSD0_CLK0_OE_N | 50OHM_Y12MIL | BUS | 5 | 6 | 5 | 10 | 5 | 14 | 6 | 15 | 12 | 12 | 12 | 12 |  | 50 Ohms-3 | TOP=L2:L3=L2/L4:L6=L5/L7:BOTTOM=L7 |
| SSD0_CLK0_OE_N | 50OHM_Y12MIL | BUS | 6 | 6 | 5 | 10 | 5 | 14 | 6 | 15 | 12 | 12 | 12 | 12 |  | 50 Ohms-3 | TOP=L2:L3=L2/L4:L6=L5/L7:BOTTOM=L7 |
| SSD0_CLK0_OE_N | 50OHM_Y12MIL | BUS | 7 | 6 | 5 | 10 | 5 | 14 | 6 | 15 | 12 | 12 | 12 | 12 |  | 50 Ohms-3 | TOP=L2:L3=L2/L4:L6=L5/L7:BOTTOM=L7 |
| SSD0_CLK0_OE_N | 50OHM_Y12MIL | BUS | 8 | 6.75 | 5 | 10 | 5 | 14 | 6 | 15 | 12 | 12 | 12 | 12 |  | 50 Ohms-3 | TOP=L2:L3=L2/L4:L6=L5/L7:BOTTOM=L7 |
| SSD0_CLK0_OE_R_N | 50OHM_Y12MIL | BUS | 1 | 6.75 | 5 | 10 | 5 | 14 | 6 | 15 | 12 | 12 | 12 | 12 |  | 50 Ohms-3 | TOP=L2:L3=L2/L4:L6=L5/L7:BOTTOM=L7 |
| SSD0_CLK0_OE_R_N | 50OHM_Y12MIL | BUS | 2 | 6 | 5 | 10 | 5 | 14 | 6 | 15 | 12 | 12 | 12 | 12 |  | 50 Ohms-3 | TOP=L2:L3=L2/L4:L6=L5/L7:BOTTOM=L7 |
| SSD0_CLK0_OE_R_N | 50OHM_Y12MIL | BUS | 3 | 6 | 5 | 10 | 5 | 14 | 6 | 15 | 12 | 12 | 12 | 12 |  | 50 Ohms-3 | TOP=L2:L3=L2/L4:L6=L5/L7:BOTTOM=L7 |
| SSD0_CLK0_OE_R_N | 50OHM_Y12MIL | BUS | 4 | 6 | 5 | 10 | 5 | 14 | 6 | 15 | 12 | 12 | 12 | 12 |  | 50 Ohms-3 | TOP=L2:L3=L2/L4:L6=L5/L7:BOTTOM=L7 |
| SSD0_CLK0_OE_R_N | 50OHM_Y12MIL | BUS | 5 | 6 | 5 | 10 | 5 | 14 | 6 | 15 | 12 | 12 | 12 | 12 |  | 50 Ohms-3 | TOP=L2:L3=L2/L4:L6=L5/L7:BOTTOM=L7 |
| SSD0_CLK0_OE_R_N | 50OHM_Y12MIL | BUS | 6 | 6 | 5 | 10 | 5 | 14 | 6 | 15 | 12 | 12 | 12 | 12 |  | 50 Ohms-3 | TOP=L2:L3=L2/L4:L6=L5/L7:BOTTOM=L7 |
| SSD0_CLK0_OE_R_N | 50OHM_Y12MIL | BUS | 7 | 6 | 5 | 10 | 5 | 14 | 6 | 15 | 12 | 12 | 12 | 12 |  | 50 Ohms-3 | TOP=L2:L3=L2/L4:L6=L5/L7:BOTTOM=L7 |
| SSD0_CLK0_OE_R_N | 50OHM_Y12MIL | BUS | 8 | 6.75 | 5 | 10 | 5 | 14 | 6 | 15 | 12 | 12 | 12 | 12 |  | 50 Ohms-3 | TOP=L2:L3=L2/L4:L6=L5/L7:BOTTOM=L7 |
| SSD0_PERST_N | 50OHM_Y12MIL | BUS | 1 | 6.75 | 5 | 10 | 5 | 14 | 6 | 15 | 12 | 12 | 12 | 12 |  | 50 Ohms-3 | TOP=L2:L3=L2/L4:L6=L5/L7:BOTTOM=L7 |
| SSD0_PERST_N | 50OHM_Y12MIL | BUS | 2 | 6 | 5 | 10 | 5 | 14 | 6 | 15 | 12 | 12 | 12 | 12 |  | 50 Ohms-3 | TOP=L2:L3=L2/L4:L6=L5/L7:BOTTOM=L7 |
| SSD0_PERST_N | 50OHM_Y12MIL | BUS | 3 | 6 | 5 | 10 | 5 | 14 | 6 | 15 | 12 | 12 | 12 | 12 |  | 50 Ohms-3 | TOP=L2:L3=L2/L4:L6=L5/L7:BOTTOM=L7 |
| SSD0_PERST_N | 50OHM_Y12MIL | BUS | 4 | 6 | 5 | 10 | 5 | 14 | 6 | 15 | 12 | 12 | 12 | 12 |  | 50 Ohms-3 | TOP=L2:L3=L2/L4:L6=L5/L7:BOTTOM=L7 |
| SSD0_PERST_N | 50OHM_Y12MIL | BUS | 5 | 6 | 5 | 10 | 5 | 14 | 6 | 15 | 12 | 12 | 12 | 12 |  | 50 Ohms-3 | TOP=L2:L3=L2/L4:L6=L5/L7:BOTTOM=L7 |
| SSD0_PERST_N | 50OHM_Y12MIL | BUS | 6 | 6 | 5 | 10 | 5 | 14 | 6 | 15 | 12 | 12 | 12 | 12 |  | 50 Ohms-3 | TOP=L2:L3=L2/L4:L6=L5/L7:BOTTOM=L7 |
| SSD0_PERST_N | 50OHM_Y12MIL | BUS | 7 | 6 | 5 | 10 | 5 | 14 | 6 | 15 | 12 | 12 | 12 | 12 |  | 50 Ohms-3 | TOP=L2:L3=L2/L4:L6=L5/L7:BOTTOM=L7 |
| SSD0_PERST_N | 50OHM_Y12MIL | BUS | 8 | 6.75 | 5 | 10 | 5 | 14 | 6 | 15 | 12 | 12 | 12 | 12 |  | 50 Ohms-3 | TOP=L2:L3=L2/L4:L6=L5/L7:BOTTOM=L7 |
| SSD0_PWREN | 50OHM_Y12MIL | BUS | 1 | 6.75 | 5 | 10 | 5 | 14 | 6 | 15 | 12 | 12 | 12 | 12 |  | 50 Ohms-3 | TOP=L2:L3=L2/L4:L6=L5/L7:BOTTOM=L7 |
| SSD0_PWREN | 50OHM_Y12MIL | BUS | 2 | 6 | 5 | 10 | 5 | 14 | 6 | 15 | 12 | 12 | 12 | 12 |  | 50 Ohms-3 | TOP=L2:L3=L2/L4:L6=L5/L7:BOTTOM=L7 |
| SSD0_PWREN | 50OHM_Y12MIL | BUS | 3 | 6 | 5 | 10 | 5 | 14 | 6 | 15 | 12 | 12 | 12 | 12 |  | 50 Ohms-3 | TOP=L2:L3=L2/L4:L6=L5/L7:BOTTOM=L7 |
| SSD0_PWREN | 50OHM_Y12MIL | BUS | 4 | 6 | 5 | 10 | 5 | 14 | 6 | 15 | 12 | 12 | 12 | 12 |  | 50 Ohms-3 | TOP=L2:L3=L2/L4:L6=L5/L7:BOTTOM=L7 |
| SSD0_PWREN | 50OHM_Y12MIL | BUS | 5 | 6 | 5 | 10 | 5 | 14 | 6 | 15 | 12 | 12 | 12 | 12 |  | 50 Ohms-3 | TOP=L2:L3=L2/L4:L6=L5/L7:BOTTOM=L7 |
| SSD0_PWREN | 50OHM_Y12MIL | BUS | 6 | 6 | 5 | 10 | 5 | 14 | 6 | 15 | 12 | 12 | 12 | 12 |  | 50 Ohms-3 | TOP=L2:L3=L2/L4:L6=L5/L7:BOTTOM=L7 |
| SSD0_PWREN | 50OHM_Y12MIL | BUS | 7 | 6 | 5 | 10 | 5 | 14 | 6 | 15 | 12 | 12 | 12 | 12 |  | 50 Ohms-3 | TOP=L2:L3=L2/L4:L6=L5/L7:BOTTOM=L7 |
| SSD0_PWREN | 50OHM_Y12MIL | BUS | 8 | 6.75 | 5 | 10 | 5 | 14 | 6 | 15 | 12 | 12 | 12 | 12 |  | 50 Ohms-3 | TOP=L2:L3=L2/L4:L6=L5/L7:BOTTOM=L7 |
| SSD0_PWREN_R | 50OHM_Y12MIL | BUS | 1 | 6.75 | 5 | 10 | 5 | 14 | 6 | 15 | 12 | 12 | 12 | 12 |  | 50 Ohms-3 | TOP=L2:L3=L2/L4:L6=L5/L7:BOTTOM=L7 |
| SSD0_PWREN_R | 50OHM_Y12MIL | BUS | 2 | 6 | 5 | 10 | 5 | 14 | 6 | 15 | 12 | 12 | 12 | 12 |  | 50 Ohms-3 | TOP=L2:L3=L2/L4:L6=L5/L7:BOTTOM=L7 |
| SSD0_PWREN_R | 50OHM_Y12MIL | BUS | 3 | 6 | 5 | 10 | 5 | 14 | 6 | 15 | 12 | 12 | 12 | 12 |  | 50 Ohms-3 | TOP=L2:L3=L2/L4:L6=L5/L7:BOTTOM=L7 |
| SSD0_PWREN_R | 50OHM_Y12MIL | BUS | 4 | 6 | 5 | 10 | 5 | 14 | 6 | 15 | 12 | 12 | 12 | 12 |  | 50 Ohms-3 | TOP=L2:L3=L2/L4:L6=L5/L7:BOTTOM=L7 |
| SSD0_PWREN_R | 50OHM_Y12MIL | BUS | 5 | 6 | 5 | 10 | 5 | 14 | 6 | 15 | 12 | 12 | 12 | 12 |  | 50 Ohms-3 | TOP=L2:L3=L2/L4:L6=L5/L7:BOTTOM=L7 |
| SSD0_PWREN_R | 50OHM_Y12MIL | BUS | 6 | 6 | 5 | 10 | 5 | 14 | 6 | 15 | 12 | 12 | 12 | 12 |  | 50 Ohms-3 | TOP=L2:L3=L2/L4:L6=L5/L7:BOTTOM=L7 |
| SSD0_PWREN_R | 50OHM_Y12MIL | BUS | 7 | 6 | 5 | 10 | 5 | 14 | 6 | 15 | 12 | 12 | 12 | 12 |  | 50 Ohms-3 | TOP=L2:L3=L2/L4:L6=L5/L7:BOTTOM=L7 |
| SSD0_PWREN_R | 50OHM_Y12MIL | BUS | 8 | 6.75 | 5 | 10 | 5 | 14 | 6 | 15 | 12 | 12 | 12 | 12 |  | 50 Ohms-3 | TOP=L2:L3=L2/L4:L6=L5/L7:BOTTOM=L7 |
| SSD1_CLK0_OE_MOS_N | 50OHM_Y12MIL | BUS | 1 | 6.75 | 5 | 10 | 5 | 14 | 6 | 15 | 12 | 12 | 12 | 12 |  | 50 Ohms-3 | TOP=L2:L3=L2/L4:L6=L5/L7:BOTTOM=L7 |
| SSD1_CLK0_OE_MOS_N | 50OHM_Y12MIL | BUS | 2 | 6 | 5 | 10 | 5 | 14 | 6 | 15 | 12 | 12 | 12 | 12 |  | 50 Ohms-3 | TOP=L2:L3=L2/L4:L6=L5/L7:BOTTOM=L7 |
| SSD1_CLK0_OE_MOS_N | 50OHM_Y12MIL | BUS | 3 | 6 | 5 | 10 | 5 | 14 | 6 | 15 | 12 | 12 | 12 | 12 |  | 50 Ohms-3 | TOP=L2:L3=L2/L4:L6=L5/L7:BOTTOM=L7 |
| SSD1_CLK0_OE_MOS_N | 50OHM_Y12MIL | BUS | 4 | 6 | 5 | 10 | 5 | 14 | 6 | 15 | 12 | 12 | 12 | 12 |  | 50 Ohms-3 | TOP=L2:L3=L2/L4:L6=L5/L7:BOTTOM=L7 |
| SSD1_CLK0_OE_MOS_N | 50OHM_Y12MIL | BUS | 5 | 6 | 5 | 10 | 5 | 14 | 6 | 15 | 12 | 12 | 12 | 12 |  | 50 Ohms-3 | TOP=L2:L3=L2/L4:L6=L5/L7:BOTTOM=L7 |
| SSD1_CLK0_OE_MOS_N | 50OHM_Y12MIL | BUS | 6 | 6 | 5 | 10 | 5 | 14 | 6 | 15 | 12 | 12 | 12 | 12 |  | 50 Ohms-3 | TOP=L2:L3=L2/L4:L6=L5/L7:BOTTOM=L7 |
| SSD1_CLK0_OE_MOS_N | 50OHM_Y12MIL | BUS | 7 | 6 | 5 | 10 | 5 | 14 | 6 | 15 | 12 | 12 | 12 | 12 |  | 50 Ohms-3 | TOP=L2:L3=L2/L4:L6=L5/L7:BOTTOM=L7 |
| SSD1_CLK0_OE_MOS_N | 50OHM_Y12MIL | BUS | 8 | 6.75 | 5 | 10 | 5 | 14 | 6 | 15 | 12 | 12 | 12 | 12 |  | 50 Ohms-3 | TOP=L2:L3=L2/L4:L6=L5/L7:BOTTOM=L7 |
| SSD1_CLK0_OE_N | 50OHM_Y12MIL | BUS | 1 | 6.75 | 5 | 10 | 5 | 14 | 6 | 15 | 12 | 12 | 12 | 12 |  | 50 Ohms-3 | TOP=L2:L3=L2/L4:L6=L5/L7:BOTTOM=L7 |
| SSD1_CLK0_OE_N | 50OHM_Y12MIL | BUS | 2 | 6 | 5 | 10 | 5 | 14 | 6 | 15 | 12 | 12 | 12 | 12 |  | 50 Ohms-3 | TOP=L2:L3=L2/L4:L6=L5/L7:BOTTOM=L7 |
| SSD1_CLK0_OE_N | 50OHM_Y12MIL | BUS | 3 | 6 | 5 | 10 | 5 | 14 | 6 | 15 | 12 | 12 | 12 | 12 |  | 50 Ohms-3 | TOP=L2:L3=L2/L4:L6=L5/L7:BOTTOM=L7 |
| SSD1_CLK0_OE_N | 50OHM_Y12MIL | BUS | 4 | 6 | 5 | 10 | 5 | 14 | 6 | 15 | 12 | 12 | 12 | 12 |  | 50 Ohms-3 | TOP=L2:L3=L2/L4:L6=L5/L7:BOTTOM=L7 |
| SSD1_CLK0_OE_N | 50OHM_Y12MIL | BUS | 5 | 6 | 5 | 10 | 5 | 14 | 6 | 15 | 12 | 12 | 12 | 12 |  | 50 Ohms-3 | TOP=L2:L3=L2/L4:L6=L5/L7:BOTTOM=L7 |
| SSD1_CLK0_OE_N | 50OHM_Y12MIL | BUS | 6 | 6 | 5 | 10 | 5 | 14 | 6 | 15 | 12 | 12 | 12 | 12 |  | 50 Ohms-3 | TOP=L2:L3=L2/L4:L6=L5/L7:BOTTOM=L7 |
| SSD1_CLK0_OE_N | 50OHM_Y12MIL | BUS | 7 | 6 | 5 | 10 | 5 | 14 | 6 | 15 | 12 | 12 | 12 | 12 |  | 50 Ohms-3 | TOP=L2:L3=L2/L4:L6=L5/L7:BOTTOM=L7 |
| SSD1_CLK0_OE_N | 50OHM_Y12MIL | BUS | 8 | 6.75 | 5 | 10 | 5 | 14 | 6 | 15 | 12 | 12 | 12 | 12 |  | 50 Ohms-3 | TOP=L2:L3=L2/L4:L6=L5/L7:BOTTOM=L7 |
| SSD1_CLK0_OE_R_N | 50OHM_Y12MIL | BUS | 1 | 6.75 | 5 | 10 | 5 | 14 | 6 | 15 | 12 | 12 | 12 | 12 |  | 50 Ohms-3 | TOP=L2:L3=L2/L4:L6=L5/L7:BOTTOM=L7 |
| SSD1_CLK0_OE_R_N | 50OHM_Y12MIL | BUS | 2 | 6 | 5 | 10 | 5 | 14 | 6 | 15 | 12 | 12 | 12 | 12 |  | 50 Ohms-3 | TOP=L2:L3=L2/L4:L6=L5/L7:BOTTOM=L7 |
| SSD1_CLK0_OE_R_N | 50OHM_Y12MIL | BUS | 3 | 6 | 5 | 10 | 5 | 14 | 6 | 15 | 12 | 12 | 12 | 12 |  | 50 Ohms-3 | TOP=L2:L3=L2/L4:L6=L5/L7:BOTTOM=L7 |
| SSD1_CLK0_OE_R_N | 50OHM_Y12MIL | BUS | 4 | 6 | 5 | 10 | 5 | 14 | 6 | 15 | 12 | 12 | 12 | 12 |  | 50 Ohms-3 | TOP=L2:L3=L2/L4:L6=L5/L7:BOTTOM=L7 |
| SSD1_CLK0_OE_R_N | 50OHM_Y12MIL | BUS | 5 | 6 | 5 | 10 | 5 | 14 | 6 | 15 | 12 | 12 | 12 | 12 |  | 50 Ohms-3 | TOP=L2:L3=L2/L4:L6=L5/L7:BOTTOM=L7 |
| SSD1_CLK0_OE_R_N | 50OHM_Y12MIL | BUS | 6 | 6 | 5 | 10 | 5 | 14 | 6 | 15 | 12 | 12 | 12 | 12 |  | 50 Ohms-3 | TOP=L2:L3=L2/L4:L6=L5/L7:BOTTOM=L7 |
| SSD1_CLK0_OE_R_N | 50OHM_Y12MIL | BUS | 7 | 6 | 5 | 10 | 5 | 14 | 6 | 15 | 12 | 12 | 12 | 12 |  | 50 Ohms-3 | TOP=L2:L3=L2/L4:L6=L5/L7:BOTTOM=L7 |
| SSD1_CLK0_OE_R_N | 50OHM_Y12MIL | BUS | 8 | 6.75 | 5 | 10 | 5 | 14 | 6 | 15 | 12 | 12 | 12 | 12 |  | 50 Ohms-3 | TOP=L2:L3=L2/L4:L6=L5/L7:BOTTOM=L7 |
| SSD1_PERST_N | 50OHM_Y12MIL | BUS | 1 | 6.75 | 5 | 10 | 5 | 14 | 6 | 15 | 12 | 12 | 12 | 12 |  | 50 Ohms-3 | TOP=L2:L3=L2/L4:L6=L5/L7:BOTTOM=L7 |
| SSD1_PERST_N | 50OHM_Y12MIL | BUS | 2 | 6 | 5 | 10 | 5 | 14 | 6 | 15 | 12 | 12 | 12 | 12 |  | 50 Ohms-3 | TOP=L2:L3=L2/L4:L6=L5/L7:BOTTOM=L7 |
| SSD1_PERST_N | 50OHM_Y12MIL | BUS | 3 | 6 | 5 | 10 | 5 | 14 | 6 | 15 | 12 | 12 | 12 | 12 |  | 50 Ohms-3 | TOP=L2:L3=L2/L4:L6=L5/L7:BOTTOM=L7 |
| SSD1_PERST_N | 50OHM_Y12MIL | BUS | 4 | 6 | 5 | 10 | 5 | 14 | 6 | 15 | 12 | 12 | 12 | 12 |  | 50 Ohms-3 | TOP=L2:L3=L2/L4:L6=L5/L7:BOTTOM=L7 |
| SSD1_PERST_N | 50OHM_Y12MIL | BUS | 5 | 6 | 5 | 10 | 5 | 14 | 6 | 15 | 12 | 12 | 12 | 12 |  | 50 Ohms-3 | TOP=L2:L3=L2/L4:L6=L5/L7:BOTTOM=L7 |
| SSD1_PERST_N | 50OHM_Y12MIL | BUS | 6 | 6 | 5 | 10 | 5 | 14 | 6 | 15 | 12 | 12 | 12 | 12 |  | 50 Ohms-3 | TOP=L2:L3=L2/L4:L6=L5/L7:BOTTOM=L7 |
| SSD1_PERST_N | 50OHM_Y12MIL | BUS | 7 | 6 | 5 | 10 | 5 | 14 | 6 | 15 | 12 | 12 | 12 | 12 |  | 50 Ohms-3 | TOP=L2:L3=L2/L4:L6=L5/L7:BOTTOM=L7 |
| SSD1_PERST_N | 50OHM_Y12MIL | BUS | 8 | 6.75 | 5 | 10 | 5 | 14 | 6 | 15 | 12 | 12 | 12 | 12 |  | 50 Ohms-3 | TOP=L2:L3=L2/L4:L6=L5/L7:BOTTOM=L7 |
| SSD1_PWREN | 50OHM_Y12MIL | BUS | 1 | 6.75 | 5 | 10 | 5 | 14 | 6 | 15 | 12 | 12 | 12 | 12 |  | 50 Ohms-3 | TOP=L2:L3=L2/L4:L6=L5/L7:BOTTOM=L7 |
| SSD1_PWREN | 50OHM_Y12MIL | BUS | 2 | 6 | 5 | 10 | 5 | 14 | 6 | 15 | 12 | 12 | 12 | 12 |  | 50 Ohms-3 | TOP=L2:L3=L2/L4:L6=L5/L7:BOTTOM=L7 |
| SSD1_PWREN | 50OHM_Y12MIL | BUS | 3 | 6 | 5 | 10 | 5 | 14 | 6 | 15 | 12 | 12 | 12 | 12 |  | 50 Ohms-3 | TOP=L2:L3=L2/L4:L6=L5/L7:BOTTOM=L7 |
| SSD1_PWREN | 50OHM_Y12MIL | BUS | 4 | 6 | 5 | 10 | 5 | 14 | 6 | 15 | 12 | 12 | 12 | 12 |  | 50 Ohms-3 | TOP=L2:L3=L2/L4:L6=L5/L7:BOTTOM=L7 |
| SSD1_PWREN | 50OHM_Y12MIL | BUS | 5 | 6 | 5 | 10 | 5 | 14 | 6 | 15 | 12 | 12 | 12 | 12 |  | 50 Ohms-3 | TOP=L2:L3=L2/L4:L6=L5/L7:BOTTOM=L7 |
| SSD1_PWREN | 50OHM_Y12MIL | BUS | 6 | 6 | 5 | 10 | 5 | 14 | 6 | 15 | 12 | 12 | 12 | 12 |  | 50 Ohms-3 | TOP=L2:L3=L2/L4:L6=L5/L7:BOTTOM=L7 |
| SSD1_PWREN | 50OHM_Y12MIL | BUS | 7 | 6 | 5 | 10 | 5 | 14 | 6 | 15 | 12 | 12 | 12 | 12 |  | 50 Ohms-3 | TOP=L2:L3=L2/L4:L6=L5/L7:BOTTOM=L7 |
| SSD1_PWREN | 50OHM_Y12MIL | BUS | 8 | 6.75 | 5 | 10 | 5 | 14 | 6 | 15 | 12 | 12 | 12 | 12 |  | 50 Ohms-3 | TOP=L2:L3=L2/L4:L6=L5/L7:BOTTOM=L7 |
| SSD1_PWREN_R | 50OHM_Y12MIL | BUS | 1 | 6.75 | 5 | 10 | 5 | 14 | 6 | 15 | 12 | 12 | 12 | 12 |  | 50 Ohms-3 | TOP=L2:L3=L2/L4:L6=L5/L7:BOTTOM=L7 |
| SSD1_PWREN_R | 50OHM_Y12MIL | BUS | 2 | 6 | 5 | 10 | 5 | 14 | 6 | 15 | 12 | 12 | 12 | 12 |  | 50 Ohms-3 | TOP=L2:L3=L2/L4:L6=L5/L7:BOTTOM=L7 |
| SSD1_PWREN_R | 50OHM_Y12MIL | BUS | 3 | 6 | 5 | 10 | 5 | 14 | 6 | 15 | 12 | 12 | 12 | 12 |  | 50 Ohms-3 | TOP=L2:L3=L2/L4:L6=L5/L7:BOTTOM=L7 |
| SSD1_PWREN_R | 50OHM_Y12MIL | BUS | 4 | 6 | 5 | 10 | 5 | 14 | 6 | 15 | 12 | 12 | 12 | 12 |  | 50 Ohms-3 | TOP=L2:L3=L2/L4:L6=L5/L7:BOTTOM=L7 |
| SSD1_PWREN_R | 50OHM_Y12MIL | BUS | 5 | 6 | 5 | 10 | 5 | 14 | 6 | 15 | 12 | 12 | 12 | 12 |  | 50 Ohms-3 | TOP=L2:L3=L2/L4:L6=L5/L7:BOTTOM=L7 |
| SSD1_PWREN_R | 50OHM_Y12MIL | BUS | 6 | 6 | 5 | 10 | 5 | 14 | 6 | 15 | 12 | 12 | 12 | 12 |  | 50 Ohms-3 | TOP=L2:L3=L2/L4:L6=L5/L7:BOTTOM=L7 |
| SSD1_PWREN_R | 50OHM_Y12MIL | BUS | 7 | 6 | 5 | 10 | 5 | 14 | 6 | 15 | 12 | 12 | 12 | 12 |  | 50 Ohms-3 | TOP=L2:L3=L2/L4:L6=L5/L7:BOTTOM=L7 |
| SSD1_PWREN_R | 50OHM_Y12MIL | BUS | 8 | 6.75 | 5 | 10 | 5 | 14 | 6 | 15 | 12 | 12 | 12 | 12 |  | 50 Ohms-3 | TOP=L2:L3=L2/L4:L6=L5/L7:BOTTOM=L7 |
| SSD10_CLK0_OE_MOS_N | 50OHM_Y12MIL | BUS | 1 | 6.75 | 5 | 10 | 5 | 14 | 6 | 15 | 12 | 12 | 12 | 12 |  | 50 Ohms-3 | TOP=L2:L3=L2/L4:L6=L5/L7:BOTTOM=L7 |
| SSD10_CLK0_OE_MOS_N | 50OHM_Y12MIL | BUS | 2 | 6 | 5 | 10 | 5 | 14 | 6 | 15 | 12 | 12 | 12 | 12 |  | 50 Ohms-3 | TOP=L2:L3=L2/L4:L6=L5/L7:BOTTOM=L7 |
| SSD10_CLK0_OE_MOS_N | 50OHM_Y12MIL | BUS | 3 | 6 | 5 | 10 | 5 | 14 | 6 | 15 | 12 | 12 | 12 | 12 |  | 50 Ohms-3 | TOP=L2:L3=L2/L4:L6=L5/L7:BOTTOM=L7 |
| SSD10_CLK0_OE_MOS_N | 50OHM_Y12MIL | BUS | 4 | 6 | 5 | 10 | 5 | 14 | 6 | 15 | 12 | 12 | 12 | 12 |  | 50 Ohms-3 | TOP=L2:L3=L2/L4:L6=L5/L7:BOTTOM=L7 |
| SSD10_CLK0_OE_MOS_N | 50OHM_Y12MIL | BUS | 5 | 6 | 5 | 10 | 5 | 14 | 6 | 15 | 12 | 12 | 12 | 12 |  | 50 Ohms-3 | TOP=L2:L3=L2/L4:L6=L5/L7:BOTTOM=L7 |
| SSD10_CLK0_OE_MOS_N | 50OHM_Y12MIL | BUS | 6 | 6 | 5 | 10 | 5 | 14 | 6 | 15 | 12 | 12 | 12 | 12 |  | 50 Ohms-3 | TOP=L2:L3=L2/L4:L6=L5/L7:BOTTOM=L7 |
| SSD10_CLK0_OE_MOS_N | 50OHM_Y12MIL | BUS | 7 | 6 | 5 | 10 | 5 | 14 | 6 | 15 | 12 | 12 | 12 | 12 |  | 50 Ohms-3 | TOP=L2:L3=L2/L4:L6=L5/L7:BOTTOM=L7 |
| SSD10_CLK0_OE_MOS_N | 50OHM_Y12MIL | BUS | 8 | 6.75 | 5 | 10 | 5 | 14 | 6 | 15 | 12 | 12 | 12 | 12 |  | 50 Ohms-3 | TOP=L2:L3=L2/L4:L6=L5/L7:BOTTOM=L7 |
| SSD10_CLK0_OE_N | 50OHM_Y12MIL | BUS | 1 | 6.75 | 5 | 10 | 5 | 14 | 6 | 15 | 12 | 12 | 12 | 12 |  | 50 Ohms-3 | TOP=L2:L3=L2/L4:L6=L5/L7:BOTTOM=L7 |
| SSD10_CLK0_OE_N | 50OHM_Y12MIL | BUS | 2 | 6 | 5 | 10 | 5 | 14 | 6 | 15 | 12 | 12 | 12 | 12 |  | 50 Ohms-3 | TOP=L2:L3=L2/L4:L6=L5/L7:BOTTOM=L7 |
| SSD10_CLK0_OE_N | 50OHM_Y12MIL | BUS | 3 | 6 | 5 | 10 | 5 | 14 | 6 | 15 | 12 | 12 | 12 | 12 |  | 50 Ohms-3 | TOP=L2:L3=L2/L4:L6=L5/L7:BOTTOM=L7 |
| SSD10_CLK0_OE_N | 50OHM_Y12MIL | BUS | 4 | 6 | 5 | 10 | 5 | 14 | 6 | 15 | 12 | 12 | 12 | 12 |  | 50 Ohms-3 | TOP=L2:L3=L2/L4:L6=L5/L7:BOTTOM=L7 |
| SSD10_CLK0_OE_N | 50OHM_Y12MIL | BUS | 5 | 6 | 5 | 10 | 5 | 14 | 6 | 15 | 12 | 12 | 12 | 12 |  | 50 Ohms-3 | TOP=L2:L3=L2/L4:L6=L5/L7:BOTTOM=L7 |
| SSD10_CLK0_OE_N | 50OHM_Y12MIL | BUS | 6 | 6 | 5 | 10 | 5 | 14 | 6 | 15 | 12 | 12 | 12 | 12 |  | 50 Ohms-3 | TOP=L2:L3=L2/L4:L6=L5/L7:BOTTOM=L7 |
| SSD10_CLK0_OE_N | 50OHM_Y12MIL | BUS | 7 | 6 | 5 | 10 | 5 | 14 | 6 | 15 | 12 | 12 | 12 | 12 |  | 50 Ohms-3 | TOP=L2:L3=L2/L4:L6=L5/L7:BOTTOM=L7 |
| SSD10_CLK0_OE_N | 50OHM_Y12MIL | BUS | 8 | 6.75 | 5 | 10 | 5 | 14 | 6 | 15 | 12 | 12 | 12 | 12 |  | 50 Ohms-3 | TOP=L2:L3=L2/L4:L6=L5/L7:BOTTOM=L7 |
| SSD10_CLK0_OE_R_N | 50OHM_Y12MIL | BUS | 1 | 6.75 | 5 | 10 | 5 | 14 | 6 | 15 | 12 | 12 | 12 | 12 |  | 50 Ohms-3 | TOP=L2:L3=L2/L4:L6=L5/L7:BOTTOM=L7 |
| SSD10_CLK0_OE_R_N | 50OHM_Y12MIL | BUS | 2 | 6 | 5 | 10 | 5 | 14 | 6 | 15 | 12 | 12 | 12 | 12 |  | 50 Ohms-3 | TOP=L2:L3=L2/L4:L6=L5/L7:BOTTOM=L7 |
| SSD10_CLK0_OE_R_N | 50OHM_Y12MIL | BUS | 3 | 6 | 5 | 10 | 5 | 14 | 6 | 15 | 12 | 12 | 12 | 12 |  | 50 Ohms-3 | TOP=L2:L3=L2/L4:L6=L5/L7:BOTTOM=L7 |
| SSD10_CLK0_OE_R_N | 50OHM_Y12MIL | BUS | 4 | 6 | 5 | 10 | 5 | 14 | 6 | 15 | 12 | 12 | 12 | 12 |  | 50 Ohms-3 | TOP=L2:L3=L2/L4:L6=L5/L7:BOTTOM=L7 |
| SSD10_CLK0_OE_R_N | 50OHM_Y12MIL | BUS | 5 | 6 | 5 | 10 | 5 | 14 | 6 | 15 | 12 | 12 | 12 | 12 |  | 50 Ohms-3 | TOP=L2:L3=L2/L4:L6=L5/L7:BOTTOM=L7 |
| SSD10_CLK0_OE_R_N | 50OHM_Y12MIL | BUS | 6 | 6 | 5 | 10 | 5 | 14 | 6 | 15 | 12 | 12 | 12 | 12 |  | 50 Ohms-3 | TOP=L2:L3=L2/L4:L6=L5/L7:BOTTOM=L7 |
| SSD10_CLK0_OE_R_N | 50OHM_Y12MIL | BUS | 7 | 6 | 5 | 10 | 5 | 14 | 6 | 15 | 12 | 12 | 12 | 12 |  | 50 Ohms-3 | TOP=L2:L3=L2/L4:L6=L5/L7:BOTTOM=L7 |
| SSD10_CLK0_OE_R_N | 50OHM_Y12MIL | BUS | 8 | 6.75 | 5 | 10 | 5 | 14 | 6 | 15 | 12 | 12 | 12 | 12 |  | 50 Ohms-3 | TOP=L2:L3=L2/L4:L6=L5/L7:BOTTOM=L7 |
| SSD10_PERST_N | 50OHM_Y12MIL | BUS | 1 | 6.75 | 5 | 10 | 5 | 14 | 6 | 15 | 12 | 12 | 12 | 12 |  | 50 Ohms-3 | TOP=L2:L3=L2/L4:L6=L5/L7:BOTTOM=L7 |
| SSD10_PERST_N | 50OHM_Y12MIL | BUS | 2 | 6 | 5 | 10 | 5 | 14 | 6 | 15 | 12 | 12 | 12 | 12 |  | 50 Ohms-3 | TOP=L2:L3=L2/L4:L6=L5/L7:BOTTOM=L7 |
| SSD10_PERST_N | 50OHM_Y12MIL | BUS | 3 | 6 | 5 | 10 | 5 | 14 | 6 | 15 | 12 | 12 | 12 | 12 |  | 50 Ohms-3 | TOP=L2:L3=L2/L4:L6=L5/L7:BOTTOM=L7 |
| SSD10_PERST_N | 50OHM_Y12MIL | BUS | 4 | 6 | 5 | 10 | 5 | 14 | 6 | 15 | 12 | 12 | 12 | 12 |  | 50 Ohms-3 | TOP=L2:L3=L2/L4:L6=L5/L7:BOTTOM=L7 |
| SSD10_PERST_N | 50OHM_Y12MIL | BUS | 5 | 6 | 5 | 10 | 5 | 14 | 6 | 15 | 12 | 12 | 12 | 12 |  | 50 Ohms-3 | TOP=L2:L3=L2/L4:L6=L5/L7:BOTTOM=L7 |
| SSD10_PERST_N | 50OHM_Y12MIL | BUS | 6 | 6 | 5 | 10 | 5 | 14 | 6 | 15 | 12 | 12 | 12 | 12 |  | 50 Ohms-3 | TOP=L2:L3=L2/L4:L6=L5/L7:BOTTOM=L7 |
| SSD10_PERST_N | 50OHM_Y12MIL | BUS | 7 | 6 | 5 | 10 | 5 | 14 | 6 | 15 | 12 | 12 | 12 | 12 |  | 50 Ohms-3 | TOP=L2:L3=L2/L4:L6=L5/L7:BOTTOM=L7 |
| SSD10_PERST_N | 50OHM_Y12MIL | BUS | 8 | 6.75 | 5 | 10 | 5 | 14 | 6 | 15 | 12 | 12 | 12 | 12 |  | 50 Ohms-3 | TOP=L2:L3=L2/L4:L6=L5/L7:BOTTOM=L7 |
| SSD10_PWREN | 50OHM_Y12MIL | BUS | 1 | 6.75 | 5 | 10 | 5 | 14 | 6 | 15 | 12 | 12 | 12 | 12 |  | 50 Ohms-3 | TOP=L2:L3=L2/L4:L6=L5/L7:BOTTOM=L7 |
| SSD10_PWREN | 50OHM_Y12MIL | BUS | 2 | 6 | 5 | 10 | 5 | 14 | 6 | 15 | 12 | 12 | 12 | 12 |  | 50 Ohms-3 | TOP=L2:L3=L2/L4:L6=L5/L7:BOTTOM=L7 |
| SSD10_PWREN | 50OHM_Y12MIL | BUS | 3 | 6 | 5 | 10 | 5 | 14 | 6 | 15 | 12 | 12 | 12 | 12 |  | 50 Ohms-3 | TOP=L2:L3=L2/L4:L6=L5/L7:BOTTOM=L7 |
| SSD10_PWREN | 50OHM_Y12MIL | BUS | 4 | 6 | 5 | 10 | 5 | 14 | 6 | 15 | 12 | 12 | 12 | 12 |  | 50 Ohms-3 | TOP=L2:L3=L2/L4:L6=L5/L7:BOTTOM=L7 |
| SSD10_PWREN | 50OHM_Y12MIL | BUS | 5 | 6 | 5 | 10 | 5 | 14 | 6 | 15 | 12 | 12 | 12 | 12 |  | 50 Ohms-3 | TOP=L2:L3=L2/L4:L6=L5/L7:BOTTOM=L7 |
| SSD10_PWREN | 50OHM_Y12MIL | BUS | 6 | 6 | 5 | 10 | 5 | 14 | 6 | 15 | 12 | 12 | 12 | 12 |  | 50 Ohms-3 | TOP=L2:L3=L2/L4:L6=L5/L7:BOTTOM=L7 |
| SSD10_PWREN | 50OHM_Y12MIL | BUS | 7 | 6 | 5 | 10 | 5 | 14 | 6 | 15 | 12 | 12 | 12 | 12 |  | 50 Ohms-3 | TOP=L2:L3=L2/L4:L6=L5/L7:BOTTOM=L7 |
| SSD10_PWREN | 50OHM_Y12MIL | BUS | 8 | 6.75 | 5 | 10 | 5 | 14 | 6 | 15 | 12 | 12 | 12 | 12 |  | 50 Ohms-3 | TOP=L2:L3=L2/L4:L6=L5/L7:BOTTOM=L7 |
| SSD10_PWREN_R | 50OHM_Y12MIL | BUS | 1 | 6.75 | 5 | 10 | 5 | 14 | 6 | 15 | 12 | 12 | 12 | 12 |  | 50 Ohms-3 | TOP=L2:L3=L2/L4:L6=L5/L7:BOTTOM=L7 |
| SSD10_PWREN_R | 50OHM_Y12MIL | BUS | 2 | 6 | 5 | 10 | 5 | 14 | 6 | 15 | 12 | 12 | 12 | 12 |  | 50 Ohms-3 | TOP=L2:L3=L2/L4:L6=L5/L7:BOTTOM=L7 |
| SSD10_PWREN_R | 50OHM_Y12MIL | BUS | 3 | 6 | 5 | 10 | 5 | 14 | 6 | 15 | 12 | 12 | 12 | 12 |  | 50 Ohms-3 | TOP=L2:L3=L2/L4:L6=L5/L7:BOTTOM=L7 |
| SSD10_PWREN_R | 50OHM_Y12MIL | BUS | 4 | 6 | 5 | 10 | 5 | 14 | 6 | 15 | 12 | 12 | 12 | 12 |  | 50 Ohms-3 | TOP=L2:L3=L2/L4:L6=L5/L7:BOTTOM=L7 |
| SSD10_PWREN_R | 50OHM_Y12MIL | BUS | 5 | 6 | 5 | 10 | 5 | 14 | 6 | 15 | 12 | 12 | 12 | 12 |  | 50 Ohms-3 | TOP=L2:L3=L2/L4:L6=L5/L7:BOTTOM=L7 |
| SSD10_PWREN_R | 50OHM_Y12MIL | BUS | 6 | 6 | 5 | 10 | 5 | 14 | 6 | 15 | 12 | 12 | 12 | 12 |  | 50 Ohms-3 | TOP=L2:L3=L2/L4:L6=L5/L7:BOTTOM=L7 |
| SSD10_PWREN_R | 50OHM_Y12MIL | BUS | 7 | 6 | 5 | 10 | 5 | 14 | 6 | 15 | 12 | 12 | 12 | 12 |  | 50 Ohms-3 | TOP=L2:L3=L2/L4:L6=L5/L7:BOTTOM=L7 |
| SSD10_PWREN_R | 50OHM_Y12MIL | BUS | 8 | 6.75 | 5 | 10 | 5 | 14 | 6 | 15 | 12 | 12 | 12 | 12 |  | 50 Ohms-3 | TOP=L2:L3=L2/L4:L6=L5/L7:BOTTOM=L7 |
| SSD11_CLK0_OE_MOS_N | 50OHM_Y12MIL | BUS | 1 | 6.75 | 5 | 10 | 5 | 14 | 6 | 15 | 12 | 12 | 12 | 12 |  | 50 Ohms-3 | TOP=L2:L3=L2/L4:L6=L5/L7:BOTTOM=L7 |
| SSD11_CLK0_OE_MOS_N | 50OHM_Y12MIL | BUS | 2 | 6 | 5 | 10 | 5 | 14 | 6 | 15 | 12 | 12 | 12 | 12 |  | 50 Ohms-3 | TOP=L2:L3=L2/L4:L6=L5/L7:BOTTOM=L7 |
| SSD11_CLK0_OE_MOS_N | 50OHM_Y12MIL | BUS | 3 | 6 | 5 | 10 | 5 | 14 | 6 | 15 | 12 | 12 | 12 | 12 |  | 50 Ohms-3 | TOP=L2:L3=L2/L4:L6=L5/L7:BOTTOM=L7 |
| SSD11_CLK0_OE_MOS_N | 50OHM_Y12MIL | BUS | 4 | 6 | 5 | 10 | 5 | 14 | 6 | 15 | 12 | 12 | 12 | 12 |  | 50 Ohms-3 | TOP=L2:L3=L2/L4:L6=L5/L7:BOTTOM=L7 |
| SSD11_CLK0_OE_MOS_N | 50OHM_Y12MIL | BUS | 5 | 6 | 5 | 10 | 5 | 14 | 6 | 15 | 12 | 12 | 12 | 12 |  | 50 Ohms-3 | TOP=L2:L3=L2/L4:L6=L5/L7:BOTTOM=L7 |
| SSD11_CLK0_OE_MOS_N | 50OHM_Y12MIL | BUS | 6 | 6 | 5 | 10 | 5 | 14 | 6 | 15 | 12 | 12 | 12 | 12 |  | 50 Ohms-3 | TOP=L2:L3=L2/L4:L6=L5/L7:BOTTOM=L7 |
| SSD11_CLK0_OE_MOS_N | 50OHM_Y12MIL | BUS | 7 | 6 | 5 | 10 | 5 | 14 | 6 | 15 | 12 | 12 | 12 | 12 |  | 50 Ohms-3 | TOP=L2:L3=L2/L4:L6=L5/L7:BOTTOM=L7 |
| SSD11_CLK0_OE_MOS_N | 50OHM_Y12MIL | BUS | 8 | 6.75 | 5 | 10 | 5 | 14 | 6 | 15 | 12 | 12 | 12 | 12 |  | 50 Ohms-3 | TOP=L2:L3=L2/L4:L6=L5/L7:BOTTOM=L7 |
| SSD11_CLK0_OE_N | 50OHM_Y12MIL | BUS | 1 | 6.75 | 5 | 10 | 5 | 14 | 6 | 15 | 12 | 12 | 12 | 12 |  | 50 Ohms-3 | TOP=L2:L3=L2/L4:L6=L5/L7:BOTTOM=L7 |
| SSD11_CLK0_OE_N | 50OHM_Y12MIL | BUS | 2 | 6 | 5 | 10 | 5 | 14 | 6 | 15 | 12 | 12 | 12 | 12 |  | 50 Ohms-3 | TOP=L2:L3=L2/L4:L6=L5/L7:BOTTOM=L7 |
| SSD11_CLK0_OE_N | 50OHM_Y12MIL | BUS | 3 | 6 | 5 | 10 | 5 | 14 | 6 | 15 | 12 | 12 | 12 | 12 |  | 50 Ohms-3 | TOP=L2:L3=L2/L4:L6=L5/L7:BOTTOM=L7 |
| SSD11_CLK0_OE_N | 50OHM_Y12MIL | BUS | 4 | 6 | 5 | 10 | 5 | 14 | 6 | 15 | 12 | 12 | 12 | 12 |  | 50 Ohms-3 | TOP=L2:L3=L2/L4:L6=L5/L7:BOTTOM=L7 |
| SSD11_CLK0_OE_N | 50OHM_Y12MIL | BUS | 5 | 6 | 5 | 10 | 5 | 14 | 6 | 15 | 12 | 12 | 12 | 12 |  | 50 Ohms-3 | TOP=L2:L3=L2/L4:L6=L5/L7:BOTTOM=L7 |
| SSD11_CLK0_OE_N | 50OHM_Y12MIL | BUS | 6 | 6 | 5 | 10 | 5 | 14 | 6 | 15 | 12 | 12 | 12 | 12 |  | 50 Ohms-3 | TOP=L2:L3=L2/L4:L6=L5/L7:BOTTOM=L7 |
| SSD11_CLK0_OE_N | 50OHM_Y12MIL | BUS | 7 | 6 | 5 | 10 | 5 | 14 | 6 | 15 | 12 | 12 | 12 | 12 |  | 50 Ohms-3 | TOP=L2:L3=L2/L4:L6=L5/L7:BOTTOM=L7 |
| SSD11_CLK0_OE_N | 50OHM_Y12MIL | BUS | 8 | 6.75 | 5 | 10 | 5 | 14 | 6 | 15 | 12 | 12 | 12 | 12 |  | 50 Ohms-3 | TOP=L2:L3=L2/L4:L6=L5/L7:BOTTOM=L7 |
| SSD11_CLK0_OE_R_N | 50OHM_Y12MIL | BUS | 1 | 6.75 | 5 | 10 | 5 | 14 | 6 | 15 | 12 | 12 | 12 | 12 |  | 50 Ohms-3 | TOP=L2:L3=L2/L4:L6=L5/L7:BOTTOM=L7 |
| SSD11_CLK0_OE_R_N | 50OHM_Y12MIL | BUS | 2 | 6 | 5 | 10 | 5 | 14 | 6 | 15 | 12 | 12 | 12 | 12 |  | 50 Ohms-3 | TOP=L2:L3=L2/L4:L6=L5/L7:BOTTOM=L7 |
| SSD11_CLK0_OE_R_N | 50OHM_Y12MIL | BUS | 3 | 6 | 5 | 10 | 5 | 14 | 6 | 15 | 12 | 12 | 12 | 12 |  | 50 Ohms-3 | TOP=L2:L3=L2/L4:L6=L5/L7:BOTTOM=L7 |
| SSD11_CLK0_OE_R_N | 50OHM_Y12MIL | BUS | 4 | 6 | 5 | 10 | 5 | 14 | 6 | 15 | 12 | 12 | 12 | 12 |  | 50 Ohms-3 | TOP=L2:L3=L2/L4:L6=L5/L7:BOTTOM=L7 |
| SSD11_CLK0_OE_R_N | 50OHM_Y12MIL | BUS | 5 | 6 | 5 | 10 | 5 | 14 | 6 | 15 | 12 | 12 | 12 | 12 |  | 50 Ohms-3 | TOP=L2:L3=L2/L4:L6=L5/L7:BOTTOM=L7 |
| SSD11_CLK0_OE_R_N | 50OHM_Y12MIL | BUS | 6 | 6 | 5 | 10 | 5 | 14 | 6 | 15 | 12 | 12 | 12 | 12 |  | 50 Ohms-3 | TOP=L2:L3=L2/L4:L6=L5/L7:BOTTOM=L7 |
| SSD11_CLK0_OE_R_N | 50OHM_Y12MIL | BUS | 7 | 6 | 5 | 10 | 5 | 14 | 6 | 15 | 12 | 12 | 12 | 12 |  | 50 Ohms-3 | TOP=L2:L3=L2/L4:L6=L5/L7:BOTTOM=L7 |
| SSD11_CLK0_OE_R_N | 50OHM_Y12MIL | BUS | 8 | 6.75 | 5 | 10 | 5 | 14 | 6 | 15 | 12 | 12 | 12 | 12 |  | 50 Ohms-3 | TOP=L2:L3=L2/L4:L6=L5/L7:BOTTOM=L7 |
| SSD11_PERST_N | 50OHM_Y12MIL | BUS | 1 | 6.75 | 5 | 10 | 5 | 14 | 6 | 15 | 12 | 12 | 12 | 12 |  | 50 Ohms-3 | TOP=L2:L3=L2/L4:L6=L5/L7:BOTTOM=L7 |
| SSD11_PERST_N | 50OHM_Y12MIL | BUS | 2 | 6 | 5 | 10 | 5 | 14 | 6 | 15 | 12 | 12 | 12 | 12 |  | 50 Ohms-3 | TOP=L2:L3=L2/L4:L6=L5/L7:BOTTOM=L7 |
| SSD11_PERST_N | 50OHM_Y12MIL | BUS | 3 | 6 | 5 | 10 | 5 | 14 | 6 | 15 | 12 | 12 | 12 | 12 |  | 50 Ohms-3 | TOP=L2:L3=L2/L4:L6=L5/L7:BOTTOM=L7 |
| SSD11_PERST_N | 50OHM_Y12MIL | BUS | 4 | 6 | 5 | 10 | 5 | 14 | 6 | 15 | 12 | 12 | 12 | 12 |  | 50 Ohms-3 | TOP=L2:L3=L2/L4:L6=L5/L7:BOTTOM=L7 |
| SSD11_PERST_N | 50OHM_Y12MIL | BUS | 5 | 6 | 5 | 10 | 5 | 14 | 6 | 15 | 12 | 12 | 12 | 12 |  | 50 Ohms-3 | TOP=L2:L3=L2/L4:L6=L5/L7:BOTTOM=L7 |
| SSD11_PERST_N | 50OHM_Y12MIL | BUS | 6 | 6 | 5 | 10 | 5 | 14 | 6 | 15 | 12 | 12 | 12 | 12 |  | 50 Ohms-3 | TOP=L2:L3=L2/L4:L6=L5/L7:BOTTOM=L7 |
| SSD11_PERST_N | 50OHM_Y12MIL | BUS | 7 | 6 | 5 | 10 | 5 | 14 | 6 | 15 | 12 | 12 | 12 | 12 |  | 50 Ohms-3 | TOP=L2:L3=L2/L4:L6=L5/L7:BOTTOM=L7 |
| SSD11_PERST_N | 50OHM_Y12MIL | BUS | 8 | 6.75 | 5 | 10 | 5 | 14 | 6 | 15 | 12 | 12 | 12 | 12 |  | 50 Ohms-3 | TOP=L2:L3=L2/L4:L6=L5/L7:BOTTOM=L7 |
| SSD11_PWREN | 50OHM_Y12MIL | BUS | 1 | 6.75 | 5 | 10 | 5 | 14 | 6 | 15 | 12 | 12 | 12 | 12 |  | 50 Ohms-3 | TOP=L2:L3=L2/L4:L6=L5/L7:BOTTOM=L7 |
| SSD11_PWREN | 50OHM_Y12MIL | BUS | 2 | 6 | 5 | 10 | 5 | 14 | 6 | 15 | 12 | 12 | 12 | 12 |  | 50 Ohms-3 | TOP=L2:L3=L2/L4:L6=L5/L7:BOTTOM=L7 |
| SSD11_PWREN | 50OHM_Y12MIL | BUS | 3 | 6 | 5 | 10 | 5 | 14 | 6 | 15 | 12 | 12 | 12 | 12 |  | 50 Ohms-3 | TOP=L2:L3=L2/L4:L6=L5/L7:BOTTOM=L7 |
| SSD11_PWREN | 50OHM_Y12MIL | BUS | 4 | 6 | 5 | 10 | 5 | 14 | 6 | 15 | 12 | 12 | 12 | 12 |  | 50 Ohms-3 | TOP=L2:L3=L2/L4:L6=L5/L7:BOTTOM=L7 |
| SSD11_PWREN | 50OHM_Y12MIL | BUS | 5 | 6 | 5 | 10 | 5 | 14 | 6 | 15 | 12 | 12 | 12 | 12 |  | 50 Ohms-3 | TOP=L2:L3=L2/L4:L6=L5/L7:BOTTOM=L7 |
| SSD11_PWREN | 50OHM_Y12MIL | BUS | 6 | 6 | 5 | 10 | 5 | 14 | 6 | 15 | 12 | 12 | 12 | 12 |  | 50 Ohms-3 | TOP=L2:L3=L2/L4:L6=L5/L7:BOTTOM=L7 |
| SSD11_PWREN | 50OHM_Y12MIL | BUS | 7 | 6 | 5 | 10 | 5 | 14 | 6 | 15 | 12 | 12 | 12 | 12 |  | 50 Ohms-3 | TOP=L2:L3=L2/L4:L6=L5/L7:BOTTOM=L7 |
| SSD11_PWREN | 50OHM_Y12MIL | BUS | 8 | 6.75 | 5 | 10 | 5 | 14 | 6 | 15 | 12 | 12 | 12 | 12 |  | 50 Ohms-3 | TOP=L2:L3=L2/L4:L6=L5/L7:BOTTOM=L7 |
| SSD11_PWREN_R | 50OHM_Y12MIL | BUS | 1 | 6.75 | 5 | 10 | 5 | 14 | 6 | 15 | 12 | 12 | 12 | 12 |  | 50 Ohms-3 | TOP=L2:L3=L2/L4:L6=L5/L7:BOTTOM=L7 |
| SSD11_PWREN_R | 50OHM_Y12MIL | BUS | 2 | 6 | 5 | 10 | 5 | 14 | 6 | 15 | 12 | 12 | 12 | 12 |  | 50 Ohms-3 | TOP=L2:L3=L2/L4:L6=L5/L7:BOTTOM=L7 |
| SSD11_PWREN_R | 50OHM_Y12MIL | BUS | 3 | 6 | 5 | 10 | 5 | 14 | 6 | 15 | 12 | 12 | 12 | 12 |  | 50 Ohms-3 | TOP=L2:L3=L2/L4:L6=L5/L7:BOTTOM=L7 |
| SSD11_PWREN_R | 50OHM_Y12MIL | BUS | 4 | 6 | 5 | 10 | 5 | 14 | 6 | 15 | 12 | 12 | 12 | 12 |  | 50 Ohms-3 | TOP=L2:L3=L2/L4:L6=L5/L7:BOTTOM=L7 |
| SSD11_PWREN_R | 50OHM_Y12MIL | BUS | 5 | 6 | 5 | 10 | 5 | 14 | 6 | 15 | 12 | 12 | 12 | 12 |  | 50 Ohms-3 | TOP=L2:L3=L2/L4:L6=L5/L7:BOTTOM=L7 |
| SSD11_PWREN_R | 50OHM_Y12MIL | BUS | 6 | 6 | 5 | 10 | 5 | 14 | 6 | 15 | 12 | 12 | 12 | 12 |  | 50 Ohms-3 | TOP=L2:L3=L2/L4:L6=L5/L7:BOTTOM=L7 |
| SSD11_PWREN_R | 50OHM_Y12MIL | BUS | 7 | 6 | 5 | 10 | 5 | 14 | 6 | 15 | 12 | 12 | 12 | 12 |  | 50 Ohms-3 | TOP=L2:L3=L2/L4:L6=L5/L7:BOTTOM=L7 |
| SSD11_PWREN_R | 50OHM_Y12MIL | BUS | 8 | 6.75 | 5 | 10 | 5 | 14 | 6 | 15 | 12 | 12 | 12 | 12 |  | 50 Ohms-3 | TOP=L2:L3=L2/L4:L6=L5/L7:BOTTOM=L7 |
| SSD12_CLK0_OE_MOS_N | 50OHM_Y12MIL | BUS | 1 | 6.75 | 5 | 10 | 5 | 14 | 6 | 15 | 12 | 12 | 12 | 12 |  | 50 Ohms-3 | TOP=L2:L3=L2/L4:L6=L5/L7:BOTTOM=L7 |
| SSD12_CLK0_OE_MOS_N | 50OHM_Y12MIL | BUS | 2 | 6 | 5 | 10 | 5 | 14 | 6 | 15 | 12 | 12 | 12 | 12 |  | 50 Ohms-3 | TOP=L2:L3=L2/L4:L6=L5/L7:BOTTOM=L7 |
| SSD12_CLK0_OE_MOS_N | 50OHM_Y12MIL | BUS | 3 | 6 | 5 | 10 | 5 | 14 | 6 | 15 | 12 | 12 | 12 | 12 |  | 50 Ohms-3 | TOP=L2:L3=L2/L4:L6=L5/L7:BOTTOM=L7 |
| SSD12_CLK0_OE_MOS_N | 50OHM_Y12MIL | BUS | 4 | 6 | 5 | 10 | 5 | 14 | 6 | 15 | 12 | 12 | 12 | 12 |  | 50 Ohms-3 | TOP=L2:L3=L2/L4:L6=L5/L7:BOTTOM=L7 |
| SSD12_CLK0_OE_MOS_N | 50OHM_Y12MIL | BUS | 5 | 6 | 5 | 10 | 5 | 14 | 6 | 15 | 12 | 12 | 12 | 12 |  | 50 Ohms-3 | TOP=L2:L3=L2/L4:L6=L5/L7:BOTTOM=L7 |
| SSD12_CLK0_OE_MOS_N | 50OHM_Y12MIL | BUS | 6 | 6 | 5 | 10 | 5 | 14 | 6 | 15 | 12 | 12 | 12 | 12 |  | 50 Ohms-3 | TOP=L2:L3=L2/L4:L6=L5/L7:BOTTOM=L7 |
| SSD12_CLK0_OE_MOS_N | 50OHM_Y12MIL | BUS | 7 | 6 | 5 | 10 | 5 | 14 | 6 | 15 | 12 | 12 | 12 | 12 |  | 50 Ohms-3 | TOP=L2:L3=L2/L4:L6=L5/L7:BOTTOM=L7 |
| SSD12_CLK0_OE_MOS_N | 50OHM_Y12MIL | BUS | 8 | 6.75 | 5 | 10 | 5 | 14 | 6 | 15 | 12 | 12 | 12 | 12 |  | 50 Ohms-3 | TOP=L2:L3=L2/L4:L6=L5/L7:BOTTOM=L7 |
| SSD12_CLK0_OE_N | 50OHM_Y12MIL | BUS | 1 | 6.75 | 5 | 10 | 5 | 14 | 6 | 15 | 12 | 12 | 12 | 12 |  | 50 Ohms-3 | TOP=L2:L3=L2/L4:L6=L5/L7:BOTTOM=L7 |
| SSD12_CLK0_OE_N | 50OHM_Y12MIL | BUS | 2 | 6 | 5 | 10 | 5 | 14 | 6 | 15 | 12 | 12 | 12 | 12 |  | 50 Ohms-3 | TOP=L2:L3=L2/L4:L6=L5/L7:BOTTOM=L7 |
| SSD12_CLK0_OE_N | 50OHM_Y12MIL | BUS | 3 | 6 | 5 | 10 | 5 | 14 | 6 | 15 | 12 | 12 | 12 | 12 |  | 50 Ohms-3 | TOP=L2:L3=L2/L4:L6=L5/L7:BOTTOM=L7 |
| SSD12_CLK0_OE_N | 50OHM_Y12MIL | BUS | 4 | 6 | 5 | 10 | 5 | 14 | 6 | 15 | 12 | 12 | 12 | 12 |  | 50 Ohms-3 | TOP=L2:L3=L2/L4:L6=L5/L7:BOTTOM=L7 |
| SSD12_CLK0_OE_N | 50OHM_Y12MIL | BUS | 5 | 6 | 5 | 10 | 5 | 14 | 6 | 15 | 12 | 12 | 12 | 12 |  | 50 Ohms-3 | TOP=L2:L3=L2/L4:L6=L5/L7:BOTTOM=L7 |
| SSD12_CLK0_OE_N | 50OHM_Y12MIL | BUS | 6 | 6 | 5 | 10 | 5 | 14 | 6 | 15 | 12 | 12 | 12 | 12 |  | 50 Ohms-3 | TOP=L2:L3=L2/L4:L6=L5/L7:BOTTOM=L7 |
| SSD12_CLK0_OE_N | 50OHM_Y12MIL | BUS | 7 | 6 | 5 | 10 | 5 | 14 | 6 | 15 | 12 | 12 | 12 | 12 |  | 50 Ohms-3 | TOP=L2:L3=L2/L4:L6=L5/L7:BOTTOM=L7 |
| SSD12_CLK0_OE_N | 50OHM_Y12MIL | BUS | 8 | 6.75 | 5 | 10 | 5 | 14 | 6 | 15 | 12 | 12 | 12 | 12 |  | 50 Ohms-3 | TOP=L2:L3=L2/L4:L6=L5/L7:BOTTOM=L7 |
| SSD12_CLK0_OE_R_N | 50OHM_Y12MIL | BUS | 1 | 6.75 | 5 | 10 | 5 | 14 | 6 | 15 | 12 | 12 | 12 | 12 |  | 50 Ohms-3 | TOP=L2:L3=L2/L4:L6=L5/L7:BOTTOM=L7 |
| SSD12_CLK0_OE_R_N | 50OHM_Y12MIL | BUS | 2 | 6 | 5 | 10 | 5 | 14 | 6 | 15 | 12 | 12 | 12 | 12 |  | 50 Ohms-3 | TOP=L2:L3=L2/L4:L6=L5/L7:BOTTOM=L7 |
| SSD12_CLK0_OE_R_N | 50OHM_Y12MIL | BUS | 3 | 6 | 5 | 10 | 5 | 14 | 6 | 15 | 12 | 12 | 12 | 12 |  | 50 Ohms-3 | TOP=L2:L3=L2/L4:L6=L5/L7:BOTTOM=L7 |
| SSD12_CLK0_OE_R_N | 50OHM_Y12MIL | BUS | 4 | 6 | 5 | 10 | 5 | 14 | 6 | 15 | 12 | 12 | 12 | 12 |  | 50 Ohms-3 | TOP=L2:L3=L2/L4:L6=L5/L7:BOTTOM=L7 |
| SSD12_CLK0_OE_R_N | 50OHM_Y12MIL | BUS | 5 | 6 | 5 | 10 | 5 | 14 | 6 | 15 | 12 | 12 | 12 | 12 |  | 50 Ohms-3 | TOP=L2:L3=L2/L4:L6=L5/L7:BOTTOM=L7 |
| SSD12_CLK0_OE_R_N | 50OHM_Y12MIL | BUS | 6 | 6 | 5 | 10 | 5 | 14 | 6 | 15 | 12 | 12 | 12 | 12 |  | 50 Ohms-3 | TOP=L2:L3=L2/L4:L6=L5/L7:BOTTOM=L7 |
| SSD12_CLK0_OE_R_N | 50OHM_Y12MIL | BUS | 7 | 6 | 5 | 10 | 5 | 14 | 6 | 15 | 12 | 12 | 12 | 12 |  | 50 Ohms-3 | TOP=L2:L3=L2/L4:L6=L5/L7:BOTTOM=L7 |
| SSD12_CLK0_OE_R_N | 50OHM_Y12MIL | BUS | 8 | 6.75 | 5 | 10 | 5 | 14 | 6 | 15 | 12 | 12 | 12 | 12 |  | 50 Ohms-3 | TOP=L2:L3=L2/L4:L6=L5/L7:BOTTOM=L7 |
| SSD12_PERST_N | 50OHM_Y12MIL | BUS | 1 | 6.75 | 5 | 10 | 5 | 14 | 6 | 15 | 12 | 12 | 12 | 12 |  | 50 Ohms-3 | TOP=L2:L3=L2/L4:L6=L5/L7:BOTTOM=L7 |
| SSD12_PERST_N | 50OHM_Y12MIL | BUS | 2 | 6 | 5 | 10 | 5 | 14 | 6 | 15 | 12 | 12 | 12 | 12 |  | 50 Ohms-3 | TOP=L2:L3=L2/L4:L6=L5/L7:BOTTOM=L7 |
| SSD12_PERST_N | 50OHM_Y12MIL | BUS | 3 | 6 | 5 | 10 | 5 | 14 | 6 | 15 | 12 | 12 | 12 | 12 |  | 50 Ohms-3 | TOP=L2:L3=L2/L4:L6=L5/L7:BOTTOM=L7 |
| SSD12_PERST_N | 50OHM_Y12MIL | BUS | 4 | 6 | 5 | 10 | 5 | 14 | 6 | 15 | 12 | 12 | 12 | 12 |  | 50 Ohms-3 | TOP=L2:L3=L2/L4:L6=L5/L7:BOTTOM=L7 |
| SSD12_PERST_N | 50OHM_Y12MIL | BUS | 5 | 6 | 5 | 10 | 5 | 14 | 6 | 15 | 12 | 12 | 12 | 12 |  | 50 Ohms-3 | TOP=L2:L3=L2/L4:L6=L5/L7:BOTTOM=L7 |
| SSD12_PERST_N | 50OHM_Y12MIL | BUS | 6 | 6 | 5 | 10 | 5 | 14 | 6 | 15 | 12 | 12 | 12 | 12 |  | 50 Ohms-3 | TOP=L2:L3=L2/L4:L6=L5/L7:BOTTOM=L7 |
| SSD12_PERST_N | 50OHM_Y12MIL | BUS | 7 | 6 | 5 | 10 | 5 | 14 | 6 | 15 | 12 | 12 | 12 | 12 |  | 50 Ohms-3 | TOP=L2:L3=L2/L4:L6=L5/L7:BOTTOM=L7 |
| SSD12_PERST_N | 50OHM_Y12MIL | BUS | 8 | 6.75 | 5 | 10 | 5 | 14 | 6 | 15 | 12 | 12 | 12 | 12 |  | 50 Ohms-3 | TOP=L2:L3=L2/L4:L6=L5/L7:BOTTOM=L7 |
| SSD12_PWREN | 50OHM_Y12MIL | BUS | 1 | 6.75 | 5 | 10 | 5 | 14 | 6 | 15 | 12 | 12 | 12 | 12 |  | 50 Ohms-3 | TOP=L2:L3=L2/L4:L6=L5/L7:BOTTOM=L7 |
| SSD12_PWREN | 50OHM_Y12MIL | BUS | 2 | 6 | 5 | 10 | 5 | 14 | 6 | 15 | 12 | 12 | 12 | 12 |  | 50 Ohms-3 | TOP=L2:L3=L2/L4:L6=L5/L7:BOTTOM=L7 |
| SSD12_PWREN | 50OHM_Y12MIL | BUS | 3 | 6 | 5 | 10 | 5 | 14 | 6 | 15 | 12 | 12 | 12 | 12 |  | 50 Ohms-3 | TOP=L2:L3=L2/L4:L6=L5/L7:BOTTOM=L7 |
| SSD12_PWREN | 50OHM_Y12MIL | BUS | 4 | 6 | 5 | 10 | 5 | 14 | 6 | 15 | 12 | 12 | 12 | 12 |  | 50 Ohms-3 | TOP=L2:L3=L2/L4:L6=L5/L7:BOTTOM=L7 |
| SSD12_PWREN | 50OHM_Y12MIL | BUS | 5 | 6 | 5 | 10 | 5 | 14 | 6 | 15 | 12 | 12 | 12 | 12 |  | 50 Ohms-3 | TOP=L2:L3=L2/L4:L6=L5/L7:BOTTOM=L7 |
| SSD12_PWREN | 50OHM_Y12MIL | BUS | 6 | 6 | 5 | 10 | 5 | 14 | 6 | 15 | 12 | 12 | 12 | 12 |  | 50 Ohms-3 | TOP=L2:L3=L2/L4:L6=L5/L7:BOTTOM=L7 |
| SSD12_PWREN | 50OHM_Y12MIL | BUS | 7 | 6 | 5 | 10 | 5 | 14 | 6 | 15 | 12 | 12 | 12 | 12 |  | 50 Ohms-3 | TOP=L2:L3=L2/L4:L6=L5/L7:BOTTOM=L7 |
| SSD12_PWREN | 50OHM_Y12MIL | BUS | 8 | 6.75 | 5 | 10 | 5 | 14 | 6 | 15 | 12 | 12 | 12 | 12 |  | 50 Ohms-3 | TOP=L2:L3=L2/L4:L6=L5/L7:BOTTOM=L7 |
| SSD12_PWREN_R | 50OHM_Y12MIL | BUS | 1 | 6.75 | 5 | 10 | 5 | 14 | 6 | 15 | 12 | 12 | 12 | 12 |  | 50 Ohms-3 | TOP=L2:L3=L2/L4:L6=L5/L7:BOTTOM=L7 |
| SSD12_PWREN_R | 50OHM_Y12MIL | BUS | 2 | 6 | 5 | 10 | 5 | 14 | 6 | 15 | 12 | 12 | 12 | 12 |  | 50 Ohms-3 | TOP=L2:L3=L2/L4:L6=L5/L7:BOTTOM=L7 |
| SSD12_PWREN_R | 50OHM_Y12MIL | BUS | 3 | 6 | 5 | 10 | 5 | 14 | 6 | 15 | 12 | 12 | 12 | 12 |  | 50 Ohms-3 | TOP=L2:L3=L2/L4:L6=L5/L7:BOTTOM=L7 |
| SSD12_PWREN_R | 50OHM_Y12MIL | BUS | 4 | 6 | 5 | 10 | 5 | 14 | 6 | 15 | 12 | 12 | 12 | 12 |  | 50 Ohms-3 | TOP=L2:L3=L2/L4:L6=L5/L7:BOTTOM=L7 |
| SSD12_PWREN_R | 50OHM_Y12MIL | BUS | 5 | 6 | 5 | 10 | 5 | 14 | 6 | 15 | 12 | 12 | 12 | 12 |  | 50 Ohms-3 | TOP=L2:L3=L2/L4:L6=L5/L7:BOTTOM=L7 |
| SSD12_PWREN_R | 50OHM_Y12MIL | BUS | 6 | 6 | 5 | 10 | 5 | 14 | 6 | 15 | 12 | 12 | 12 | 12 |  | 50 Ohms-3 | TOP=L2:L3=L2/L4:L6=L5/L7:BOTTOM=L7 |
| SSD12_PWREN_R | 50OHM_Y12MIL | BUS | 7 | 6 | 5 | 10 | 5 | 14 | 6 | 15 | 12 | 12 | 12 | 12 |  | 50 Ohms-3 | TOP=L2:L3=L2/L4:L6=L5/L7:BOTTOM=L7 |
| SSD12_PWREN_R | 50OHM_Y12MIL | BUS | 8 | 6.75 | 5 | 10 | 5 | 14 | 6 | 15 | 12 | 12 | 12 | 12 |  | 50 Ohms-3 | TOP=L2:L3=L2/L4:L6=L5/L7:BOTTOM=L7 |
| SSD13_CLK0_OE_MOS_N | 50OHM_Y12MIL | BUS | 1 | 6.75 | 5 | 10 | 5 | 14 | 6 | 15 | 12 | 12 | 12 | 12 |  | 50 Ohms-3 | TOP=L2:L3=L2/L4:L6=L5/L7:BOTTOM=L7 |
| SSD13_CLK0_OE_MOS_N | 50OHM_Y12MIL | BUS | 2 | 6 | 5 | 10 | 5 | 14 | 6 | 15 | 12 | 12 | 12 | 12 |  | 50 Ohms-3 | TOP=L2:L3=L2/L4:L6=L5/L7:BOTTOM=L7 |
| SSD13_CLK0_OE_MOS_N | 50OHM_Y12MIL | BUS | 3 | 6 | 5 | 10 | 5 | 14 | 6 | 15 | 12 | 12 | 12 | 12 |  | 50 Ohms-3 | TOP=L2:L3=L2/L4:L6=L5/L7:BOTTOM=L7 |
| SSD13_CLK0_OE_MOS_N | 50OHM_Y12MIL | BUS | 4 | 6 | 5 | 10 | 5 | 14 | 6 | 15 | 12 | 12 | 12 | 12 |  | 50 Ohms-3 | TOP=L2:L3=L2/L4:L6=L5/L7:BOTTOM=L7 |
| SSD13_CLK0_OE_MOS_N | 50OHM_Y12MIL | BUS | 5 | 6 | 5 | 10 | 5 | 14 | 6 | 15 | 12 | 12 | 12 | 12 |  | 50 Ohms-3 | TOP=L2:L3=L2/L4:L6=L5/L7:BOTTOM=L7 |
| SSD13_CLK0_OE_MOS_N | 50OHM_Y12MIL | BUS | 6 | 6 | 5 | 10 | 5 | 14 | 6 | 15 | 12 | 12 | 12 | 12 |  | 50 Ohms-3 | TOP=L2:L3=L2/L4:L6=L5/L7:BOTTOM=L7 |
| SSD13_CLK0_OE_MOS_N | 50OHM_Y12MIL | BUS | 7 | 6 | 5 | 10 | 5 | 14 | 6 | 15 | 12 | 12 | 12 | 12 |  | 50 Ohms-3 | TOP=L2:L3=L2/L4:L6=L5/L7:BOTTOM=L7 |
| SSD13_CLK0_OE_MOS_N | 50OHM_Y12MIL | BUS | 8 | 6.75 | 5 | 10 | 5 | 14 | 6 | 15 | 12 | 12 | 12 | 12 |  | 50 Ohms-3 | TOP=L2:L3=L2/L4:L6=L5/L7:BOTTOM=L7 |
| SSD13_CLK0_OE_N | 50OHM_Y12MIL | BUS | 1 | 6.75 | 5 | 10 | 5 | 14 | 6 | 15 | 12 | 12 | 12 | 12 |  | 50 Ohms-3 | TOP=L2:L3=L2/L4:L6=L5/L7:BOTTOM=L7 |
| SSD13_CLK0_OE_N | 50OHM_Y12MIL | BUS | 2 | 6 | 5 | 10 | 5 | 14 | 6 | 15 | 12 | 12 | 12 | 12 |  | 50 Ohms-3 | TOP=L2:L3=L2/L4:L6=L5/L7:BOTTOM=L7 |
| SSD13_CLK0_OE_N | 50OHM_Y12MIL | BUS | 3 | 6 | 5 | 10 | 5 | 14 | 6 | 15 | 12 | 12 | 12 | 12 |  | 50 Ohms-3 | TOP=L2:L3=L2/L4:L6=L5/L7:BOTTOM=L7 |
| SSD13_CLK0_OE_N | 50OHM_Y12MIL | BUS | 4 | 6 | 5 | 10 | 5 | 14 | 6 | 15 | 12 | 12 | 12 | 12 |  | 50 Ohms-3 | TOP=L2:L3=L2/L4:L6=L5/L7:BOTTOM=L7 |
| SSD13_CLK0_OE_N | 50OHM_Y12MIL | BUS | 5 | 6 | 5 | 10 | 5 | 14 | 6 | 15 | 12 | 12 | 12 | 12 |  | 50 Ohms-3 | TOP=L2:L3=L2/L4:L6=L5/L7:BOTTOM=L7 |
| SSD13_CLK0_OE_N | 50OHM_Y12MIL | BUS | 6 | 6 | 5 | 10 | 5 | 14 | 6 | 15 | 12 | 12 | 12 | 12 |  | 50 Ohms-3 | TOP=L2:L3=L2/L4:L6=L5/L7:BOTTOM=L7 |
| SSD13_CLK0_OE_N | 50OHM_Y12MIL | BUS | 7 | 6 | 5 | 10 | 5 | 14 | 6 | 15 | 12 | 12 | 12 | 12 |  | 50 Ohms-3 | TOP=L2:L3=L2/L4:L6=L5/L7:BOTTOM=L7 |
| SSD13_CLK0_OE_N | 50OHM_Y12MIL | BUS | 8 | 6.75 | 5 | 10 | 5 | 14 | 6 | 15 | 12 | 12 | 12 | 12 |  | 50 Ohms-3 | TOP=L2:L3=L2/L4:L6=L5/L7:BOTTOM=L7 |
| SSD13_CLK0_OE_R_N | 50OHM_Y12MIL | BUS | 1 | 6.75 | 5 | 10 | 5 | 14 | 6 | 15 | 12 | 12 | 12 | 12 |  | 50 Ohms-3 | TOP=L2:L3=L2/L4:L6=L5/L7:BOTTOM=L7 |
| SSD13_CLK0_OE_R_N | 50OHM_Y12MIL | BUS | 2 | 6 | 5 | 10 | 5 | 14 | 6 | 15 | 12 | 12 | 12 | 12 |  | 50 Ohms-3 | TOP=L2:L3=L2/L4:L6=L5/L7:BOTTOM=L7 |
| SSD13_CLK0_OE_R_N | 50OHM_Y12MIL | BUS | 3 | 6 | 5 | 10 | 5 | 14 | 6 | 15 | 12 | 12 | 12 | 12 |  | 50 Ohms-3 | TOP=L2:L3=L2/L4:L6=L5/L7:BOTTOM=L7 |
| SSD13_CLK0_OE_R_N | 50OHM_Y12MIL | BUS | 4 | 6 | 5 | 10 | 5 | 14 | 6 | 15 | 12 | 12 | 12 | 12 |  | 50 Ohms-3 | TOP=L2:L3=L2/L4:L6=L5/L7:BOTTOM=L7 |
| SSD13_CLK0_OE_R_N | 50OHM_Y12MIL | BUS | 5 | 6 | 5 | 10 | 5 | 14 | 6 | 15 | 12 | 12 | 12 | 12 |  | 50 Ohms-3 | TOP=L2:L3=L2/L4:L6=L5/L7:BOTTOM=L7 |
| SSD13_CLK0_OE_R_N | 50OHM_Y12MIL | BUS | 6 | 6 | 5 | 10 | 5 | 14 | 6 | 15 | 12 | 12 | 12 | 12 |  | 50 Ohms-3 | TOP=L2:L3=L2/L4:L6=L5/L7:BOTTOM=L7 |
| SSD13_CLK0_OE_R_N | 50OHM_Y12MIL | BUS | 7 | 6 | 5 | 10 | 5 | 14 | 6 | 15 | 12 | 12 | 12 | 12 |  | 50 Ohms-3 | TOP=L2:L3=L2/L4:L6=L5/L7:BOTTOM=L7 |
| SSD13_CLK0_OE_R_N | 50OHM_Y12MIL | BUS | 8 | 6.75 | 5 | 10 | 5 | 14 | 6 | 15 | 12 | 12 | 12 | 12 |  | 50 Ohms-3 | TOP=L2:L3=L2/L4:L6=L5/L7:BOTTOM=L7 |
| SSD13_PERST_N | 50OHM_Y12MIL | BUS | 1 | 6.75 | 5 | 10 | 5 | 14 | 6 | 15 | 12 | 12 | 12 | 12 |  | 50 Ohms-3 | TOP=L2:L3=L2/L4:L6=L5/L7:BOTTOM=L7 |
| SSD13_PERST_N | 50OHM_Y12MIL | BUS | 2 | 6 | 5 | 10 | 5 | 14 | 6 | 15 | 12 | 12 | 12 | 12 |  | 50 Ohms-3 | TOP=L2:L3=L2/L4:L6=L5/L7:BOTTOM=L7 |
| SSD13_PERST_N | 50OHM_Y12MIL | BUS | 3 | 6 | 5 | 10 | 5 | 14 | 6 | 15 | 12 | 12 | 12 | 12 |  | 50 Ohms-3 | TOP=L2:L3=L2/L4:L6=L5/L7:BOTTOM=L7 |
| SSD13_PERST_N | 50OHM_Y12MIL | BUS | 4 | 6 | 5 | 10 | 5 | 14 | 6 | 15 | 12 | 12 | 12 | 12 |  | 50 Ohms-3 | TOP=L2:L3=L2/L4:L6=L5/L7:BOTTOM=L7 |
| SSD13_PERST_N | 50OHM_Y12MIL | BUS | 5 | 6 | 5 | 10 | 5 | 14 | 6 | 15 | 12 | 12 | 12 | 12 |  | 50 Ohms-3 | TOP=L2:L3=L2/L4:L6=L5/L7:BOTTOM=L7 |
| SSD13_PERST_N | 50OHM_Y12MIL | BUS | 6 | 6 | 5 | 10 | 5 | 14 | 6 | 15 | 12 | 12 | 12 | 12 |  | 50 Ohms-3 | TOP=L2:L3=L2/L4:L6=L5/L7:BOTTOM=L7 |
| SSD13_PERST_N | 50OHM_Y12MIL | BUS | 7 | 6 | 5 | 10 | 5 | 14 | 6 | 15 | 12 | 12 | 12 | 12 |  | 50 Ohms-3 | TOP=L2:L3=L2/L4:L6=L5/L7:BOTTOM=L7 |
| SSD13_PERST_N | 50OHM_Y12MIL | BUS | 8 | 6.75 | 5 | 10 | 5 | 14 | 6 | 15 | 12 | 12 | 12 | 12 |  | 50 Ohms-3 | TOP=L2:L3=L2/L4:L6=L5/L7:BOTTOM=L7 |
| SSD13_PWREN | 50OHM_Y12MIL | BUS | 1 | 6.75 | 5 | 10 | 5 | 14 | 6 | 15 | 12 | 12 | 12 | 12 |  | 50 Ohms-3 | TOP=L2:L3=L2/L4:L6=L5/L7:BOTTOM=L7 |
| SSD13_PWREN | 50OHM_Y12MIL | BUS | 2 | 6 | 5 | 10 | 5 | 14 | 6 | 15 | 12 | 12 | 12 | 12 |  | 50 Ohms-3 | TOP=L2:L3=L2/L4:L6=L5/L7:BOTTOM=L7 |
| SSD13_PWREN | 50OHM_Y12MIL | BUS | 3 | 6 | 5 | 10 | 5 | 14 | 6 | 15 | 12 | 12 | 12 | 12 |  | 50 Ohms-3 | TOP=L2:L3=L2/L4:L6=L5/L7:BOTTOM=L7 |
| SSD13_PWREN | 50OHM_Y12MIL | BUS | 4 | 6 | 5 | 10 | 5 | 14 | 6 | 15 | 12 | 12 | 12 | 12 |  | 50 Ohms-3 | TOP=L2:L3=L2/L4:L6=L5/L7:BOTTOM=L7 |
| SSD13_PWREN | 50OHM_Y12MIL | BUS | 5 | 6 | 5 | 10 | 5 | 14 | 6 | 15 | 12 | 12 | 12 | 12 |  | 50 Ohms-3 | TOP=L2:L3=L2/L4:L6=L5/L7:BOTTOM=L7 |
| SSD13_PWREN | 50OHM_Y12MIL | BUS | 6 | 6 | 5 | 10 | 5 | 14 | 6 | 15 | 12 | 12 | 12 | 12 |  | 50 Ohms-3 | TOP=L2:L3=L2/L4:L6=L5/L7:BOTTOM=L7 |
| SSD13_PWREN | 50OHM_Y12MIL | BUS | 7 | 6 | 5 | 10 | 5 | 14 | 6 | 15 | 12 | 12 | 12 | 12 |  | 50 Ohms-3 | TOP=L2:L3=L2/L4:L6=L5/L7:BOTTOM=L7 |
| SSD13_PWREN | 50OHM_Y12MIL | BUS | 8 | 6.75 | 5 | 10 | 5 | 14 | 6 | 15 | 12 | 12 | 12 | 12 |  | 50 Ohms-3 | TOP=L2:L3=L2/L4:L6=L5/L7:BOTTOM=L7 |
| SSD13_PWREN_R | 50OHM_Y12MIL | BUS | 1 | 6.75 | 5 | 10 | 5 | 14 | 6 | 15 | 12 | 12 | 12 | 12 |  | 50 Ohms-3 | TOP=L2:L3=L2/L4:L6=L5/L7:BOTTOM=L7 |
| SSD13_PWREN_R | 50OHM_Y12MIL | BUS | 2 | 6 | 5 | 10 | 5 | 14 | 6 | 15 | 12 | 12 | 12 | 12 |  | 50 Ohms-3 | TOP=L2:L3=L2/L4:L6=L5/L7:BOTTOM=L7 |
| SSD13_PWREN_R | 50OHM_Y12MIL | BUS | 3 | 6 | 5 | 10 | 5 | 14 | 6 | 15 | 12 | 12 | 12 | 12 |  | 50 Ohms-3 | TOP=L2:L3=L2/L4:L6=L5/L7:BOTTOM=L7 |
| SSD13_PWREN_R | 50OHM_Y12MIL | BUS | 4 | 6 | 5 | 10 | 5 | 14 | 6 | 15 | 12 | 12 | 12 | 12 |  | 50 Ohms-3 | TOP=L2:L3=L2/L4:L6=L5/L7:BOTTOM=L7 |
| SSD13_PWREN_R | 50OHM_Y12MIL | BUS | 5 | 6 | 5 | 10 | 5 | 14 | 6 | 15 | 12 | 12 | 12 | 12 |  | 50 Ohms-3 | TOP=L2:L3=L2/L4:L6=L5/L7:BOTTOM=L7 |
| SSD13_PWREN_R | 50OHM_Y12MIL | BUS | 6 | 6 | 5 | 10 | 5 | 14 | 6 | 15 | 12 | 12 | 12 | 12 |  | 50 Ohms-3 | TOP=L2:L3=L2/L4:L6=L5/L7:BOTTOM=L7 |
| SSD13_PWREN_R | 50OHM_Y12MIL | BUS | 7 | 6 | 5 | 10 | 5 | 14 | 6 | 15 | 12 | 12 | 12 | 12 |  | 50 Ohms-3 | TOP=L2:L3=L2/L4:L6=L5/L7:BOTTOM=L7 |
| SSD13_PWREN_R | 50OHM_Y12MIL | BUS | 8 | 6.75 | 5 | 10 | 5 | 14 | 6 | 15 | 12 | 12 | 12 | 12 |  | 50 Ohms-3 | TOP=L2:L3=L2/L4:L6=L5/L7:BOTTOM=L7 |
| SSD14_CLK0_OE_MOS_N | 50OHM_Y12MIL | BUS | 1 | 6.75 | 5 | 10 | 5 | 14 | 6 | 15 | 12 | 12 | 12 | 12 |  | 50 Ohms-3 | TOP=L2:L3=L2/L4:L6=L5/L7:BOTTOM=L7 |
| SSD14_CLK0_OE_MOS_N | 50OHM_Y12MIL | BUS | 2 | 6 | 5 | 10 | 5 | 14 | 6 | 15 | 12 | 12 | 12 | 12 |  | 50 Ohms-3 | TOP=L2:L3=L2/L4:L6=L5/L7:BOTTOM=L7 |
| SSD14_CLK0_OE_MOS_N | 50OHM_Y12MIL | BUS | 3 | 6 | 5 | 10 | 5 | 14 | 6 | 15 | 12 | 12 | 12 | 12 |  | 50 Ohms-3 | TOP=L2:L3=L2/L4:L6=L5/L7:BOTTOM=L7 |
| SSD14_CLK0_OE_MOS_N | 50OHM_Y12MIL | BUS | 4 | 6 | 5 | 10 | 5 | 14 | 6 | 15 | 12 | 12 | 12 | 12 |  | 50 Ohms-3 | TOP=L2:L3=L2/L4:L6=L5/L7:BOTTOM=L7 |
| SSD14_CLK0_OE_MOS_N | 50OHM_Y12MIL | BUS | 5 | 6 | 5 | 10 | 5 | 14 | 6 | 15 | 12 | 12 | 12 | 12 |  | 50 Ohms-3 | TOP=L2:L3=L2/L4:L6=L5/L7:BOTTOM=L7 |
| SSD14_CLK0_OE_MOS_N | 50OHM_Y12MIL | BUS | 6 | 6 | 5 | 10 | 5 | 14 | 6 | 15 | 12 | 12 | 12 | 12 |  | 50 Ohms-3 | TOP=L2:L3=L2/L4:L6=L5/L7:BOTTOM=L7 |
| SSD14_CLK0_OE_MOS_N | 50OHM_Y12MIL | BUS | 7 | 6 | 5 | 10 | 5 | 14 | 6 | 15 | 12 | 12 | 12 | 12 |  | 50 Ohms-3 | TOP=L2:L3=L2/L4:L6=L5/L7:BOTTOM=L7 |
| SSD14_CLK0_OE_MOS_N | 50OHM_Y12MIL | BUS | 8 | 6.75 | 5 | 10 | 5 | 14 | 6 | 15 | 12 | 12 | 12 | 12 |  | 50 Ohms-3 | TOP=L2:L3=L2/L4:L6=L5/L7:BOTTOM=L7 |
| SSD14_CLK0_OE_N | 50OHM_Y12MIL | BUS | 1 | 6.75 | 5 | 10 | 5 | 14 | 6 | 15 | 12 | 12 | 12 | 12 |  | 50 Ohms-3 | TOP=L2:L3=L2/L4:L6=L5/L7:BOTTOM=L7 |
| SSD14_CLK0_OE_N | 50OHM_Y12MIL | BUS | 2 | 6 | 5 | 10 | 5 | 14 | 6 | 15 | 12 | 12 | 12 | 12 |  | 50 Ohms-3 | TOP=L2:L3=L2/L4:L6=L5/L7:BOTTOM=L7 |
| SSD14_CLK0_OE_N | 50OHM_Y12MIL | BUS | 3 | 6 | 5 | 10 | 5 | 14 | 6 | 15 | 12 | 12 | 12 | 12 |  | 50 Ohms-3 | TOP=L2:L3=L2/L4:L6=L5/L7:BOTTOM=L7 |
| SSD14_CLK0_OE_N | 50OHM_Y12MIL | BUS | 4 | 6 | 5 | 10 | 5 | 14 | 6 | 15 | 12 | 12 | 12 | 12 |  | 50 Ohms-3 | TOP=L2:L3=L2/L4:L6=L5/L7:BOTTOM=L7 |
| SSD14_CLK0_OE_N | 50OHM_Y12MIL | BUS | 5 | 6 | 5 | 10 | 5 | 14 | 6 | 15 | 12 | 12 | 12 | 12 |  | 50 Ohms-3 | TOP=L2:L3=L2/L4:L6=L5/L7:BOTTOM=L7 |
| SSD14_CLK0_OE_N | 50OHM_Y12MIL | BUS | 6 | 6 | 5 | 10 | 5 | 14 | 6 | 15 | 12 | 12 | 12 | 12 |  | 50 Ohms-3 | TOP=L2:L3=L2/L4:L6=L5/L7:BOTTOM=L7 |
| SSD14_CLK0_OE_N | 50OHM_Y12MIL | BUS | 7 | 6 | 5 | 10 | 5 | 14 | 6 | 15 | 12 | 12 | 12 | 12 |  | 50 Ohms-3 | TOP=L2:L3=L2/L4:L6=L5/L7:BOTTOM=L7 |
| SSD14_CLK0_OE_N | 50OHM_Y12MIL | BUS | 8 | 6.75 | 5 | 10 | 5 | 14 | 6 | 15 | 12 | 12 | 12 | 12 |  | 50 Ohms-3 | TOP=L2:L3=L2/L4:L6=L5/L7:BOTTOM=L7 |
| SSD14_CLK0_OE_R_N | 50OHM_Y12MIL | BUS | 1 | 6.75 | 5 | 10 | 5 | 14 | 6 | 15 | 12 | 12 | 12 | 12 |  | 50 Ohms-3 | TOP=L2:L3=L2/L4:L6=L5/L7:BOTTOM=L7 |
| SSD14_CLK0_OE_R_N | 50OHM_Y12MIL | BUS | 2 | 6 | 5 | 10 | 5 | 14 | 6 | 15 | 12 | 12 | 12 | 12 |  | 50 Ohms-3 | TOP=L2:L3=L2/L4:L6=L5/L7:BOTTOM=L7 |
| SSD14_CLK0_OE_R_N | 50OHM_Y12MIL | BUS | 3 | 6 | 5 | 10 | 5 | 14 | 6 | 15 | 12 | 12 | 12 | 12 |  | 50 Ohms-3 | TOP=L2:L3=L2/L4:L6=L5/L7:BOTTOM=L7 |
| SSD14_CLK0_OE_R_N | 50OHM_Y12MIL | BUS | 4 | 6 | 5 | 10 | 5 | 14 | 6 | 15 | 12 | 12 | 12 | 12 |  | 50 Ohms-3 | TOP=L2:L3=L2/L4:L6=L5/L7:BOTTOM=L7 |
| SSD14_CLK0_OE_R_N | 50OHM_Y12MIL | BUS | 5 | 6 | 5 | 10 | 5 | 14 | 6 | 15 | 12 | 12 | 12 | 12 |  | 50 Ohms-3 | TOP=L2:L3=L2/L4:L6=L5/L7:BOTTOM=L7 |
| SSD14_CLK0_OE_R_N | 50OHM_Y12MIL | BUS | 6 | 6 | 5 | 10 | 5 | 14 | 6 | 15 | 12 | 12 | 12 | 12 |  | 50 Ohms-3 | TOP=L2:L3=L2/L4:L6=L5/L7:BOTTOM=L7 |
| SSD14_CLK0_OE_R_N | 50OHM_Y12MIL | BUS | 7 | 6 | 5 | 10 | 5 | 14 | 6 | 15 | 12 | 12 | 12 | 12 |  | 50 Ohms-3 | TOP=L2:L3=L2/L4:L6=L5/L7:BOTTOM=L7 |
| SSD14_CLK0_OE_R_N | 50OHM_Y12MIL | BUS | 8 | 6.75 | 5 | 10 | 5 | 14 | 6 | 15 | 12 | 12 | 12 | 12 |  | 50 Ohms-3 | TOP=L2:L3=L2/L4:L6=L5/L7:BOTTOM=L7 |
| SSD14_PERST_N | 50OHM_Y12MIL | BUS | 1 | 6.75 | 5 | 10 | 5 | 14 | 6 | 15 | 12 | 12 | 12 | 12 |  | 50 Ohms-3 | TOP=L2:L3=L2/L4:L6=L5/L7:BOTTOM=L7 |
| SSD14_PERST_N | 50OHM_Y12MIL | BUS | 2 | 6 | 5 | 10 | 5 | 14 | 6 | 15 | 12 | 12 | 12 | 12 |  | 50 Ohms-3 | TOP=L2:L3=L2/L4:L6=L5/L7:BOTTOM=L7 |
| SSD14_PERST_N | 50OHM_Y12MIL | BUS | 3 | 6 | 5 | 10 | 5 | 14 | 6 | 15 | 12 | 12 | 12 | 12 |  | 50 Ohms-3 | TOP=L2:L3=L2/L4:L6=L5/L7:BOTTOM=L7 |
| SSD14_PERST_N | 50OHM_Y12MIL | BUS | 4 | 6 | 5 | 10 | 5 | 14 | 6 | 15 | 12 | 12 | 12 | 12 |  | 50 Ohms-3 | TOP=L2:L3=L2/L4:L6=L5/L7:BOTTOM=L7 |
| SSD14_PERST_N | 50OHM_Y12MIL | BUS | 5 | 6 | 5 | 10 | 5 | 14 | 6 | 15 | 12 | 12 | 12 | 12 |  | 50 Ohms-3 | TOP=L2:L3=L2/L4:L6=L5/L7:BOTTOM=L7 |
| SSD14_PERST_N | 50OHM_Y12MIL | BUS | 6 | 6 | 5 | 10 | 5 | 14 | 6 | 15 | 12 | 12 | 12 | 12 |  | 50 Ohms-3 | TOP=L2:L3=L2/L4:L6=L5/L7:BOTTOM=L7 |
| SSD14_PERST_N | 50OHM_Y12MIL | BUS | 7 | 6 | 5 | 10 | 5 | 14 | 6 | 15 | 12 | 12 | 12 | 12 |  | 50 Ohms-3 | TOP=L2:L3=L2/L4:L6=L5/L7:BOTTOM=L7 |
| SSD14_PERST_N | 50OHM_Y12MIL | BUS | 8 | 6.75 | 5 | 10 | 5 | 14 | 6 | 15 | 12 | 12 | 12 | 12 |  | 50 Ohms-3 | TOP=L2:L3=L2/L4:L6=L5/L7:BOTTOM=L7 |
| SSD14_PWREN | 50OHM_Y12MIL | BUS | 1 | 6.75 | 5 | 10 | 5 | 14 | 6 | 15 | 12 | 12 | 12 | 12 |  | 50 Ohms-3 | TOP=L2:L3=L2/L4:L6=L5/L7:BOTTOM=L7 |
| SSD14_PWREN | 50OHM_Y12MIL | BUS | 2 | 6 | 5 | 10 | 5 | 14 | 6 | 15 | 12 | 12 | 12 | 12 |  | 50 Ohms-3 | TOP=L2:L3=L2/L4:L6=L5/L7:BOTTOM=L7 |
| SSD14_PWREN | 50OHM_Y12MIL | BUS | 3 | 6 | 5 | 10 | 5 | 14 | 6 | 15 | 12 | 12 | 12 | 12 |  | 50 Ohms-3 | TOP=L2:L3=L2/L4:L6=L5/L7:BOTTOM=L7 |
| SSD14_PWREN | 50OHM_Y12MIL | BUS | 4 | 6 | 5 | 10 | 5 | 14 | 6 | 15 | 12 | 12 | 12 | 12 |  | 50 Ohms-3 | TOP=L2:L3=L2/L4:L6=L5/L7:BOTTOM=L7 |
| SSD14_PWREN | 50OHM_Y12MIL | BUS | 5 | 6 | 5 | 10 | 5 | 14 | 6 | 15 | 12 | 12 | 12 | 12 |  | 50 Ohms-3 | TOP=L2:L3=L2/L4:L6=L5/L7:BOTTOM=L7 |
| SSD14_PWREN | 50OHM_Y12MIL | BUS | 6 | 6 | 5 | 10 | 5 | 14 | 6 | 15 | 12 | 12 | 12 | 12 |  | 50 Ohms-3 | TOP=L2:L3=L2/L4:L6=L5/L7:BOTTOM=L7 |
| SSD14_PWREN | 50OHM_Y12MIL | BUS | 7 | 6 | 5 | 10 | 5 | 14 | 6 | 15 | 12 | 12 | 12 | 12 |  | 50 Ohms-3 | TOP=L2:L3=L2/L4:L6=L5/L7:BOTTOM=L7 |
| SSD14_PWREN | 50OHM_Y12MIL | BUS | 8 | 6.75 | 5 | 10 | 5 | 14 | 6 | 15 | 12 | 12 | 12 | 12 |  | 50 Ohms-3 | TOP=L2:L3=L2/L4:L6=L5/L7:BOTTOM=L7 |
| SSD14_PWREN_R | 50OHM_Y12MIL | BUS | 1 | 6.75 | 5 | 10 | 5 | 14 | 6 | 15 | 12 | 12 | 12 | 12 |  | 50 Ohms-3 | TOP=L2:L3=L2/L4:L6=L5/L7:BOTTOM=L7 |
| SSD14_PWREN_R | 50OHM_Y12MIL | BUS | 2 | 6 | 5 | 10 | 5 | 14 | 6 | 15 | 12 | 12 | 12 | 12 |  | 50 Ohms-3 | TOP=L2:L3=L2/L4:L6=L5/L7:BOTTOM=L7 |
| SSD14_PWREN_R | 50OHM_Y12MIL | BUS | 3 | 6 | 5 | 10 | 5 | 14 | 6 | 15 | 12 | 12 | 12 | 12 |  | 50 Ohms-3 | TOP=L2:L3=L2/L4:L6=L5/L7:BOTTOM=L7 |
| SSD14_PWREN_R | 50OHM_Y12MIL | BUS | 4 | 6 | 5 | 10 | 5 | 14 | 6 | 15 | 12 | 12 | 12 | 12 |  | 50 Ohms-3 | TOP=L2:L3=L2/L4:L6=L5/L7:BOTTOM=L7 |
| SSD14_PWREN_R | 50OHM_Y12MIL | BUS | 5 | 6 | 5 | 10 | 5 | 14 | 6 | 15 | 12 | 12 | 12 | 12 |  | 50 Ohms-3 | TOP=L2:L3=L2/L4:L6=L5/L7:BOTTOM=L7 |
| SSD14_PWREN_R | 50OHM_Y12MIL | BUS | 6 | 6 | 5 | 10 | 5 | 14 | 6 | 15 | 12 | 12 | 12 | 12 |  | 50 Ohms-3 | TOP=L2:L3=L2/L4:L6=L5/L7:BOTTOM=L7 |
| SSD14_PWREN_R | 50OHM_Y12MIL | BUS | 7 | 6 | 5 | 10 | 5 | 14 | 6 | 15 | 12 | 12 | 12 | 12 |  | 50 Ohms-3 | TOP=L2:L3=L2/L4:L6=L5/L7:BOTTOM=L7 |
| SSD14_PWREN_R | 50OHM_Y12MIL | BUS | 8 | 6.75 | 5 | 10 | 5 | 14 | 6 | 15 | 12 | 12 | 12 | 12 |  | 50 Ohms-3 | TOP=L2:L3=L2/L4:L6=L5/L7:BOTTOM=L7 |
| SSD2_CLK0_OE_MOS_N | 50OHM_Y12MIL | BUS | 1 | 6.75 | 5 | 10 | 5 | 14 | 6 | 15 | 12 | 12 | 12 | 12 |  | 50 Ohms-3 | TOP=L2:L3=L2/L4:L6=L5/L7:BOTTOM=L7 |
| SSD2_CLK0_OE_MOS_N | 50OHM_Y12MIL | BUS | 2 | 6 | 5 | 10 | 5 | 14 | 6 | 15 | 12 | 12 | 12 | 12 |  | 50 Ohms-3 | TOP=L2:L3=L2/L4:L6=L5/L7:BOTTOM=L7 |
| SSD2_CLK0_OE_MOS_N | 50OHM_Y12MIL | BUS | 3 | 6 | 5 | 10 | 5 | 14 | 6 | 15 | 12 | 12 | 12 | 12 |  | 50 Ohms-3 | TOP=L2:L3=L2/L4:L6=L5/L7:BOTTOM=L7 |
| SSD2_CLK0_OE_MOS_N | 50OHM_Y12MIL | BUS | 4 | 6 | 5 | 10 | 5 | 14 | 6 | 15 | 12 | 12 | 12 | 12 |  | 50 Ohms-3 | TOP=L2:L3=L2/L4:L6=L5/L7:BOTTOM=L7 |
| SSD2_CLK0_OE_MOS_N | 50OHM_Y12MIL | BUS | 5 | 6 | 5 | 10 | 5 | 14 | 6 | 15 | 12 | 12 | 12 | 12 |  | 50 Ohms-3 | TOP=L2:L3=L2/L4:L6=L5/L7:BOTTOM=L7 |
| SSD2_CLK0_OE_MOS_N | 50OHM_Y12MIL | BUS | 6 | 6 | 5 | 10 | 5 | 14 | 6 | 15 | 12 | 12 | 12 | 12 |  | 50 Ohms-3 | TOP=L2:L3=L2/L4:L6=L5/L7:BOTTOM=L7 |
| SSD2_CLK0_OE_MOS_N | 50OHM_Y12MIL | BUS | 7 | 6 | 5 | 10 | 5 | 14 | 6 | 15 | 12 | 12 | 12 | 12 |  | 50 Ohms-3 | TOP=L2:L3=L2/L4:L6=L5/L7:BOTTOM=L7 |
| SSD2_CLK0_OE_MOS_N | 50OHM_Y12MIL | BUS | 8 | 6.75 | 5 | 10 | 5 | 14 | 6 | 15 | 12 | 12 | 12 | 12 |  | 50 Ohms-3 | TOP=L2:L3=L2/L4:L6=L5/L7:BOTTOM=L7 |
| SSD2_CLK0_OE_N | 50OHM_Y12MIL | BUS | 1 | 6.75 | 5 | 10 | 5 | 14 | 6 | 15 | 12 | 12 | 12 | 12 |  | 50 Ohms-3 | TOP=L2:L3=L2/L4:L6=L5/L7:BOTTOM=L7 |
| SSD2_CLK0_OE_N | 50OHM_Y12MIL | BUS | 2 | 6 | 5 | 10 | 5 | 14 | 6 | 15 | 12 | 12 | 12 | 12 |  | 50 Ohms-3 | TOP=L2:L3=L2/L4:L6=L5/L7:BOTTOM=L7 |
| SSD2_CLK0_OE_N | 50OHM_Y12MIL | BUS | 3 | 6 | 5 | 10 | 5 | 14 | 6 | 15 | 12 | 12 | 12 | 12 |  | 50 Ohms-3 | TOP=L2:L3=L2/L4:L6=L5/L7:BOTTOM=L7 |
| SSD2_CLK0_OE_N | 50OHM_Y12MIL | BUS | 4 | 6 | 5 | 10 | 5 | 14 | 6 | 15 | 12 | 12 | 12 | 12 |  | 50 Ohms-3 | TOP=L2:L3=L2/L4:L6=L5/L7:BOTTOM=L7 |
| SSD2_CLK0_OE_N | 50OHM_Y12MIL | BUS | 5 | 6 | 5 | 10 | 5 | 14 | 6 | 15 | 12 | 12 | 12 | 12 |  | 50 Ohms-3 | TOP=L2:L3=L2/L4:L6=L5/L7:BOTTOM=L7 |
| SSD2_CLK0_OE_N | 50OHM_Y12MIL | BUS | 6 | 6 | 5 | 10 | 5 | 14 | 6 | 15 | 12 | 12 | 12 | 12 |  | 50 Ohms-3 | TOP=L2:L3=L2/L4:L6=L5/L7:BOTTOM=L7 |
| SSD2_CLK0_OE_N | 50OHM_Y12MIL | BUS | 7 | 6 | 5 | 10 | 5 | 14 | 6 | 15 | 12 | 12 | 12 | 12 |  | 50 Ohms-3 | TOP=L2:L3=L2/L4:L6=L5/L7:BOTTOM=L7 |
| SSD2_CLK0_OE_N | 50OHM_Y12MIL | BUS | 8 | 6.75 | 5 | 10 | 5 | 14 | 6 | 15 | 12 | 12 | 12 | 12 |  | 50 Ohms-3 | TOP=L2:L3=L2/L4:L6=L5/L7:BOTTOM=L7 |
| SSD2_CLK0_OE_R_N | 50OHM_Y12MIL | BUS | 1 | 6.75 | 5 | 10 | 5 | 14 | 6 | 15 | 12 | 12 | 12 | 12 |  | 50 Ohms-3 | TOP=L2:L3=L2/L4:L6=L5/L7:BOTTOM=L7 |
| SSD2_CLK0_OE_R_N | 50OHM_Y12MIL | BUS | 2 | 6 | 5 | 10 | 5 | 14 | 6 | 15 | 12 | 12 | 12 | 12 |  | 50 Ohms-3 | TOP=L2:L3=L2/L4:L6=L5/L7:BOTTOM=L7 |
| SSD2_CLK0_OE_R_N | 50OHM_Y12MIL | BUS | 3 | 6 | 5 | 10 | 5 | 14 | 6 | 15 | 12 | 12 | 12 | 12 |  | 50 Ohms-3 | TOP=L2:L3=L2/L4:L6=L5/L7:BOTTOM=L7 |
| SSD2_CLK0_OE_R_N | 50OHM_Y12MIL | BUS | 4 | 6 | 5 | 10 | 5 | 14 | 6 | 15 | 12 | 12 | 12 | 12 |  | 50 Ohms-3 | TOP=L2:L3=L2/L4:L6=L5/L7:BOTTOM=L7 |
| SSD2_CLK0_OE_R_N | 50OHM_Y12MIL | BUS | 5 | 6 | 5 | 10 | 5 | 14 | 6 | 15 | 12 | 12 | 12 | 12 |  | 50 Ohms-3 | TOP=L2:L3=L2/L4:L6=L5/L7:BOTTOM=L7 |
| SSD2_CLK0_OE_R_N | 50OHM_Y12MIL | BUS | 6 | 6 | 5 | 10 | 5 | 14 | 6 | 15 | 12 | 12 | 12 | 12 |  | 50 Ohms-3 | TOP=L2:L3=L2/L4:L6=L5/L7:BOTTOM=L7 |
| SSD2_CLK0_OE_R_N | 50OHM_Y12MIL | BUS | 7 | 6 | 5 | 10 | 5 | 14 | 6 | 15 | 12 | 12 | 12 | 12 |  | 50 Ohms-3 | TOP=L2:L3=L2/L4:L6=L5/L7:BOTTOM=L7 |
| SSD2_CLK0_OE_R_N | 50OHM_Y12MIL | BUS | 8 | 6.75 | 5 | 10 | 5 | 14 | 6 | 15 | 12 | 12 | 12 | 12 |  | 50 Ohms-3 | TOP=L2:L3=L2/L4:L6=L5/L7:BOTTOM=L7 |
| SSD2_PERST_N | 50OHM_Y12MIL | BUS | 1 | 6.75 | 5 | 10 | 5 | 14 | 6 | 15 | 12 | 12 | 12 | 12 |  | 50 Ohms-3 | TOP=L2:L3=L2/L4:L6=L5/L7:BOTTOM=L7 |
| SSD2_PERST_N | 50OHM_Y12MIL | BUS | 2 | 6 | 5 | 10 | 5 | 14 | 6 | 15 | 12 | 12 | 12 | 12 |  | 50 Ohms-3 | TOP=L2:L3=L2/L4:L6=L5/L7:BOTTOM=L7 |
| SSD2_PERST_N | 50OHM_Y12MIL | BUS | 3 | 6 | 5 | 10 | 5 | 14 | 6 | 15 | 12 | 12 | 12 | 12 |  | 50 Ohms-3 | TOP=L2:L3=L2/L4:L6=L5/L7:BOTTOM=L7 |
| SSD2_PERST_N | 50OHM_Y12MIL | BUS | 4 | 6 | 5 | 10 | 5 | 14 | 6 | 15 | 12 | 12 | 12 | 12 |  | 50 Ohms-3 | TOP=L2:L3=L2/L4:L6=L5/L7:BOTTOM=L7 |
| SSD2_PERST_N | 50OHM_Y12MIL | BUS | 5 | 6 | 5 | 10 | 5 | 14 | 6 | 15 | 12 | 12 | 12 | 12 |  | 50 Ohms-3 | TOP=L2:L3=L2/L4:L6=L5/L7:BOTTOM=L7 |
| SSD2_PERST_N | 50OHM_Y12MIL | BUS | 6 | 6 | 5 | 10 | 5 | 14 | 6 | 15 | 12 | 12 | 12 | 12 |  | 50 Ohms-3 | TOP=L2:L3=L2/L4:L6=L5/L7:BOTTOM=L7 |
| SSD2_PERST_N | 50OHM_Y12MIL | BUS | 7 | 6 | 5 | 10 | 5 | 14 | 6 | 15 | 12 | 12 | 12 | 12 |  | 50 Ohms-3 | TOP=L2:L3=L2/L4:L6=L5/L7:BOTTOM=L7 |
| SSD2_PERST_N | 50OHM_Y12MIL | BUS | 8 | 6.75 | 5 | 10 | 5 | 14 | 6 | 15 | 12 | 12 | 12 | 12 |  | 50 Ohms-3 | TOP=L2:L3=L2/L4:L6=L5/L7:BOTTOM=L7 |
| SSD2_PWREN | 50OHM_Y12MIL | BUS | 1 | 6.75 | 5 | 10 | 5 | 14 | 6 | 15 | 12 | 12 | 12 | 12 |  | 50 Ohms-3 | TOP=L2:L3=L2/L4:L6=L5/L7:BOTTOM=L7 |
| SSD2_PWREN | 50OHM_Y12MIL | BUS | 2 | 6 | 5 | 10 | 5 | 14 | 6 | 15 | 12 | 12 | 12 | 12 |  | 50 Ohms-3 | TOP=L2:L3=L2/L4:L6=L5/L7:BOTTOM=L7 |
| SSD2_PWREN | 50OHM_Y12MIL | BUS | 3 | 6 | 5 | 10 | 5 | 14 | 6 | 15 | 12 | 12 | 12 | 12 |  | 50 Ohms-3 | TOP=L2:L3=L2/L4:L6=L5/L7:BOTTOM=L7 |
| SSD2_PWREN | 50OHM_Y12MIL | BUS | 4 | 6 | 5 | 10 | 5 | 14 | 6 | 15 | 12 | 12 | 12 | 12 |  | 50 Ohms-3 | TOP=L2:L3=L2/L4:L6=L5/L7:BOTTOM=L7 |
| SSD2_PWREN | 50OHM_Y12MIL | BUS | 5 | 6 | 5 | 10 | 5 | 14 | 6 | 15 | 12 | 12 | 12 | 12 |  | 50 Ohms-3 | TOP=L2:L3=L2/L4:L6=L5/L7:BOTTOM=L7 |
| SSD2_PWREN | 50OHM_Y12MIL | BUS | 6 | 6 | 5 | 10 | 5 | 14 | 6 | 15 | 12 | 12 | 12 | 12 |  | 50 Ohms-3 | TOP=L2:L3=L2/L4:L6=L5/L7:BOTTOM=L7 |
| SSD2_PWREN | 50OHM_Y12MIL | BUS | 7 | 6 | 5 | 10 | 5 | 14 | 6 | 15 | 12 | 12 | 12 | 12 |  | 50 Ohms-3 | TOP=L2:L3=L2/L4:L6=L5/L7:BOTTOM=L7 |
| SSD2_PWREN | 50OHM_Y12MIL | BUS | 8 | 6.75 | 5 | 10 | 5 | 14 | 6 | 15 | 12 | 12 | 12 | 12 |  | 50 Ohms-3 | TOP=L2:L3=L2/L4:L6=L5/L7:BOTTOM=L7 |
| SSD2_PWREN_R | 50OHM_Y12MIL | BUS | 1 | 6.75 | 5 | 10 | 5 | 14 | 6 | 15 | 12 | 12 | 12 | 12 |  | 50 Ohms-3 | TOP=L2:L3=L2/L4:L6=L5/L7:BOTTOM=L7 |
| SSD2_PWREN_R | 50OHM_Y12MIL | BUS | 2 | 6 | 5 | 10 | 5 | 14 | 6 | 15 | 12 | 12 | 12 | 12 |  | 50 Ohms-3 | TOP=L2:L3=L2/L4:L6=L5/L7:BOTTOM=L7 |
| SSD2_PWREN_R | 50OHM_Y12MIL | BUS | 3 | 6 | 5 | 10 | 5 | 14 | 6 | 15 | 12 | 12 | 12 | 12 |  | 50 Ohms-3 | TOP=L2:L3=L2/L4:L6=L5/L7:BOTTOM=L7 |
| SSD2_PWREN_R | 50OHM_Y12MIL | BUS | 4 | 6 | 5 | 10 | 5 | 14 | 6 | 15 | 12 | 12 | 12 | 12 |  | 50 Ohms-3 | TOP=L2:L3=L2/L4:L6=L5/L7:BOTTOM=L7 |
| SSD2_PWREN_R | 50OHM_Y12MIL | BUS | 5 | 6 | 5 | 10 | 5 | 14 | 6 | 15 | 12 | 12 | 12 | 12 |  | 50 Ohms-3 | TOP=L2:L3=L2/L4:L6=L5/L7:BOTTOM=L7 |
| SSD2_PWREN_R | 50OHM_Y12MIL | BUS | 6 | 6 | 5 | 10 | 5 | 14 | 6 | 15 | 12 | 12 | 12 | 12 |  | 50 Ohms-3 | TOP=L2:L3=L2/L4:L6=L5/L7:BOTTOM=L7 |
| SSD2_PWREN_R | 50OHM_Y12MIL | BUS | 7 | 6 | 5 | 10 | 5 | 14 | 6 | 15 | 12 | 12 | 12 | 12 |  | 50 Ohms-3 | TOP=L2:L3=L2/L4:L6=L5/L7:BOTTOM=L7 |
| SSD2_PWREN_R | 50OHM_Y12MIL | BUS | 8 | 6.75 | 5 | 10 | 5 | 14 | 6 | 15 | 12 | 12 | 12 | 12 |  | 50 Ohms-3 | TOP=L2:L3=L2/L4:L6=L5/L7:BOTTOM=L7 |
| SSD3_CLK0_OE_MOS_N | 50OHM_Y12MIL | BUS | 1 | 6.75 | 5 | 10 | 5 | 14 | 6 | 15 | 12 | 12 | 12 | 12 |  | 50 Ohms-3 | TOP=L2:L3=L2/L4:L6=L5/L7:BOTTOM=L7 |
| SSD3_CLK0_OE_MOS_N | 50OHM_Y12MIL | BUS | 2 | 6 | 5 | 10 | 5 | 14 | 6 | 15 | 12 | 12 | 12 | 12 |  | 50 Ohms-3 | TOP=L2:L3=L2/L4:L6=L5/L7:BOTTOM=L7 |
| SSD3_CLK0_OE_MOS_N | 50OHM_Y12MIL | BUS | 3 | 6 | 5 | 10 | 5 | 14 | 6 | 15 | 12 | 12 | 12 | 12 |  | 50 Ohms-3 | TOP=L2:L3=L2/L4:L6=L5/L7:BOTTOM=L7 |
| SSD3_CLK0_OE_MOS_N | 50OHM_Y12MIL | BUS | 4 | 6 | 5 | 10 | 5 | 14 | 6 | 15 | 12 | 12 | 12 | 12 |  | 50 Ohms-3 | TOP=L2:L3=L2/L4:L6=L5/L7:BOTTOM=L7 |
| SSD3_CLK0_OE_MOS_N | 50OHM_Y12MIL | BUS | 5 | 6 | 5 | 10 | 5 | 14 | 6 | 15 | 12 | 12 | 12 | 12 |  | 50 Ohms-3 | TOP=L2:L3=L2/L4:L6=L5/L7:BOTTOM=L7 |
| SSD3_CLK0_OE_MOS_N | 50OHM_Y12MIL | BUS | 6 | 6 | 5 | 10 | 5 | 14 | 6 | 15 | 12 | 12 | 12 | 12 |  | 50 Ohms-3 | TOP=L2:L3=L2/L4:L6=L5/L7:BOTTOM=L7 |
| SSD3_CLK0_OE_MOS_N | 50OHM_Y12MIL | BUS | 7 | 6 | 5 | 10 | 5 | 14 | 6 | 15 | 12 | 12 | 12 | 12 |  | 50 Ohms-3 | TOP=L2:L3=L2/L4:L6=L5/L7:BOTTOM=L7 |
| SSD3_CLK0_OE_MOS_N | 50OHM_Y12MIL | BUS | 8 | 6.75 | 5 | 10 | 5 | 14 | 6 | 15 | 12 | 12 | 12 | 12 |  | 50 Ohms-3 | TOP=L2:L3=L2/L4:L6=L5/L7:BOTTOM=L7 |
| SSD3_CLK0_OE_N | 50OHM_Y12MIL | BUS | 1 | 6.75 | 5 | 10 | 5 | 14 | 6 | 15 | 12 | 12 | 12 | 12 |  | 50 Ohms-3 | TOP=L2:L3=L2/L4:L6=L5/L7:BOTTOM=L7 |
| SSD3_CLK0_OE_N | 50OHM_Y12MIL | BUS | 2 | 6 | 5 | 10 | 5 | 14 | 6 | 15 | 12 | 12 | 12 | 12 |  | 50 Ohms-3 | TOP=L2:L3=L2/L4:L6=L5/L7:BOTTOM=L7 |
| SSD3_CLK0_OE_N | 50OHM_Y12MIL | BUS | 3 | 6 | 5 | 10 | 5 | 14 | 6 | 15 | 12 | 12 | 12 | 12 |  | 50 Ohms-3 | TOP=L2:L3=L2/L4:L6=L5/L7:BOTTOM=L7 |
| SSD3_CLK0_OE_N | 50OHM_Y12MIL | BUS | 4 | 6 | 5 | 10 | 5 | 14 | 6 | 15 | 12 | 12 | 12 | 12 |  | 50 Ohms-3 | TOP=L2:L3=L2/L4:L6=L5/L7:BOTTOM=L7 |
| SSD3_CLK0_OE_N | 50OHM_Y12MIL | BUS | 5 | 6 | 5 | 10 | 5 | 14 | 6 | 15 | 12 | 12 | 12 | 12 |  | 50 Ohms-3 | TOP=L2:L3=L2/L4:L6=L5/L7:BOTTOM=L7 |
| SSD3_CLK0_OE_N | 50OHM_Y12MIL | BUS | 6 | 6 | 5 | 10 | 5 | 14 | 6 | 15 | 12 | 12 | 12 | 12 |  | 50 Ohms-3 | TOP=L2:L3=L2/L4:L6=L5/L7:BOTTOM=L7 |
| SSD3_CLK0_OE_N | 50OHM_Y12MIL | BUS | 7 | 6 | 5 | 10 | 5 | 14 | 6 | 15 | 12 | 12 | 12 | 12 |  | 50 Ohms-3 | TOP=L2:L3=L2/L4:L6=L5/L7:BOTTOM=L7 |
| SSD3_CLK0_OE_N | 50OHM_Y12MIL | BUS | 8 | 6.75 | 5 | 10 | 5 | 14 | 6 | 15 | 12 | 12 | 12 | 12 |  | 50 Ohms-3 | TOP=L2:L3=L2/L4:L6=L5/L7:BOTTOM=L7 |
| SSD3_CLK0_OE_R_N | 50OHM_Y12MIL | BUS | 1 | 6.75 | 5 | 10 | 5 | 14 | 6 | 15 | 12 | 12 | 12 | 12 |  | 50 Ohms-3 | TOP=L2:L3=L2/L4:L6=L5/L7:BOTTOM=L7 |
| SSD3_CLK0_OE_R_N | 50OHM_Y12MIL | BUS | 2 | 6 | 5 | 10 | 5 | 14 | 6 | 15 | 12 | 12 | 12 | 12 |  | 50 Ohms-3 | TOP=L2:L3=L2/L4:L6=L5/L7:BOTTOM=L7 |
| SSD3_CLK0_OE_R_N | 50OHM_Y12MIL | BUS | 3 | 6 | 5 | 10 | 5 | 14 | 6 | 15 | 12 | 12 | 12 | 12 |  | 50 Ohms-3 | TOP=L2:L3=L2/L4:L6=L5/L7:BOTTOM=L7 |
| SSD3_CLK0_OE_R_N | 50OHM_Y12MIL | BUS | 4 | 6 | 5 | 10 | 5 | 14 | 6 | 15 | 12 | 12 | 12 | 12 |  | 50 Ohms-3 | TOP=L2:L3=L2/L4:L6=L5/L7:BOTTOM=L7 |
| SSD3_CLK0_OE_R_N | 50OHM_Y12MIL | BUS | 5 | 6 | 5 | 10 | 5 | 14 | 6 | 15 | 12 | 12 | 12 | 12 |  | 50 Ohms-3 | TOP=L2:L3=L2/L4:L6=L5/L7:BOTTOM=L7 |
| SSD3_CLK0_OE_R_N | 50OHM_Y12MIL | BUS | 6 | 6 | 5 | 10 | 5 | 14 | 6 | 15 | 12 | 12 | 12 | 12 |  | 50 Ohms-3 | TOP=L2:L3=L2/L4:L6=L5/L7:BOTTOM=L7 |
| SSD3_CLK0_OE_R_N | 50OHM_Y12MIL | BUS | 7 | 6 | 5 | 10 | 5 | 14 | 6 | 15 | 12 | 12 | 12 | 12 |  | 50 Ohms-3 | TOP=L2:L3=L2/L4:L6=L5/L7:BOTTOM=L7 |
| SSD3_CLK0_OE_R_N | 50OHM_Y12MIL | BUS | 8 | 6.75 | 5 | 10 | 5 | 14 | 6 | 15 | 12 | 12 | 12 | 12 |  | 50 Ohms-3 | TOP=L2:L3=L2/L4:L6=L5/L7:BOTTOM=L7 |
| SSD3_PERST_N | 50OHM_Y12MIL | BUS | 1 | 6.75 | 5 | 10 | 5 | 14 | 6 | 15 | 12 | 12 | 12 | 12 |  | 50 Ohms-3 | TOP=L2:L3=L2/L4:L6=L5/L7:BOTTOM=L7 |
| SSD3_PERST_N | 50OHM_Y12MIL | BUS | 2 | 6 | 5 | 10 | 5 | 14 | 6 | 15 | 12 | 12 | 12 | 12 |  | 50 Ohms-3 | TOP=L2:L3=L2/L4:L6=L5/L7:BOTTOM=L7 |
| SSD3_PERST_N | 50OHM_Y12MIL | BUS | 3 | 6 | 5 | 10 | 5 | 14 | 6 | 15 | 12 | 12 | 12 | 12 |  | 50 Ohms-3 | TOP=L2:L3=L2/L4:L6=L5/L7:BOTTOM=L7 |
| SSD3_PERST_N | 50OHM_Y12MIL | BUS | 4 | 6 | 5 | 10 | 5 | 14 | 6 | 15 | 12 | 12 | 12 | 12 |  | 50 Ohms-3 | TOP=L2:L3=L2/L4:L6=L5/L7:BOTTOM=L7 |
| SSD3_PERST_N | 50OHM_Y12MIL | BUS | 5 | 6 | 5 | 10 | 5 | 14 | 6 | 15 | 12 | 12 | 12 | 12 |  | 50 Ohms-3 | TOP=L2:L3=L2/L4:L6=L5/L7:BOTTOM=L7 |
| SSD3_PERST_N | 50OHM_Y12MIL | BUS | 6 | 6 | 5 | 10 | 5 | 14 | 6 | 15 | 12 | 12 | 12 | 12 |  | 50 Ohms-3 | TOP=L2:L3=L2/L4:L6=L5/L7:BOTTOM=L7 |
| SSD3_PERST_N | 50OHM_Y12MIL | BUS | 7 | 6 | 5 | 10 | 5 | 14 | 6 | 15 | 12 | 12 | 12 | 12 |  | 50 Ohms-3 | TOP=L2:L3=L2/L4:L6=L5/L7:BOTTOM=L7 |
| SSD3_PERST_N | 50OHM_Y12MIL | BUS | 8 | 6.75 | 5 | 10 | 5 | 14 | 6 | 15 | 12 | 12 | 12 | 12 |  | 50 Ohms-3 | TOP=L2:L3=L2/L4:L6=L5/L7:BOTTOM=L7 |
| SSD3_PWREN | 50OHM_Y12MIL | BUS | 1 | 6.75 | 5 | 10 | 5 | 14 | 6 | 15 | 12 | 12 | 12 | 12 |  | 50 Ohms-3 | TOP=L2:L3=L2/L4:L6=L5/L7:BOTTOM=L7 |
| SSD3_PWREN | 50OHM_Y12MIL | BUS | 2 | 6 | 5 | 10 | 5 | 14 | 6 | 15 | 12 | 12 | 12 | 12 |  | 50 Ohms-3 | TOP=L2:L3=L2/L4:L6=L5/L7:BOTTOM=L7 |
| SSD3_PWREN | 50OHM_Y12MIL | BUS | 3 | 6 | 5 | 10 | 5 | 14 | 6 | 15 | 12 | 12 | 12 | 12 |  | 50 Ohms-3 | TOP=L2:L3=L2/L4:L6=L5/L7:BOTTOM=L7 |
| SSD3_PWREN | 50OHM_Y12MIL | BUS | 4 | 6 | 5 | 10 | 5 | 14 | 6 | 15 | 12 | 12 | 12 | 12 |  | 50 Ohms-3 | TOP=L2:L3=L2/L4:L6=L5/L7:BOTTOM=L7 |
| SSD3_PWREN | 50OHM_Y12MIL | BUS | 5 | 6 | 5 | 10 | 5 | 14 | 6 | 15 | 12 | 12 | 12 | 12 |  | 50 Ohms-3 | TOP=L2:L3=L2/L4:L6=L5/L7:BOTTOM=L7 |
| SSD3_PWREN | 50OHM_Y12MIL | BUS | 6 | 6 | 5 | 10 | 5 | 14 | 6 | 15 | 12 | 12 | 12 | 12 |  | 50 Ohms-3 | TOP=L2:L3=L2/L4:L6=L5/L7:BOTTOM=L7 |
| SSD3_PWREN | 50OHM_Y12MIL | BUS | 7 | 6 | 5 | 10 | 5 | 14 | 6 | 15 | 12 | 12 | 12 | 12 |  | 50 Ohms-3 | TOP=L2:L3=L2/L4:L6=L5/L7:BOTTOM=L7 |
| SSD3_PWREN | 50OHM_Y12MIL | BUS | 8 | 6.75 | 5 | 10 | 5 | 14 | 6 | 15 | 12 | 12 | 12 | 12 |  | 50 Ohms-3 | TOP=L2:L3=L2/L4:L6=L5/L7:BOTTOM=L7 |
| SSD3_PWREN_R | 50OHM_Y12MIL | BUS | 1 | 6.75 | 5 | 10 | 5 | 14 | 6 | 15 | 12 | 12 | 12 | 12 |  | 50 Ohms-3 | TOP=L2:L3=L2/L4:L6=L5/L7:BOTTOM=L7 |
| SSD3_PWREN_R | 50OHM_Y12MIL | BUS | 2 | 6 | 5 | 10 | 5 | 14 | 6 | 15 | 12 | 12 | 12 | 12 |  | 50 Ohms-3 | TOP=L2:L3=L2/L4:L6=L5/L7:BOTTOM=L7 |
| SSD3_PWREN_R | 50OHM_Y12MIL | BUS | 3 | 6 | 5 | 10 | 5 | 14 | 6 | 15 | 12 | 12 | 12 | 12 |  | 50 Ohms-3 | TOP=L2:L3=L2/L4:L6=L5/L7:BOTTOM=L7 |
| SSD3_PWREN_R | 50OHM_Y12MIL | BUS | 4 | 6 | 5 | 10 | 5 | 14 | 6 | 15 | 12 | 12 | 12 | 12 |  | 50 Ohms-3 | TOP=L2:L3=L2/L4:L6=L5/L7:BOTTOM=L7 |
| SSD3_PWREN_R | 50OHM_Y12MIL | BUS | 5 | 6 | 5 | 10 | 5 | 14 | 6 | 15 | 12 | 12 | 12 | 12 |  | 50 Ohms-3 | TOP=L2:L3=L2/L4:L6=L5/L7:BOTTOM=L7 |
| SSD3_PWREN_R | 50OHM_Y12MIL | BUS | 6 | 6 | 5 | 10 | 5 | 14 | 6 | 15 | 12 | 12 | 12 | 12 |  | 50 Ohms-3 | TOP=L2:L3=L2/L4:L6=L5/L7:BOTTOM=L7 |
| SSD3_PWREN_R | 50OHM_Y12MIL | BUS | 7 | 6 | 5 | 10 | 5 | 14 | 6 | 15 | 12 | 12 | 12 | 12 |  | 50 Ohms-3 | TOP=L2:L3=L2/L4:L6=L5/L7:BOTTOM=L7 |
| SSD3_PWREN_R | 50OHM_Y12MIL | BUS | 8 | 6.75 | 5 | 10 | 5 | 14 | 6 | 15 | 12 | 12 | 12 | 12 |  | 50 Ohms-3 | TOP=L2:L3=L2/L4:L6=L5/L7:BOTTOM=L7 |
| SSD4_CLK0_OE_MOS_N | 50OHM_Y12MIL | BUS | 1 | 6.75 | 5 | 10 | 5 | 14 | 6 | 15 | 12 | 12 | 12 | 12 |  | 50 Ohms-3 | TOP=L2:L3=L2/L4:L6=L5/L7:BOTTOM=L7 |
| SSD4_CLK0_OE_MOS_N | 50OHM_Y12MIL | BUS | 2 | 6 | 5 | 10 | 5 | 14 | 6 | 15 | 12 | 12 | 12 | 12 |  | 50 Ohms-3 | TOP=L2:L3=L2/L4:L6=L5/L7:BOTTOM=L7 |
| SSD4_CLK0_OE_MOS_N | 50OHM_Y12MIL | BUS | 3 | 6 | 5 | 10 | 5 | 14 | 6 | 15 | 12 | 12 | 12 | 12 |  | 50 Ohms-3 | TOP=L2:L3=L2/L4:L6=L5/L7:BOTTOM=L7 |
| SSD4_CLK0_OE_MOS_N | 50OHM_Y12MIL | BUS | 4 | 6 | 5 | 10 | 5 | 14 | 6 | 15 | 12 | 12 | 12 | 12 |  | 50 Ohms-3 | TOP=L2:L3=L2/L4:L6=L5/L7:BOTTOM=L7 |
| SSD4_CLK0_OE_MOS_N | 50OHM_Y12MIL | BUS | 5 | 6 | 5 | 10 | 5 | 14 | 6 | 15 | 12 | 12 | 12 | 12 |  | 50 Ohms-3 | TOP=L2:L3=L2/L4:L6=L5/L7:BOTTOM=L7 |
| SSD4_CLK0_OE_MOS_N | 50OHM_Y12MIL | BUS | 6 | 6 | 5 | 10 | 5 | 14 | 6 | 15 | 12 | 12 | 12 | 12 |  | 50 Ohms-3 | TOP=L2:L3=L2/L4:L6=L5/L7:BOTTOM=L7 |
| SSD4_CLK0_OE_MOS_N | 50OHM_Y12MIL | BUS | 7 | 6 | 5 | 10 | 5 | 14 | 6 | 15 | 12 | 12 | 12 | 12 |  | 50 Ohms-3 | TOP=L2:L3=L2/L4:L6=L5/L7:BOTTOM=L7 |
| SSD4_CLK0_OE_MOS_N | 50OHM_Y12MIL | BUS | 8 | 6.75 | 5 | 10 | 5 | 14 | 6 | 15 | 12 | 12 | 12 | 12 |  | 50 Ohms-3 | TOP=L2:L3=L2/L4:L6=L5/L7:BOTTOM=L7 |
| SSD4_CLK0_OE_N | 50OHM_Y12MIL | BUS | 1 | 6.75 | 5 | 10 | 5 | 14 | 6 | 15 | 12 | 12 | 12 | 12 |  | 50 Ohms-3 | TOP=L2:L3=L2/L4:L6=L5/L7:BOTTOM=L7 |
| SSD4_CLK0_OE_N | 50OHM_Y12MIL | BUS | 2 | 6 | 5 | 10 | 5 | 14 | 6 | 15 | 12 | 12 | 12 | 12 |  | 50 Ohms-3 | TOP=L2:L3=L2/L4:L6=L5/L7:BOTTOM=L7 |
| SSD4_CLK0_OE_N | 50OHM_Y12MIL | BUS | 3 | 6 | 5 | 10 | 5 | 14 | 6 | 15 | 12 | 12 | 12 | 12 |  | 50 Ohms-3 | TOP=L2:L3=L2/L4:L6=L5/L7:BOTTOM=L7 |
| SSD4_CLK0_OE_N | 50OHM_Y12MIL | BUS | 4 | 6 | 5 | 10 | 5 | 14 | 6 | 15 | 12 | 12 | 12 | 12 |  | 50 Ohms-3 | TOP=L2:L3=L2/L4:L6=L5/L7:BOTTOM=L7 |
| SSD4_CLK0_OE_N | 50OHM_Y12MIL | BUS | 5 | 6 | 5 | 10 | 5 | 14 | 6 | 15 | 12 | 12 | 12 | 12 |  | 50 Ohms-3 | TOP=L2:L3=L2/L4:L6=L5/L7:BOTTOM=L7 |
| SSD4_CLK0_OE_N | 50OHM_Y12MIL | BUS | 6 | 6 | 5 | 10 | 5 | 14 | 6 | 15 | 12 | 12 | 12 | 12 |  | 50 Ohms-3 | TOP=L2:L3=L2/L4:L6=L5/L7:BOTTOM=L7 |
| SSD4_CLK0_OE_N | 50OHM_Y12MIL | BUS | 7 | 6 | 5 | 10 | 5 | 14 | 6 | 15 | 12 | 12 | 12 | 12 |  | 50 Ohms-3 | TOP=L2:L3=L2/L4:L6=L5/L7:BOTTOM=L7 |
| SSD4_CLK0_OE_N | 50OHM_Y12MIL | BUS | 8 | 6.75 | 5 | 10 | 5 | 14 | 6 | 15 | 12 | 12 | 12 | 12 |  | 50 Ohms-3 | TOP=L2:L3=L2/L4:L6=L5/L7:BOTTOM=L7 |
| SSD4_CLK0_OE_R_N | 50OHM_Y12MIL | BUS | 1 | 6.75 | 5 | 10 | 5 | 14 | 6 | 15 | 12 | 12 | 12 | 12 |  | 50 Ohms-3 | TOP=L2:L3=L2/L4:L6=L5/L7:BOTTOM=L7 |
| SSD4_CLK0_OE_R_N | 50OHM_Y12MIL | BUS | 2 | 6 | 5 | 10 | 5 | 14 | 6 | 15 | 12 | 12 | 12 | 12 |  | 50 Ohms-3 | TOP=L2:L3=L2/L4:L6=L5/L7:BOTTOM=L7 |
| SSD4_CLK0_OE_R_N | 50OHM_Y12MIL | BUS | 3 | 6 | 5 | 10 | 5 | 14 | 6 | 15 | 12 | 12 | 12 | 12 |  | 50 Ohms-3 | TOP=L2:L3=L2/L4:L6=L5/L7:BOTTOM=L7 |
| SSD4_CLK0_OE_R_N | 50OHM_Y12MIL | BUS | 4 | 6 | 5 | 10 | 5 | 14 | 6 | 15 | 12 | 12 | 12 | 12 |  | 50 Ohms-3 | TOP=L2:L3=L2/L4:L6=L5/L7:BOTTOM=L7 |
| SSD4_CLK0_OE_R_N | 50OHM_Y12MIL | BUS | 5 | 6 | 5 | 10 | 5 | 14 | 6 | 15 | 12 | 12 | 12 | 12 |  | 50 Ohms-3 | TOP=L2:L3=L2/L4:L6=L5/L7:BOTTOM=L7 |
| SSD4_CLK0_OE_R_N | 50OHM_Y12MIL | BUS | 6 | 6 | 5 | 10 | 5 | 14 | 6 | 15 | 12 | 12 | 12 | 12 |  | 50 Ohms-3 | TOP=L2:L3=L2/L4:L6=L5/L7:BOTTOM=L7 |
| SSD4_CLK0_OE_R_N | 50OHM_Y12MIL | BUS | 7 | 6 | 5 | 10 | 5 | 14 | 6 | 15 | 12 | 12 | 12 | 12 |  | 50 Ohms-3 | TOP=L2:L3=L2/L4:L6=L5/L7:BOTTOM=L7 |
| SSD4_CLK0_OE_R_N | 50OHM_Y12MIL | BUS | 8 | 6.75 | 5 | 10 | 5 | 14 | 6 | 15 | 12 | 12 | 12 | 12 |  | 50 Ohms-3 | TOP=L2:L3=L2/L4:L6=L5/L7:BOTTOM=L7 |
| SSD4_PERST_N | 50OHM_Y12MIL | BUS | 1 | 6.75 | 5 | 10 | 5 | 14 | 6 | 15 | 12 | 12 | 12 | 12 |  | 50 Ohms-3 | TOP=L2:L3=L2/L4:L6=L5/L7:BOTTOM=L7 |
| SSD4_PERST_N | 50OHM_Y12MIL | BUS | 2 | 6 | 5 | 10 | 5 | 14 | 6 | 15 | 12 | 12 | 12 | 12 |  | 50 Ohms-3 | TOP=L2:L3=L2/L4:L6=L5/L7:BOTTOM=L7 |
| SSD4_PERST_N | 50OHM_Y12MIL | BUS | 3 | 6 | 5 | 10 | 5 | 14 | 6 | 15 | 12 | 12 | 12 | 12 |  | 50 Ohms-3 | TOP=L2:L3=L2/L4:L6=L5/L7:BOTTOM=L7 |
| SSD4_PERST_N | 50OHM_Y12MIL | BUS | 4 | 6 | 5 | 10 | 5 | 14 | 6 | 15 | 12 | 12 | 12 | 12 |  | 50 Ohms-3 | TOP=L2:L3=L2/L4:L6=L5/L7:BOTTOM=L7 |
| SSD4_PERST_N | 50OHM_Y12MIL | BUS | 5 | 6 | 5 | 10 | 5 | 14 | 6 | 15 | 12 | 12 | 12 | 12 |  | 50 Ohms-3 | TOP=L2:L3=L2/L4:L6=L5/L7:BOTTOM=L7 |
| SSD4_PERST_N | 50OHM_Y12MIL | BUS | 6 | 6 | 5 | 10 | 5 | 14 | 6 | 15 | 12 | 12 | 12 | 12 |  | 50 Ohms-3 | TOP=L2:L3=L2/L4:L6=L5/L7:BOTTOM=L7 |
| SSD4_PERST_N | 50OHM_Y12MIL | BUS | 7 | 6 | 5 | 10 | 5 | 14 | 6 | 15 | 12 | 12 | 12 | 12 |  | 50 Ohms-3 | TOP=L2:L3=L2/L4:L6=L5/L7:BOTTOM=L7 |
| SSD4_PERST_N | 50OHM_Y12MIL | BUS | 8 | 6.75 | 5 | 10 | 5 | 14 | 6 | 15 | 12 | 12 | 12 | 12 |  | 50 Ohms-3 | TOP=L2:L3=L2/L4:L6=L5/L7:BOTTOM=L7 |
| SSD4_PWREN | 50OHM_Y12MIL | BUS | 1 | 6.75 | 5 | 10 | 5 | 14 | 6 | 15 | 12 | 12 | 12 | 12 |  | 50 Ohms-3 | TOP=L2:L3=L2/L4:L6=L5/L7:BOTTOM=L7 |
| SSD4_PWREN | 50OHM_Y12MIL | BUS | 2 | 6 | 5 | 10 | 5 | 14 | 6 | 15 | 12 | 12 | 12 | 12 |  | 50 Ohms-3 | TOP=L2:L3=L2/L4:L6=L5/L7:BOTTOM=L7 |
| SSD4_PWREN | 50OHM_Y12MIL | BUS | 3 | 6 | 5 | 10 | 5 | 14 | 6 | 15 | 12 | 12 | 12 | 12 |  | 50 Ohms-3 | TOP=L2:L3=L2/L4:L6=L5/L7:BOTTOM=L7 |
| SSD4_PWREN | 50OHM_Y12MIL | BUS | 4 | 6 | 5 | 10 | 5 | 14 | 6 | 15 | 12 | 12 | 12 | 12 |  | 50 Ohms-3 | TOP=L2:L3=L2/L4:L6=L5/L7:BOTTOM=L7 |
| SSD4_PWREN | 50OHM_Y12MIL | BUS | 5 | 6 | 5 | 10 | 5 | 14 | 6 | 15 | 12 | 12 | 12 | 12 |  | 50 Ohms-3 | TOP=L2:L3=L2/L4:L6=L5/L7:BOTTOM=L7 |
| SSD4_PWREN | 50OHM_Y12MIL | BUS | 6 | 6 | 5 | 10 | 5 | 14 | 6 | 15 | 12 | 12 | 12 | 12 |  | 50 Ohms-3 | TOP=L2:L3=L2/L4:L6=L5/L7:BOTTOM=L7 |
| SSD4_PWREN | 50OHM_Y12MIL | BUS | 7 | 6 | 5 | 10 | 5 | 14 | 6 | 15 | 12 | 12 | 12 | 12 |  | 50 Ohms-3 | TOP=L2:L3=L2/L4:L6=L5/L7:BOTTOM=L7 |
| SSD4_PWREN | 50OHM_Y12MIL | BUS | 8 | 6.75 | 5 | 10 | 5 | 14 | 6 | 15 | 12 | 12 | 12 | 12 |  | 50 Ohms-3 | TOP=L2:L3=L2/L4:L6=L5/L7:BOTTOM=L7 |
| SSD4_PWREN_R | 50OHM_Y12MIL | BUS | 1 | 6.75 | 5 | 10 | 5 | 14 | 6 | 15 | 12 | 12 | 12 | 12 |  | 50 Ohms-3 | TOP=L2:L3=L2/L4:L6=L5/L7:BOTTOM=L7 |
| SSD4_PWREN_R | 50OHM_Y12MIL | BUS | 2 | 6 | 5 | 10 | 5 | 14 | 6 | 15 | 12 | 12 | 12 | 12 |  | 50 Ohms-3 | TOP=L2:L3=L2/L4:L6=L5/L7:BOTTOM=L7 |
| SSD4_PWREN_R | 50OHM_Y12MIL | BUS | 3 | 6 | 5 | 10 | 5 | 14 | 6 | 15 | 12 | 12 | 12 | 12 |  | 50 Ohms-3 | TOP=L2:L3=L2/L4:L6=L5/L7:BOTTOM=L7 |
| SSD4_PWREN_R | 50OHM_Y12MIL | BUS | 4 | 6 | 5 | 10 | 5 | 14 | 6 | 15 | 12 | 12 | 12 | 12 |  | 50 Ohms-3 | TOP=L2:L3=L2/L4:L6=L5/L7:BOTTOM=L7 |
| SSD4_PWREN_R | 50OHM_Y12MIL | BUS | 5 | 6 | 5 | 10 | 5 | 14 | 6 | 15 | 12 | 12 | 12 | 12 |  | 50 Ohms-3 | TOP=L2:L3=L2/L4:L6=L5/L7:BOTTOM=L7 |
| SSD4_PWREN_R | 50OHM_Y12MIL | BUS | 6 | 6 | 5 | 10 | 5 | 14 | 6 | 15 | 12 | 12 | 12 | 12 |  | 50 Ohms-3 | TOP=L2:L3=L2/L4:L6=L5/L7:BOTTOM=L7 |
| SSD4_PWREN_R | 50OHM_Y12MIL | BUS | 7 | 6 | 5 | 10 | 5 | 14 | 6 | 15 | 12 | 12 | 12 | 12 |  | 50 Ohms-3 | TOP=L2:L3=L2/L4:L6=L5/L7:BOTTOM=L7 |
| SSD4_PWREN_R | 50OHM_Y12MIL | BUS | 8 | 6.75 | 5 | 10 | 5 | 14 | 6 | 15 | 12 | 12 | 12 | 12 |  | 50 Ohms-3 | TOP=L2:L3=L2/L4:L6=L5/L7:BOTTOM=L7 |
| SSD5_CLK0_OE_MOS_N | 50OHM_Y12MIL | BUS | 1 | 6.75 | 5 | 10 | 5 | 14 | 6 | 15 | 12 | 12 | 12 | 12 |  | 50 Ohms-3 | TOP=L2:L3=L2/L4:L6=L5/L7:BOTTOM=L7 |
| SSD5_CLK0_OE_MOS_N | 50OHM_Y12MIL | BUS | 2 | 6 | 5 | 10 | 5 | 14 | 6 | 15 | 12 | 12 | 12 | 12 |  | 50 Ohms-3 | TOP=L2:L3=L2/L4:L6=L5/L7:BOTTOM=L7 |
| SSD5_CLK0_OE_MOS_N | 50OHM_Y12MIL | BUS | 3 | 6 | 5 | 10 | 5 | 14 | 6 | 15 | 12 | 12 | 12 | 12 |  | 50 Ohms-3 | TOP=L2:L3=L2/L4:L6=L5/L7:BOTTOM=L7 |
| SSD5_CLK0_OE_MOS_N | 50OHM_Y12MIL | BUS | 4 | 6 | 5 | 10 | 5 | 14 | 6 | 15 | 12 | 12 | 12 | 12 |  | 50 Ohms-3 | TOP=L2:L3=L2/L4:L6=L5/L7:BOTTOM=L7 |
| SSD5_CLK0_OE_MOS_N | 50OHM_Y12MIL | BUS | 5 | 6 | 5 | 10 | 5 | 14 | 6 | 15 | 12 | 12 | 12 | 12 |  | 50 Ohms-3 | TOP=L2:L3=L2/L4:L6=L5/L7:BOTTOM=L7 |
| SSD5_CLK0_OE_MOS_N | 50OHM_Y12MIL | BUS | 6 | 6 | 5 | 10 | 5 | 14 | 6 | 15 | 12 | 12 | 12 | 12 |  | 50 Ohms-3 | TOP=L2:L3=L2/L4:L6=L5/L7:BOTTOM=L7 |
| SSD5_CLK0_OE_MOS_N | 50OHM_Y12MIL | BUS | 7 | 6 | 5 | 10 | 5 | 14 | 6 | 15 | 12 | 12 | 12 | 12 |  | 50 Ohms-3 | TOP=L2:L3=L2/L4:L6=L5/L7:BOTTOM=L7 |
| SSD5_CLK0_OE_MOS_N | 50OHM_Y12MIL | BUS | 8 | 6.75 | 5 | 10 | 5 | 14 | 6 | 15 | 12 | 12 | 12 | 12 |  | 50 Ohms-3 | TOP=L2:L3=L2/L4:L6=L5/L7:BOTTOM=L7 |
| SSD5_CLK0_OE_N | 50OHM_Y12MIL | BUS | 1 | 6.75 | 5 | 10 | 5 | 14 | 6 | 15 | 12 | 12 | 12 | 12 |  | 50 Ohms-3 | TOP=L2:L3=L2/L4:L6=L5/L7:BOTTOM=L7 |
| SSD5_CLK0_OE_N | 50OHM_Y12MIL | BUS | 2 | 6 | 5 | 10 | 5 | 14 | 6 | 15 | 12 | 12 | 12 | 12 |  | 50 Ohms-3 | TOP=L2:L3=L2/L4:L6=L5/L7:BOTTOM=L7 |
| SSD5_CLK0_OE_N | 50OHM_Y12MIL | BUS | 3 | 6 | 5 | 10 | 5 | 14 | 6 | 15 | 12 | 12 | 12 | 12 |  | 50 Ohms-3 | TOP=L2:L3=L2/L4:L6=L5/L7:BOTTOM=L7 |
| SSD5_CLK0_OE_N | 50OHM_Y12MIL | BUS | 4 | 6 | 5 | 10 | 5 | 14 | 6 | 15 | 12 | 12 | 12 | 12 |  | 50 Ohms-3 | TOP=L2:L3=L2/L4:L6=L5/L7:BOTTOM=L7 |
| SSD5_CLK0_OE_N | 50OHM_Y12MIL | BUS | 5 | 6 | 5 | 10 | 5 | 14 | 6 | 15 | 12 | 12 | 12 | 12 |  | 50 Ohms-3 | TOP=L2:L3=L2/L4:L6=L5/L7:BOTTOM=L7 |
| SSD5_CLK0_OE_N | 50OHM_Y12MIL | BUS | 6 | 6 | 5 | 10 | 5 | 14 | 6 | 15 | 12 | 12 | 12 | 12 |  | 50 Ohms-3 | TOP=L2:L3=L2/L4:L6=L5/L7:BOTTOM=L7 |
| SSD5_CLK0_OE_N | 50OHM_Y12MIL | BUS | 7 | 6 | 5 | 10 | 5 | 14 | 6 | 15 | 12 | 12 | 12 | 12 |  | 50 Ohms-3 | TOP=L2:L3=L2/L4:L6=L5/L7:BOTTOM=L7 |
| SSD5_CLK0_OE_N | 50OHM_Y12MIL | BUS | 8 | 6.75 | 5 | 10 | 5 | 14 | 6 | 15 | 12 | 12 | 12 | 12 |  | 50 Ohms-3 | TOP=L2:L3=L2/L4:L6=L5/L7:BOTTOM=L7 |
| SSD5_CLK0_OE_R_N | 50OHM_Y12MIL | BUS | 1 | 6.75 | 5 | 10 | 5 | 14 | 6 | 15 | 12 | 12 | 12 | 12 |  | 50 Ohms-3 | TOP=L2:L3=L2/L4:L6=L5/L7:BOTTOM=L7 |
| SSD5_CLK0_OE_R_N | 50OHM_Y12MIL | BUS | 2 | 6 | 5 | 10 | 5 | 14 | 6 | 15 | 12 | 12 | 12 | 12 |  | 50 Ohms-3 | TOP=L2:L3=L2/L4:L6=L5/L7:BOTTOM=L7 |
| SSD5_CLK0_OE_R_N | 50OHM_Y12MIL | BUS | 3 | 6 | 5 | 10 | 5 | 14 | 6 | 15 | 12 | 12 | 12 | 12 |  | 50 Ohms-3 | TOP=L2:L3=L2/L4:L6=L5/L7:BOTTOM=L7 |
| SSD5_CLK0_OE_R_N | 50OHM_Y12MIL | BUS | 4 | 6 | 5 | 10 | 5 | 14 | 6 | 15 | 12 | 12 | 12 | 12 |  | 50 Ohms-3 | TOP=L2:L3=L2/L4:L6=L5/L7:BOTTOM=L7 |
| SSD5_CLK0_OE_R_N | 50OHM_Y12MIL | BUS | 5 | 6 | 5 | 10 | 5 | 14 | 6 | 15 | 12 | 12 | 12 | 12 |  | 50 Ohms-3 | TOP=L2:L3=L2/L4:L6=L5/L7:BOTTOM=L7 |
| SSD5_CLK0_OE_R_N | 50OHM_Y12MIL | BUS | 6 | 6 | 5 | 10 | 5 | 14 | 6 | 15 | 12 | 12 | 12 | 12 |  | 50 Ohms-3 | TOP=L2:L3=L2/L4:L6=L5/L7:BOTTOM=L7 |
| SSD5_CLK0_OE_R_N | 50OHM_Y12MIL | BUS | 7 | 6 | 5 | 10 | 5 | 14 | 6 | 15 | 12 | 12 | 12 | 12 |  | 50 Ohms-3 | TOP=L2:L3=L2/L4:L6=L5/L7:BOTTOM=L7 |
| SSD5_CLK0_OE_R_N | 50OHM_Y12MIL | BUS | 8 | 6.75 | 5 | 10 | 5 | 14 | 6 | 15 | 12 | 12 | 12 | 12 |  | 50 Ohms-3 | TOP=L2:L3=L2/L4:L6=L5/L7:BOTTOM=L7 |
| SSD5_PERST_N | 50OHM_Y12MIL | BUS | 1 | 6.75 | 5 | 10 | 5 | 14 | 6 | 15 | 12 | 12 | 12 | 12 |  | 50 Ohms-3 | TOP=L2:L3=L2/L4:L6=L5/L7:BOTTOM=L7 |
| SSD5_PERST_N | 50OHM_Y12MIL | BUS | 2 | 6 | 5 | 10 | 5 | 14 | 6 | 15 | 12 | 12 | 12 | 12 |  | 50 Ohms-3 | TOP=L2:L3=L2/L4:L6=L5/L7:BOTTOM=L7 |
| SSD5_PERST_N | 50OHM_Y12MIL | BUS | 3 | 6 | 5 | 10 | 5 | 14 | 6 | 15 | 12 | 12 | 12 | 12 |  | 50 Ohms-3 | TOP=L2:L3=L2/L4:L6=L5/L7:BOTTOM=L7 |
| SSD5_PERST_N | 50OHM_Y12MIL | BUS | 4 | 6 | 5 | 10 | 5 | 14 | 6 | 15 | 12 | 12 | 12 | 12 |  | 50 Ohms-3 | TOP=L2:L3=L2/L4:L6=L5/L7:BOTTOM=L7 |
| SSD5_PERST_N | 50OHM_Y12MIL | BUS | 5 | 6 | 5 | 10 | 5 | 14 | 6 | 15 | 12 | 12 | 12 | 12 |  | 50 Ohms-3 | TOP=L2:L3=L2/L4:L6=L5/L7:BOTTOM=L7 |
| SSD5_PERST_N | 50OHM_Y12MIL | BUS | 6 | 6 | 5 | 10 | 5 | 14 | 6 | 15 | 12 | 12 | 12 | 12 |  | 50 Ohms-3 | TOP=L2:L3=L2/L4:L6=L5/L7:BOTTOM=L7 |
| SSD5_PERST_N | 50OHM_Y12MIL | BUS | 7 | 6 | 5 | 10 | 5 | 14 | 6 | 15 | 12 | 12 | 12 | 12 |  | 50 Ohms-3 | TOP=L2:L3=L2/L4:L6=L5/L7:BOTTOM=L7 |
| SSD5_PERST_N | 50OHM_Y12MIL | BUS | 8 | 6.75 | 5 | 10 | 5 | 14 | 6 | 15 | 12 | 12 | 12 | 12 |  | 50 Ohms-3 | TOP=L2:L3=L2/L4:L6=L5/L7:BOTTOM=L7 |
| SSD5_PWREN | 50OHM_Y12MIL | BUS | 1 | 6.75 | 5 | 10 | 5 | 14 | 6 | 15 | 12 | 12 | 12 | 12 |  | 50 Ohms-3 | TOP=L2:L3=L2/L4:L6=L5/L7:BOTTOM=L7 |
| SSD5_PWREN | 50OHM_Y12MIL | BUS | 2 | 6 | 5 | 10 | 5 | 14 | 6 | 15 | 12 | 12 | 12 | 12 |  | 50 Ohms-3 | TOP=L2:L3=L2/L4:L6=L5/L7:BOTTOM=L7 |
| SSD5_PWREN | 50OHM_Y12MIL | BUS | 3 | 6 | 5 | 10 | 5 | 14 | 6 | 15 | 12 | 12 | 12 | 12 |  | 50 Ohms-3 | TOP=L2:L3=L2/L4:L6=L5/L7:BOTTOM=L7 |
| SSD5_PWREN | 50OHM_Y12MIL | BUS | 4 | 6 | 5 | 10 | 5 | 14 | 6 | 15 | 12 | 12 | 12 | 12 |  | 50 Ohms-3 | TOP=L2:L3=L2/L4:L6=L5/L7:BOTTOM=L7 |
| SSD5_PWREN | 50OHM_Y12MIL | BUS | 5 | 6 | 5 | 10 | 5 | 14 | 6 | 15 | 12 | 12 | 12 | 12 |  | 50 Ohms-3 | TOP=L2:L3=L2/L4:L6=L5/L7:BOTTOM=L7 |
| SSD5_PWREN | 50OHM_Y12MIL | BUS | 6 | 6 | 5 | 10 | 5 | 14 | 6 | 15 | 12 | 12 | 12 | 12 |  | 50 Ohms-3 | TOP=L2:L3=L2/L4:L6=L5/L7:BOTTOM=L7 |
| SSD5_PWREN | 50OHM_Y12MIL | BUS | 7 | 6 | 5 | 10 | 5 | 14 | 6 | 15 | 12 | 12 | 12 | 12 |  | 50 Ohms-3 | TOP=L2:L3=L2/L4:L6=L5/L7:BOTTOM=L7 |
| SSD5_PWREN | 50OHM_Y12MIL | BUS | 8 | 6.75 | 5 | 10 | 5 | 14 | 6 | 15 | 12 | 12 | 12 | 12 |  | 50 Ohms-3 | TOP=L2:L3=L2/L4:L6=L5/L7:BOTTOM=L7 |
| SSD5_PWREN_R | 50OHM_Y12MIL | BUS | 1 | 6.75 | 5 | 10 | 5 | 14 | 6 | 15 | 12 | 12 | 12 | 12 |  | 50 Ohms-3 | TOP=L2:L3=L2/L4:L6=L5/L7:BOTTOM=L7 |
| SSD5_PWREN_R | 50OHM_Y12MIL | BUS | 2 | 6 | 5 | 10 | 5 | 14 | 6 | 15 | 12 | 12 | 12 | 12 |  | 50 Ohms-3 | TOP=L2:L3=L2/L4:L6=L5/L7:BOTTOM=L7 |
| SSD5_PWREN_R | 50OHM_Y12MIL | BUS | 3 | 6 | 5 | 10 | 5 | 14 | 6 | 15 | 12 | 12 | 12 | 12 |  | 50 Ohms-3 | TOP=L2:L3=L2/L4:L6=L5/L7:BOTTOM=L7 |
| SSD5_PWREN_R | 50OHM_Y12MIL | BUS | 4 | 6 | 5 | 10 | 5 | 14 | 6 | 15 | 12 | 12 | 12 | 12 |  | 50 Ohms-3 | TOP=L2:L3=L2/L4:L6=L5/L7:BOTTOM=L7 |
| SSD5_PWREN_R | 50OHM_Y12MIL | BUS | 5 | 6 | 5 | 10 | 5 | 14 | 6 | 15 | 12 | 12 | 12 | 12 |  | 50 Ohms-3 | TOP=L2:L3=L2/L4:L6=L5/L7:BOTTOM=L7 |
| SSD5_PWREN_R | 50OHM_Y12MIL | BUS | 6 | 6 | 5 | 10 | 5 | 14 | 6 | 15 | 12 | 12 | 12 | 12 |  | 50 Ohms-3 | TOP=L2:L3=L2/L4:L6=L5/L7:BOTTOM=L7 |
| SSD5_PWREN_R | 50OHM_Y12MIL | BUS | 7 | 6 | 5 | 10 | 5 | 14 | 6 | 15 | 12 | 12 | 12 | 12 |  | 50 Ohms-3 | TOP=L2:L3=L2/L4:L6=L5/L7:BOTTOM=L7 |
| SSD5_PWREN_R | 50OHM_Y12MIL | BUS | 8 | 6.75 | 5 | 10 | 5 | 14 | 6 | 15 | 12 | 12 | 12 | 12 |  | 50 Ohms-3 | TOP=L2:L3=L2/L4:L6=L5/L7:BOTTOM=L7 |
| SSD6_CLK0_OE_MOS_N | 50OHM_Y12MIL | BUS | 1 | 6.75 | 5 | 10 | 5 | 14 | 6 | 15 | 12 | 12 | 12 | 12 |  | 50 Ohms-3 | TOP=L2:L3=L2/L4:L6=L5/L7:BOTTOM=L7 |
| SSD6_CLK0_OE_MOS_N | 50OHM_Y12MIL | BUS | 2 | 6 | 5 | 10 | 5 | 14 | 6 | 15 | 12 | 12 | 12 | 12 |  | 50 Ohms-3 | TOP=L2:L3=L2/L4:L6=L5/L7:BOTTOM=L7 |
| SSD6_CLK0_OE_MOS_N | 50OHM_Y12MIL | BUS | 3 | 6 | 5 | 10 | 5 | 14 | 6 | 15 | 12 | 12 | 12 | 12 |  | 50 Ohms-3 | TOP=L2:L3=L2/L4:L6=L5/L7:BOTTOM=L7 |
| SSD6_CLK0_OE_MOS_N | 50OHM_Y12MIL | BUS | 4 | 6 | 5 | 10 | 5 | 14 | 6 | 15 | 12 | 12 | 12 | 12 |  | 50 Ohms-3 | TOP=L2:L3=L2/L4:L6=L5/L7:BOTTOM=L7 |
| SSD6_CLK0_OE_MOS_N | 50OHM_Y12MIL | BUS | 5 | 6 | 5 | 10 | 5 | 14 | 6 | 15 | 12 | 12 | 12 | 12 |  | 50 Ohms-3 | TOP=L2:L3=L2/L4:L6=L5/L7:BOTTOM=L7 |
| SSD6_CLK0_OE_MOS_N | 50OHM_Y12MIL | BUS | 6 | 6 | 5 | 10 | 5 | 14 | 6 | 15 | 12 | 12 | 12 | 12 |  | 50 Ohms-3 | TOP=L2:L3=L2/L4:L6=L5/L7:BOTTOM=L7 |
| SSD6_CLK0_OE_MOS_N | 50OHM_Y12MIL | BUS | 7 | 6 | 5 | 10 | 5 | 14 | 6 | 15 | 12 | 12 | 12 | 12 |  | 50 Ohms-3 | TOP=L2:L3=L2/L4:L6=L5/L7:BOTTOM=L7 |
| SSD6_CLK0_OE_MOS_N | 50OHM_Y12MIL | BUS | 8 | 6.75 | 5 | 10 | 5 | 14 | 6 | 15 | 12 | 12 | 12 | 12 |  | 50 Ohms-3 | TOP=L2:L3=L2/L4:L6=L5/L7:BOTTOM=L7 |
| SSD6_CLK0_OE_N | 50OHM_Y12MIL | BUS | 1 | 6.75 | 5 | 10 | 5 | 14 | 6 | 15 | 12 | 12 | 12 | 12 |  | 50 Ohms-3 | TOP=L2:L3=L2/L4:L6=L5/L7:BOTTOM=L7 |
| SSD6_CLK0_OE_N | 50OHM_Y12MIL | BUS | 2 | 6 | 5 | 10 | 5 | 14 | 6 | 15 | 12 | 12 | 12 | 12 |  | 50 Ohms-3 | TOP=L2:L3=L2/L4:L6=L5/L7:BOTTOM=L7 |
| SSD6_CLK0_OE_N | 50OHM_Y12MIL | BUS | 3 | 6 | 5 | 10 | 5 | 14 | 6 | 15 | 12 | 12 | 12 | 12 |  | 50 Ohms-3 | TOP=L2:L3=L2/L4:L6=L5/L7:BOTTOM=L7 |
| SSD6_CLK0_OE_N | 50OHM_Y12MIL | BUS | 4 | 6 | 5 | 10 | 5 | 14 | 6 | 15 | 12 | 12 | 12 | 12 |  | 50 Ohms-3 | TOP=L2:L3=L2/L4:L6=L5/L7:BOTTOM=L7 |
| SSD6_CLK0_OE_N | 50OHM_Y12MIL | BUS | 5 | 6 | 5 | 10 | 5 | 14 | 6 | 15 | 12 | 12 | 12 | 12 |  | 50 Ohms-3 | TOP=L2:L3=L2/L4:L6=L5/L7:BOTTOM=L7 |
| SSD6_CLK0_OE_N | 50OHM_Y12MIL | BUS | 6 | 6 | 5 | 10 | 5 | 14 | 6 | 15 | 12 | 12 | 12 | 12 |  | 50 Ohms-3 | TOP=L2:L3=L2/L4:L6=L5/L7:BOTTOM=L7 |
| SSD6_CLK0_OE_N | 50OHM_Y12MIL | BUS | 7 | 6 | 5 | 10 | 5 | 14 | 6 | 15 | 12 | 12 | 12 | 12 |  | 50 Ohms-3 | TOP=L2:L3=L2/L4:L6=L5/L7:BOTTOM=L7 |
| SSD6_CLK0_OE_N | 50OHM_Y12MIL | BUS | 8 | 6.75 | 5 | 10 | 5 | 14 | 6 | 15 | 12 | 12 | 12 | 12 |  | 50 Ohms-3 | TOP=L2:L3=L2/L4:L6=L5/L7:BOTTOM=L7 |
| SSD6_CLK0_OE_R_N | 50OHM_Y12MIL | BUS | 1 | 6.75 | 5 | 10 | 5 | 14 | 6 | 15 | 12 | 12 | 12 | 12 |  | 50 Ohms-3 | TOP=L2:L3=L2/L4:L6=L5/L7:BOTTOM=L7 |
| SSD6_CLK0_OE_R_N | 50OHM_Y12MIL | BUS | 2 | 6 | 5 | 10 | 5 | 14 | 6 | 15 | 12 | 12 | 12 | 12 |  | 50 Ohms-3 | TOP=L2:L3=L2/L4:L6=L5/L7:BOTTOM=L7 |
| SSD6_CLK0_OE_R_N | 50OHM_Y12MIL | BUS | 3 | 6 | 5 | 10 | 5 | 14 | 6 | 15 | 12 | 12 | 12 | 12 |  | 50 Ohms-3 | TOP=L2:L3=L2/L4:L6=L5/L7:BOTTOM=L7 |
| SSD6_CLK0_OE_R_N | 50OHM_Y12MIL | BUS | 4 | 6 | 5 | 10 | 5 | 14 | 6 | 15 | 12 | 12 | 12 | 12 |  | 50 Ohms-3 | TOP=L2:L3=L2/L4:L6=L5/L7:BOTTOM=L7 |
| SSD6_CLK0_OE_R_N | 50OHM_Y12MIL | BUS | 5 | 6 | 5 | 10 | 5 | 14 | 6 | 15 | 12 | 12 | 12 | 12 |  | 50 Ohms-3 | TOP=L2:L3=L2/L4:L6=L5/L7:BOTTOM=L7 |
| SSD6_CLK0_OE_R_N | 50OHM_Y12MIL | BUS | 6 | 6 | 5 | 10 | 5 | 14 | 6 | 15 | 12 | 12 | 12 | 12 |  | 50 Ohms-3 | TOP=L2:L3=L2/L4:L6=L5/L7:BOTTOM=L7 |
| SSD6_CLK0_OE_R_N | 50OHM_Y12MIL | BUS | 7 | 6 | 5 | 10 | 5 | 14 | 6 | 15 | 12 | 12 | 12 | 12 |  | 50 Ohms-3 | TOP=L2:L3=L2/L4:L6=L5/L7:BOTTOM=L7 |
| SSD6_CLK0_OE_R_N | 50OHM_Y12MIL | BUS | 8 | 6.75 | 5 | 10 | 5 | 14 | 6 | 15 | 12 | 12 | 12 | 12 |  | 50 Ohms-3 | TOP=L2:L3=L2/L4:L6=L5/L7:BOTTOM=L7 |
| SSD6_PERST_N | 50OHM_Y12MIL | BUS | 1 | 6.75 | 5 | 10 | 5 | 14 | 6 | 15 | 12 | 12 | 12 | 12 |  | 50 Ohms-3 | TOP=L2:L3=L2/L4:L6=L5/L7:BOTTOM=L7 |
| SSD6_PERST_N | 50OHM_Y12MIL | BUS | 2 | 6 | 5 | 10 | 5 | 14 | 6 | 15 | 12 | 12 | 12 | 12 |  | 50 Ohms-3 | TOP=L2:L3=L2/L4:L6=L5/L7:BOTTOM=L7 |
| SSD6_PERST_N | 50OHM_Y12MIL | BUS | 3 | 6 | 5 | 10 | 5 | 14 | 6 | 15 | 12 | 12 | 12 | 12 |  | 50 Ohms-3 | TOP=L2:L3=L2/L4:L6=L5/L7:BOTTOM=L7 |
| SSD6_PERST_N | 50OHM_Y12MIL | BUS | 4 | 6 | 5 | 10 | 5 | 14 | 6 | 15 | 12 | 12 | 12 | 12 |  | 50 Ohms-3 | TOP=L2:L3=L2/L4:L6=L5/L7:BOTTOM=L7 |
| SSD6_PERST_N | 50OHM_Y12MIL | BUS | 5 | 6 | 5 | 10 | 5 | 14 | 6 | 15 | 12 | 12 | 12 | 12 |  | 50 Ohms-3 | TOP=L2:L3=L2/L4:L6=L5/L7:BOTTOM=L7 |
| SSD6_PERST_N | 50OHM_Y12MIL | BUS | 6 | 6 | 5 | 10 | 5 | 14 | 6 | 15 | 12 | 12 | 12 | 12 |  | 50 Ohms-3 | TOP=L2:L3=L2/L4:L6=L5/L7:BOTTOM=L7 |
| SSD6_PERST_N | 50OHM_Y12MIL | BUS | 7 | 6 | 5 | 10 | 5 | 14 | 6 | 15 | 12 | 12 | 12 | 12 |  | 50 Ohms-3 | TOP=L2:L3=L2/L4:L6=L5/L7:BOTTOM=L7 |
| SSD6_PERST_N | 50OHM_Y12MIL | BUS | 8 | 6.75 | 5 | 10 | 5 | 14 | 6 | 15 | 12 | 12 | 12 | 12 |  | 50 Ohms-3 | TOP=L2:L3=L2/L4:L6=L5/L7:BOTTOM=L7 |
| SSD6_PWREN | 50OHM_Y12MIL | BUS | 1 | 6.75 | 5 | 10 | 5 | 14 | 6 | 15 | 12 | 12 | 12 | 12 |  | 50 Ohms-3 | TOP=L2:L3=L2/L4:L6=L5/L7:BOTTOM=L7 |
| SSD6_PWREN | 50OHM_Y12MIL | BUS | 2 | 6 | 5 | 10 | 5 | 14 | 6 | 15 | 12 | 12 | 12 | 12 |  | 50 Ohms-3 | TOP=L2:L3=L2/L4:L6=L5/L7:BOTTOM=L7 |
| SSD6_PWREN | 50OHM_Y12MIL | BUS | 3 | 6 | 5 | 10 | 5 | 14 | 6 | 15 | 12 | 12 | 12 | 12 |  | 50 Ohms-3 | TOP=L2:L3=L2/L4:L6=L5/L7:BOTTOM=L7 |
| SSD6_PWREN | 50OHM_Y12MIL | BUS | 4 | 6 | 5 | 10 | 5 | 14 | 6 | 15 | 12 | 12 | 12 | 12 |  | 50 Ohms-3 | TOP=L2:L3=L2/L4:L6=L5/L7:BOTTOM=L7 |
| SSD6_PWREN | 50OHM_Y12MIL | BUS | 5 | 6 | 5 | 10 | 5 | 14 | 6 | 15 | 12 | 12 | 12 | 12 |  | 50 Ohms-3 | TOP=L2:L3=L2/L4:L6=L5/L7:BOTTOM=L7 |
| SSD6_PWREN | 50OHM_Y12MIL | BUS | 6 | 6 | 5 | 10 | 5 | 14 | 6 | 15 | 12 | 12 | 12 | 12 |  | 50 Ohms-3 | TOP=L2:L3=L2/L4:L6=L5/L7:BOTTOM=L7 |
| SSD6_PWREN | 50OHM_Y12MIL | BUS | 7 | 6 | 5 | 10 | 5 | 14 | 6 | 15 | 12 | 12 | 12 | 12 |  | 50 Ohms-3 | TOP=L2:L3=L2/L4:L6=L5/L7:BOTTOM=L7 |
| SSD6_PWREN | 50OHM_Y12MIL | BUS | 8 | 6.75 | 5 | 10 | 5 | 14 | 6 | 15 | 12 | 12 | 12 | 12 |  | 50 Ohms-3 | TOP=L2:L3=L2/L4:L6=L5/L7:BOTTOM=L7 |
| SSD6_PWREN_R | 50OHM_Y12MIL | BUS | 1 | 6.75 | 5 | 10 | 5 | 14 | 6 | 15 | 12 | 12 | 12 | 12 |  | 50 Ohms-3 | TOP=L2:L3=L2/L4:L6=L5/L7:BOTTOM=L7 |
| SSD6_PWREN_R | 50OHM_Y12MIL | BUS | 2 | 6 | 5 | 10 | 5 | 14 | 6 | 15 | 12 | 12 | 12 | 12 |  | 50 Ohms-3 | TOP=L2:L3=L2/L4:L6=L5/L7:BOTTOM=L7 |
| SSD6_PWREN_R | 50OHM_Y12MIL | BUS | 3 | 6 | 5 | 10 | 5 | 14 | 6 | 15 | 12 | 12 | 12 | 12 |  | 50 Ohms-3 | TOP=L2:L3=L2/L4:L6=L5/L7:BOTTOM=L7 |
| SSD6_PWREN_R | 50OHM_Y12MIL | BUS | 4 | 6 | 5 | 10 | 5 | 14 | 6 | 15 | 12 | 12 | 12 | 12 |  | 50 Ohms-3 | TOP=L2:L3=L2/L4:L6=L5/L7:BOTTOM=L7 |
| SSD6_PWREN_R | 50OHM_Y12MIL | BUS | 5 | 6 | 5 | 10 | 5 | 14 | 6 | 15 | 12 | 12 | 12 | 12 |  | 50 Ohms-3 | TOP=L2:L3=L2/L4:L6=L5/L7:BOTTOM=L7 |
| SSD6_PWREN_R | 50OHM_Y12MIL | BUS | 6 | 6 | 5 | 10 | 5 | 14 | 6 | 15 | 12 | 12 | 12 | 12 |  | 50 Ohms-3 | TOP=L2:L3=L2/L4:L6=L5/L7:BOTTOM=L7 |
| SSD6_PWREN_R | 50OHM_Y12MIL | BUS | 7 | 6 | 5 | 10 | 5 | 14 | 6 | 15 | 12 | 12 | 12 | 12 |  | 50 Ohms-3 | TOP=L2:L3=L2/L4:L6=L5/L7:BOTTOM=L7 |
| SSD6_PWREN_R | 50OHM_Y12MIL | BUS | 8 | 6.75 | 5 | 10 | 5 | 14 | 6 | 15 | 12 | 12 | 12 | 12 |  | 50 Ohms-3 | TOP=L2:L3=L2/L4:L6=L5/L7:BOTTOM=L7 |
| SSD7_CLK0_OE_MOS_N | 50OHM_Y12MIL | BUS | 1 | 6.75 | 5 | 10 | 5 | 14 | 6 | 15 | 12 | 12 | 12 | 12 |  | 50 Ohms-3 | TOP=L2:L3=L2/L4:L6=L5/L7:BOTTOM=L7 |
| SSD7_CLK0_OE_MOS_N | 50OHM_Y12MIL | BUS | 2 | 6 | 5 | 10 | 5 | 14 | 6 | 15 | 12 | 12 | 12 | 12 |  | 50 Ohms-3 | TOP=L2:L3=L2/L4:L6=L5/L7:BOTTOM=L7 |
| SSD7_CLK0_OE_MOS_N | 50OHM_Y12MIL | BUS | 3 | 6 | 5 | 10 | 5 | 14 | 6 | 15 | 12 | 12 | 12 | 12 |  | 50 Ohms-3 | TOP=L2:L3=L2/L4:L6=L5/L7:BOTTOM=L7 |
| SSD7_CLK0_OE_MOS_N | 50OHM_Y12MIL | BUS | 4 | 6 | 5 | 10 | 5 | 14 | 6 | 15 | 12 | 12 | 12 | 12 |  | 50 Ohms-3 | TOP=L2:L3=L2/L4:L6=L5/L7:BOTTOM=L7 |
| SSD7_CLK0_OE_MOS_N | 50OHM_Y12MIL | BUS | 5 | 6 | 5 | 10 | 5 | 14 | 6 | 15 | 12 | 12 | 12 | 12 |  | 50 Ohms-3 | TOP=L2:L3=L2/L4:L6=L5/L7:BOTTOM=L7 |
| SSD7_CLK0_OE_MOS_N | 50OHM_Y12MIL | BUS | 6 | 6 | 5 | 10 | 5 | 14 | 6 | 15 | 12 | 12 | 12 | 12 |  | 50 Ohms-3 | TOP=L2:L3=L2/L4:L6=L5/L7:BOTTOM=L7 |
| SSD7_CLK0_OE_MOS_N | 50OHM_Y12MIL | BUS | 7 | 6 | 5 | 10 | 5 | 14 | 6 | 15 | 12 | 12 | 12 | 12 |  | 50 Ohms-3 | TOP=L2:L3=L2/L4:L6=L5/L7:BOTTOM=L7 |
| SSD7_CLK0_OE_MOS_N | 50OHM_Y12MIL | BUS | 8 | 6.75 | 5 | 10 | 5 | 14 | 6 | 15 | 12 | 12 | 12 | 12 |  | 50 Ohms-3 | TOP=L2:L3=L2/L4:L6=L5/L7:BOTTOM=L7 |
| SSD7_CLK0_OE_N | 50OHM_Y12MIL | BUS | 1 | 6.75 | 5 | 10 | 5 | 14 | 6 | 15 | 12 | 12 | 12 | 12 |  | 50 Ohms-3 | TOP=L2:L3=L2/L4:L6=L5/L7:BOTTOM=L7 |
| SSD7_CLK0_OE_N | 50OHM_Y12MIL | BUS | 2 | 6 | 5 | 10 | 5 | 14 | 6 | 15 | 12 | 12 | 12 | 12 |  | 50 Ohms-3 | TOP=L2:L3=L2/L4:L6=L5/L7:BOTTOM=L7 |
| SSD7_CLK0_OE_N | 50OHM_Y12MIL | BUS | 3 | 6 | 5 | 10 | 5 | 14 | 6 | 15 | 12 | 12 | 12 | 12 |  | 50 Ohms-3 | TOP=L2:L3=L2/L4:L6=L5/L7:BOTTOM=L7 |
| SSD7_CLK0_OE_N | 50OHM_Y12MIL | BUS | 4 | 6 | 5 | 10 | 5 | 14 | 6 | 15 | 12 | 12 | 12 | 12 |  | 50 Ohms-3 | TOP=L2:L3=L2/L4:L6=L5/L7:BOTTOM=L7 |
| SSD7_CLK0_OE_N | 50OHM_Y12MIL | BUS | 5 | 6 | 5 | 10 | 5 | 14 | 6 | 15 | 12 | 12 | 12 | 12 |  | 50 Ohms-3 | TOP=L2:L3=L2/L4:L6=L5/L7:BOTTOM=L7 |
| SSD7_CLK0_OE_N | 50OHM_Y12MIL | BUS | 6 | 6 | 5 | 10 | 5 | 14 | 6 | 15 | 12 | 12 | 12 | 12 |  | 50 Ohms-3 | TOP=L2:L3=L2/L4:L6=L5/L7:BOTTOM=L7 |
| SSD7_CLK0_OE_N | 50OHM_Y12MIL | BUS | 7 | 6 | 5 | 10 | 5 | 14 | 6 | 15 | 12 | 12 | 12 | 12 |  | 50 Ohms-3 | TOP=L2:L3=L2/L4:L6=L5/L7:BOTTOM=L7 |
| SSD7_CLK0_OE_N | 50OHM_Y12MIL | BUS | 8 | 6.75 | 5 | 10 | 5 | 14 | 6 | 15 | 12 | 12 | 12 | 12 |  | 50 Ohms-3 | TOP=L2:L3=L2/L4:L6=L5/L7:BOTTOM=L7 |
| SSD7_CLK0_OE_R_N | 50OHM_Y12MIL | BUS | 1 | 6.75 | 5 | 10 | 5 | 14 | 6 | 15 | 12 | 12 | 12 | 12 |  | 50 Ohms-3 | TOP=L2:L3=L2/L4:L6=L5/L7:BOTTOM=L7 |
| SSD7_CLK0_OE_R_N | 50OHM_Y12MIL | BUS | 2 | 6 | 5 | 10 | 5 | 14 | 6 | 15 | 12 | 12 | 12 | 12 |  | 50 Ohms-3 | TOP=L2:L3=L2/L4:L6=L5/L7:BOTTOM=L7 |
| SSD7_CLK0_OE_R_N | 50OHM_Y12MIL | BUS | 3 | 6 | 5 | 10 | 5 | 14 | 6 | 15 | 12 | 12 | 12 | 12 |  | 50 Ohms-3 | TOP=L2:L3=L2/L4:L6=L5/L7:BOTTOM=L7 |
| SSD7_CLK0_OE_R_N | 50OHM_Y12MIL | BUS | 4 | 6 | 5 | 10 | 5 | 14 | 6 | 15 | 12 | 12 | 12 | 12 |  | 50 Ohms-3 | TOP=L2:L3=L2/L4:L6=L5/L7:BOTTOM=L7 |
| SSD7_CLK0_OE_R_N | 50OHM_Y12MIL | BUS | 5 | 6 | 5 | 10 | 5 | 14 | 6 | 15 | 12 | 12 | 12 | 12 |  | 50 Ohms-3 | TOP=L2:L3=L2/L4:L6=L5/L7:BOTTOM=L7 |
| SSD7_CLK0_OE_R_N | 50OHM_Y12MIL | BUS | 6 | 6 | 5 | 10 | 5 | 14 | 6 | 15 | 12 | 12 | 12 | 12 |  | 50 Ohms-3 | TOP=L2:L3=L2/L4:L6=L5/L7:BOTTOM=L7 |
| SSD7_CLK0_OE_R_N | 50OHM_Y12MIL | BUS | 7 | 6 | 5 | 10 | 5 | 14 | 6 | 15 | 12 | 12 | 12 | 12 |  | 50 Ohms-3 | TOP=L2:L3=L2/L4:L6=L5/L7:BOTTOM=L7 |
| SSD7_CLK0_OE_R_N | 50OHM_Y12MIL | BUS | 8 | 6.75 | 5 | 10 | 5 | 14 | 6 | 15 | 12 | 12 | 12 | 12 |  | 50 Ohms-3 | TOP=L2:L3=L2/L4:L6=L5/L7:BOTTOM=L7 |
| SSD7_PERST_N | 50OHM_Y12MIL | BUS | 1 | 6.75 | 5 | 10 | 5 | 14 | 6 | 15 | 12 | 12 | 12 | 12 |  | 50 Ohms-3 | TOP=L2:L3=L2/L4:L6=L5/L7:BOTTOM=L7 |
| SSD7_PERST_N | 50OHM_Y12MIL | BUS | 2 | 6 | 5 | 10 | 5 | 14 | 6 | 15 | 12 | 12 | 12 | 12 |  | 50 Ohms-3 | TOP=L2:L3=L2/L4:L6=L5/L7:BOTTOM=L7 |
| SSD7_PERST_N | 50OHM_Y12MIL | BUS | 3 | 6 | 5 | 10 | 5 | 14 | 6 | 15 | 12 | 12 | 12 | 12 |  | 50 Ohms-3 | TOP=L2:L3=L2/L4:L6=L5/L7:BOTTOM=L7 |
| SSD7_PERST_N | 50OHM_Y12MIL | BUS | 4 | 6 | 5 | 10 | 5 | 14 | 6 | 15 | 12 | 12 | 12 | 12 |  | 50 Ohms-3 | TOP=L2:L3=L2/L4:L6=L5/L7:BOTTOM=L7 |
| SSD7_PERST_N | 50OHM_Y12MIL | BUS | 5 | 6 | 5 | 10 | 5 | 14 | 6 | 15 | 12 | 12 | 12 | 12 |  | 50 Ohms-3 | TOP=L2:L3=L2/L4:L6=L5/L7:BOTTOM=L7 |
| SSD7_PERST_N | 50OHM_Y12MIL | BUS | 6 | 6 | 5 | 10 | 5 | 14 | 6 | 15 | 12 | 12 | 12 | 12 |  | 50 Ohms-3 | TOP=L2:L3=L2/L4:L6=L5/L7:BOTTOM=L7 |
| SSD7_PERST_N | 50OHM_Y12MIL | BUS | 7 | 6 | 5 | 10 | 5 | 14 | 6 | 15 | 12 | 12 | 12 | 12 |  | 50 Ohms-3 | TOP=L2:L3=L2/L4:L6=L5/L7:BOTTOM=L7 |
| SSD7_PERST_N | 50OHM_Y12MIL | BUS | 8 | 6.75 | 5 | 10 | 5 | 14 | 6 | 15 | 12 | 12 | 12 | 12 |  | 50 Ohms-3 | TOP=L2:L3=L2/L4:L6=L5/L7:BOTTOM=L7 |
| SSD7_PWREN | 50OHM_Y12MIL | BUS | 1 | 6.75 | 5 | 10 | 5 | 14 | 6 | 15 | 12 | 12 | 12 | 12 |  | 50 Ohms-3 | TOP=L2:L3=L2/L4:L6=L5/L7:BOTTOM=L7 |
| SSD7_PWREN | 50OHM_Y12MIL | BUS | 2 | 6 | 5 | 10 | 5 | 14 | 6 | 15 | 12 | 12 | 12 | 12 |  | 50 Ohms-3 | TOP=L2:L3=L2/L4:L6=L5/L7:BOTTOM=L7 |
| SSD7_PWREN | 50OHM_Y12MIL | BUS | 3 | 6 | 5 | 10 | 5 | 14 | 6 | 15 | 12 | 12 | 12 | 12 |  | 50 Ohms-3 | TOP=L2:L3=L2/L4:L6=L5/L7:BOTTOM=L7 |
| SSD7_PWREN | 50OHM_Y12MIL | BUS | 4 | 6 | 5 | 10 | 5 | 14 | 6 | 15 | 12 | 12 | 12 | 12 |  | 50 Ohms-3 | TOP=L2:L3=L2/L4:L6=L5/L7:BOTTOM=L7 |
| SSD7_PWREN | 50OHM_Y12MIL | BUS | 5 | 6 | 5 | 10 | 5 | 14 | 6 | 15 | 12 | 12 | 12 | 12 |  | 50 Ohms-3 | TOP=L2:L3=L2/L4:L6=L5/L7:BOTTOM=L7 |
| SSD7_PWREN | 50OHM_Y12MIL | BUS | 6 | 6 | 5 | 10 | 5 | 14 | 6 | 15 | 12 | 12 | 12 | 12 |  | 50 Ohms-3 | TOP=L2:L3=L2/L4:L6=L5/L7:BOTTOM=L7 |
| SSD7_PWREN | 50OHM_Y12MIL | BUS | 7 | 6 | 5 | 10 | 5 | 14 | 6 | 15 | 12 | 12 | 12 | 12 |  | 50 Ohms-3 | TOP=L2:L3=L2/L4:L6=L5/L7:BOTTOM=L7 |
| SSD7_PWREN | 50OHM_Y12MIL | BUS | 8 | 6.75 | 5 | 10 | 5 | 14 | 6 | 15 | 12 | 12 | 12 | 12 |  | 50 Ohms-3 | TOP=L2:L3=L2/L4:L6=L5/L7:BOTTOM=L7 |
| SSD7_PWREN_R | 50OHM_Y12MIL | BUS | 1 | 6.75 | 5 | 10 | 5 | 14 | 6 | 15 | 12 | 12 | 12 | 12 |  | 50 Ohms-3 | TOP=L2:L3=L2/L4:L6=L5/L7:BOTTOM=L7 |
| SSD7_PWREN_R | 50OHM_Y12MIL | BUS | 2 | 6 | 5 | 10 | 5 | 14 | 6 | 15 | 12 | 12 | 12 | 12 |  | 50 Ohms-3 | TOP=L2:L3=L2/L4:L6=L5/L7:BOTTOM=L7 |
| SSD7_PWREN_R | 50OHM_Y12MIL | BUS | 3 | 6 | 5 | 10 | 5 | 14 | 6 | 15 | 12 | 12 | 12 | 12 |  | 50 Ohms-3 | TOP=L2:L3=L2/L4:L6=L5/L7:BOTTOM=L7 |
| SSD7_PWREN_R | 50OHM_Y12MIL | BUS | 4 | 6 | 5 | 10 | 5 | 14 | 6 | 15 | 12 | 12 | 12 | 12 |  | 50 Ohms-3 | TOP=L2:L3=L2/L4:L6=L5/L7:BOTTOM=L7 |
| SSD7_PWREN_R | 50OHM_Y12MIL | BUS | 5 | 6 | 5 | 10 | 5 | 14 | 6 | 15 | 12 | 12 | 12 | 12 |  | 50 Ohms-3 | TOP=L2:L3=L2/L4:L6=L5/L7:BOTTOM=L7 |
| SSD7_PWREN_R | 50OHM_Y12MIL | BUS | 6 | 6 | 5 | 10 | 5 | 14 | 6 | 15 | 12 | 12 | 12 | 12 |  | 50 Ohms-3 | TOP=L2:L3=L2/L4:L6=L5/L7:BOTTOM=L7 |
| SSD7_PWREN_R | 50OHM_Y12MIL | BUS | 7 | 6 | 5 | 10 | 5 | 14 | 6 | 15 | 12 | 12 | 12 | 12 |  | 50 Ohms-3 | TOP=L2:L3=L2/L4:L6=L5/L7:BOTTOM=L7 |
| SSD7_PWREN_R | 50OHM_Y12MIL | BUS | 8 | 6.75 | 5 | 10 | 5 | 14 | 6 | 15 | 12 | 12 | 12 | 12 |  | 50 Ohms-3 | TOP=L2:L3=L2/L4:L6=L5/L7:BOTTOM=L7 |
| SSD8_CLK0_OE_MOS_N | 50OHM_Y12MIL | BUS | 1 | 6.75 | 5 | 10 | 5 | 14 | 6 | 15 | 12 | 12 | 12 | 12 |  | 50 Ohms-3 | TOP=L2:L3=L2/L4:L6=L5/L7:BOTTOM=L7 |
| SSD8_CLK0_OE_MOS_N | 50OHM_Y12MIL | BUS | 2 | 6 | 5 | 10 | 5 | 14 | 6 | 15 | 12 | 12 | 12 | 12 |  | 50 Ohms-3 | TOP=L2:L3=L2/L4:L6=L5/L7:BOTTOM=L7 |
| SSD8_CLK0_OE_MOS_N | 50OHM_Y12MIL | BUS | 3 | 6 | 5 | 10 | 5 | 14 | 6 | 15 | 12 | 12 | 12 | 12 |  | 50 Ohms-3 | TOP=L2:L3=L2/L4:L6=L5/L7:BOTTOM=L7 |
| SSD8_CLK0_OE_MOS_N | 50OHM_Y12MIL | BUS | 4 | 6 | 5 | 10 | 5 | 14 | 6 | 15 | 12 | 12 | 12 | 12 |  | 50 Ohms-3 | TOP=L2:L3=L2/L4:L6=L5/L7:BOTTOM=L7 |
| SSD8_CLK0_OE_MOS_N | 50OHM_Y12MIL | BUS | 5 | 6 | 5 | 10 | 5 | 14 | 6 | 15 | 12 | 12 | 12 | 12 |  | 50 Ohms-3 | TOP=L2:L3=L2/L4:L6=L5/L7:BOTTOM=L7 |
| SSD8_CLK0_OE_MOS_N | 50OHM_Y12MIL | BUS | 6 | 6 | 5 | 10 | 5 | 14 | 6 | 15 | 12 | 12 | 12 | 12 |  | 50 Ohms-3 | TOP=L2:L3=L2/L4:L6=L5/L7:BOTTOM=L7 |
| SSD8_CLK0_OE_MOS_N | 50OHM_Y12MIL | BUS | 7 | 6 | 5 | 10 | 5 | 14 | 6 | 15 | 12 | 12 | 12 | 12 |  | 50 Ohms-3 | TOP=L2:L3=L2/L4:L6=L5/L7:BOTTOM=L7 |
| SSD8_CLK0_OE_MOS_N | 50OHM_Y12MIL | BUS | 8 | 6.75 | 5 | 10 | 5 | 14 | 6 | 15 | 12 | 12 | 12 | 12 |  | 50 Ohms-3 | TOP=L2:L3=L2/L4:L6=L5/L7:BOTTOM=L7 |
| SSD8_CLK0_OE_N | 50OHM_Y12MIL | BUS | 1 | 6.75 | 5 | 10 | 5 | 14 | 6 | 15 | 12 | 12 | 12 | 12 |  | 50 Ohms-3 | TOP=L2:L3=L2/L4:L6=L5/L7:BOTTOM=L7 |
| SSD8_CLK0_OE_N | 50OHM_Y12MIL | BUS | 2 | 6 | 5 | 10 | 5 | 14 | 6 | 15 | 12 | 12 | 12 | 12 |  | 50 Ohms-3 | TOP=L2:L3=L2/L4:L6=L5/L7:BOTTOM=L7 |
| SSD8_CLK0_OE_N | 50OHM_Y12MIL | BUS | 3 | 6 | 5 | 10 | 5 | 14 | 6 | 15 | 12 | 12 | 12 | 12 |  | 50 Ohms-3 | TOP=L2:L3=L2/L4:L6=L5/L7:BOTTOM=L7 |
| SSD8_CLK0_OE_N | 50OHM_Y12MIL | BUS | 4 | 6 | 5 | 10 | 5 | 14 | 6 | 15 | 12 | 12 | 12 | 12 |  | 50 Ohms-3 | TOP=L2:L3=L2/L4:L6=L5/L7:BOTTOM=L7 |
| SSD8_CLK0_OE_N | 50OHM_Y12MIL | BUS | 5 | 6 | 5 | 10 | 5 | 14 | 6 | 15 | 12 | 12 | 12 | 12 |  | 50 Ohms-3 | TOP=L2:L3=L2/L4:L6=L5/L7:BOTTOM=L7 |
| SSD8_CLK0_OE_N | 50OHM_Y12MIL | BUS | 6 | 6 | 5 | 10 | 5 | 14 | 6 | 15 | 12 | 12 | 12 | 12 |  | 50 Ohms-3 | TOP=L2:L3=L2/L4:L6=L5/L7:BOTTOM=L7 |
| SSD8_CLK0_OE_N | 50OHM_Y12MIL | BUS | 7 | 6 | 5 | 10 | 5 | 14 | 6 | 15 | 12 | 12 | 12 | 12 |  | 50 Ohms-3 | TOP=L2:L3=L2/L4:L6=L5/L7:BOTTOM=L7 |
| SSD8_CLK0_OE_N | 50OHM_Y12MIL | BUS | 8 | 6.75 | 5 | 10 | 5 | 14 | 6 | 15 | 12 | 12 | 12 | 12 |  | 50 Ohms-3 | TOP=L2:L3=L2/L4:L6=L5/L7:BOTTOM=L7 |
| SSD8_CLK0_OE_R_N | 50OHM_Y12MIL | BUS | 1 | 6.75 | 5 | 10 | 5 | 14 | 6 | 15 | 12 | 12 | 12 | 12 |  | 50 Ohms-3 | TOP=L2:L3=L2/L4:L6=L5/L7:BOTTOM=L7 |
| SSD8_CLK0_OE_R_N | 50OHM_Y12MIL | BUS | 2 | 6 | 5 | 10 | 5 | 14 | 6 | 15 | 12 | 12 | 12 | 12 |  | 50 Ohms-3 | TOP=L2:L3=L2/L4:L6=L5/L7:BOTTOM=L7 |
| SSD8_CLK0_OE_R_N | 50OHM_Y12MIL | BUS | 3 | 6 | 5 | 10 | 5 | 14 | 6 | 15 | 12 | 12 | 12 | 12 |  | 50 Ohms-3 | TOP=L2:L3=L2/L4:L6=L5/L7:BOTTOM=L7 |
| SSD8_CLK0_OE_R_N | 50OHM_Y12MIL | BUS | 4 | 6 | 5 | 10 | 5 | 14 | 6 | 15 | 12 | 12 | 12 | 12 |  | 50 Ohms-3 | TOP=L2:L3=L2/L4:L6=L5/L7:BOTTOM=L7 |
| SSD8_CLK0_OE_R_N | 50OHM_Y12MIL | BUS | 5 | 6 | 5 | 10 | 5 | 14 | 6 | 15 | 12 | 12 | 12 | 12 |  | 50 Ohms-3 | TOP=L2:L3=L2/L4:L6=L5/L7:BOTTOM=L7 |
| SSD8_CLK0_OE_R_N | 50OHM_Y12MIL | BUS | 6 | 6 | 5 | 10 | 5 | 14 | 6 | 15 | 12 | 12 | 12 | 12 |  | 50 Ohms-3 | TOP=L2:L3=L2/L4:L6=L5/L7:BOTTOM=L7 |
| SSD8_CLK0_OE_R_N | 50OHM_Y12MIL | BUS | 7 | 6 | 5 | 10 | 5 | 14 | 6 | 15 | 12 | 12 | 12 | 12 |  | 50 Ohms-3 | TOP=L2:L3=L2/L4:L6=L5/L7:BOTTOM=L7 |
| SSD8_CLK0_OE_R_N | 50OHM_Y12MIL | BUS | 8 | 6.75 | 5 | 10 | 5 | 14 | 6 | 15 | 12 | 12 | 12 | 12 |  | 50 Ohms-3 | TOP=L2:L3=L2/L4:L6=L5/L7:BOTTOM=L7 |
| SSD8_PERST_N | 50OHM_Y12MIL | BUS | 1 | 6.75 | 5 | 10 | 5 | 14 | 6 | 15 | 12 | 12 | 12 | 12 |  | 50 Ohms-3 | TOP=L2:L3=L2/L4:L6=L5/L7:BOTTOM=L7 |
| SSD8_PERST_N | 50OHM_Y12MIL | BUS | 2 | 6 | 5 | 10 | 5 | 14 | 6 | 15 | 12 | 12 | 12 | 12 |  | 50 Ohms-3 | TOP=L2:L3=L2/L4:L6=L5/L7:BOTTOM=L7 |
| SSD8_PERST_N | 50OHM_Y12MIL | BUS | 3 | 6 | 5 | 10 | 5 | 14 | 6 | 15 | 12 | 12 | 12 | 12 |  | 50 Ohms-3 | TOP=L2:L3=L2/L4:L6=L5/L7:BOTTOM=L7 |
| SSD8_PERST_N | 50OHM_Y12MIL | BUS | 4 | 6 | 5 | 10 | 5 | 14 | 6 | 15 | 12 | 12 | 12 | 12 |  | 50 Ohms-3 | TOP=L2:L3=L2/L4:L6=L5/L7:BOTTOM=L7 |
| SSD8_PERST_N | 50OHM_Y12MIL | BUS | 5 | 6 | 5 | 10 | 5 | 14 | 6 | 15 | 12 | 12 | 12 | 12 |  | 50 Ohms-3 | TOP=L2:L3=L2/L4:L6=L5/L7:BOTTOM=L7 |
| SSD8_PERST_N | 50OHM_Y12MIL | BUS | 6 | 6 | 5 | 10 | 5 | 14 | 6 | 15 | 12 | 12 | 12 | 12 |  | 50 Ohms-3 | TOP=L2:L3=L2/L4:L6=L5/L7:BOTTOM=L7 |
| SSD8_PERST_N | 50OHM_Y12MIL | BUS | 7 | 6 | 5 | 10 | 5 | 14 | 6 | 15 | 12 | 12 | 12 | 12 |  | 50 Ohms-3 | TOP=L2:L3=L2/L4:L6=L5/L7:BOTTOM=L7 |
| SSD8_PERST_N | 50OHM_Y12MIL | BUS | 8 | 6.75 | 5 | 10 | 5 | 14 | 6 | 15 | 12 | 12 | 12 | 12 |  | 50 Ohms-3 | TOP=L2:L3=L2/L4:L6=L5/L7:BOTTOM=L7 |
| SSD8_PWREN | 50OHM_Y12MIL | BUS | 1 | 6.75 | 5 | 10 | 5 | 14 | 6 | 15 | 12 | 12 | 12 | 12 |  | 50 Ohms-3 | TOP=L2:L3=L2/L4:L6=L5/L7:BOTTOM=L7 |
| SSD8_PWREN | 50OHM_Y12MIL | BUS | 2 | 6 | 5 | 10 | 5 | 14 | 6 | 15 | 12 | 12 | 12 | 12 |  | 50 Ohms-3 | TOP=L2:L3=L2/L4:L6=L5/L7:BOTTOM=L7 |
| SSD8_PWREN | 50OHM_Y12MIL | BUS | 3 | 6 | 5 | 10 | 5 | 14 | 6 | 15 | 12 | 12 | 12 | 12 |  | 50 Ohms-3 | TOP=L2:L3=L2/L4:L6=L5/L7:BOTTOM=L7 |
| SSD8_PWREN | 50OHM_Y12MIL | BUS | 4 | 6 | 5 | 10 | 5 | 14 | 6 | 15 | 12 | 12 | 12 | 12 |  | 50 Ohms-3 | TOP=L2:L3=L2/L4:L6=L5/L7:BOTTOM=L7 |
| SSD8_PWREN | 50OHM_Y12MIL | BUS | 5 | 6 | 5 | 10 | 5 | 14 | 6 | 15 | 12 | 12 | 12 | 12 |  | 50 Ohms-3 | TOP=L2:L3=L2/L4:L6=L5/L7:BOTTOM=L7 |
| SSD8_PWREN | 50OHM_Y12MIL | BUS | 6 | 6 | 5 | 10 | 5 | 14 | 6 | 15 | 12 | 12 | 12 | 12 |  | 50 Ohms-3 | TOP=L2:L3=L2/L4:L6=L5/L7:BOTTOM=L7 |
| SSD8_PWREN | 50OHM_Y12MIL | BUS | 7 | 6 | 5 | 10 | 5 | 14 | 6 | 15 | 12 | 12 | 12 | 12 |  | 50 Ohms-3 | TOP=L2:L3=L2/L4:L6=L5/L7:BOTTOM=L7 |
| SSD8_PWREN | 50OHM_Y12MIL | BUS | 8 | 6.75 | 5 | 10 | 5 | 14 | 6 | 15 | 12 | 12 | 12 | 12 |  | 50 Ohms-3 | TOP=L2:L3=L2/L4:L6=L5/L7:BOTTOM=L7 |
| SSD8_PWREN_R | 50OHM_Y12MIL | BUS | 1 | 6.75 | 5 | 10 | 5 | 14 | 6 | 15 | 12 | 12 | 12 | 12 |  | 50 Ohms-3 | TOP=L2:L3=L2/L4:L6=L5/L7:BOTTOM=L7 |
| SSD8_PWREN_R | 50OHM_Y12MIL | BUS | 2 | 6 | 5 | 10 | 5 | 14 | 6 | 15 | 12 | 12 | 12 | 12 |  | 50 Ohms-3 | TOP=L2:L3=L2/L4:L6=L5/L7:BOTTOM=L7 |
| SSD8_PWREN_R | 50OHM_Y12MIL | BUS | 3 | 6 | 5 | 10 | 5 | 14 | 6 | 15 | 12 | 12 | 12 | 12 |  | 50 Ohms-3 | TOP=L2:L3=L2/L4:L6=L5/L7:BOTTOM=L7 |
| SSD8_PWREN_R | 50OHM_Y12MIL | BUS | 4 | 6 | 5 | 10 | 5 | 14 | 6 | 15 | 12 | 12 | 12 | 12 |  | 50 Ohms-3 | TOP=L2:L3=L2/L4:L6=L5/L7:BOTTOM=L7 |
| SSD8_PWREN_R | 50OHM_Y12MIL | BUS | 5 | 6 | 5 | 10 | 5 | 14 | 6 | 15 | 12 | 12 | 12 | 12 |  | 50 Ohms-3 | TOP=L2:L3=L2/L4:L6=L5/L7:BOTTOM=L7 |
| SSD8_PWREN_R | 50OHM_Y12MIL | BUS | 6 | 6 | 5 | 10 | 5 | 14 | 6 | 15 | 12 | 12 | 12 | 12 |  | 50 Ohms-3 | TOP=L2:L3=L2/L4:L6=L5/L7:BOTTOM=L7 |
| SSD8_PWREN_R | 50OHM_Y12MIL | BUS | 7 | 6 | 5 | 10 | 5 | 14 | 6 | 15 | 12 | 12 | 12 | 12 |  | 50 Ohms-3 | TOP=L2:L3=L2/L4:L6=L5/L7:BOTTOM=L7 |
| SSD8_PWREN_R | 50OHM_Y12MIL | BUS | 8 | 6.75 | 5 | 10 | 5 | 14 | 6 | 15 | 12 | 12 | 12 | 12 |  | 50 Ohms-3 | TOP=L2:L3=L2/L4:L6=L5/L7:BOTTOM=L7 |
| SSD9_CLK0_OE_MOS_N | 50OHM_Y12MIL | BUS | 1 | 6.75 | 5 | 10 | 5 | 14 | 6 | 15 | 12 | 12 | 12 | 12 |  | 50 Ohms-3 | TOP=L2:L3=L2/L4:L6=L5/L7:BOTTOM=L7 |
| SSD9_CLK0_OE_MOS_N | 50OHM_Y12MIL | BUS | 2 | 6 | 5 | 10 | 5 | 14 | 6 | 15 | 12 | 12 | 12 | 12 |  | 50 Ohms-3 | TOP=L2:L3=L2/L4:L6=L5/L7:BOTTOM=L7 |
| SSD9_CLK0_OE_MOS_N | 50OHM_Y12MIL | BUS | 3 | 6 | 5 | 10 | 5 | 14 | 6 | 15 | 12 | 12 | 12 | 12 |  | 50 Ohms-3 | TOP=L2:L3=L2/L4:L6=L5/L7:BOTTOM=L7 |
| SSD9_CLK0_OE_MOS_N | 50OHM_Y12MIL | BUS | 4 | 6 | 5 | 10 | 5 | 14 | 6 | 15 | 12 | 12 | 12 | 12 |  | 50 Ohms-3 | TOP=L2:L3=L2/L4:L6=L5/L7:BOTTOM=L7 |
| SSD9_CLK0_OE_MOS_N | 50OHM_Y12MIL | BUS | 5 | 6 | 5 | 10 | 5 | 14 | 6 | 15 | 12 | 12 | 12 | 12 |  | 50 Ohms-3 | TOP=L2:L3=L2/L4:L6=L5/L7:BOTTOM=L7 |
| SSD9_CLK0_OE_MOS_N | 50OHM_Y12MIL | BUS | 6 | 6 | 5 | 10 | 5 | 14 | 6 | 15 | 12 | 12 | 12 | 12 |  | 50 Ohms-3 | TOP=L2:L3=L2/L4:L6=L5/L7:BOTTOM=L7 |
| SSD9_CLK0_OE_MOS_N | 50OHM_Y12MIL | BUS | 7 | 6 | 5 | 10 | 5 | 14 | 6 | 15 | 12 | 12 | 12 | 12 |  | 50 Ohms-3 | TOP=L2:L3=L2/L4:L6=L5/L7:BOTTOM=L7 |
| SSD9_CLK0_OE_MOS_N | 50OHM_Y12MIL | BUS | 8 | 6.75 | 5 | 10 | 5 | 14 | 6 | 15 | 12 | 12 | 12 | 12 |  | 50 Ohms-3 | TOP=L2:L3=L2/L4:L6=L5/L7:BOTTOM=L7 |
| SSD9_CLK0_OE_N | 50OHM_Y12MIL | BUS | 1 | 6.75 | 5 | 10 | 5 | 14 | 6 | 15 | 12 | 12 | 12 | 12 |  | 50 Ohms-3 | TOP=L2:L3=L2/L4:L6=L5/L7:BOTTOM=L7 |
| SSD9_CLK0_OE_N | 50OHM_Y12MIL | BUS | 2 | 6 | 5 | 10 | 5 | 14 | 6 | 15 | 12 | 12 | 12 | 12 |  | 50 Ohms-3 | TOP=L2:L3=L2/L4:L6=L5/L7:BOTTOM=L7 |
| SSD9_CLK0_OE_N | 50OHM_Y12MIL | BUS | 3 | 6 | 5 | 10 | 5 | 14 | 6 | 15 | 12 | 12 | 12 | 12 |  | 50 Ohms-3 | TOP=L2:L3=L2/L4:L6=L5/L7:BOTTOM=L7 |
| SSD9_CLK0_OE_N | 50OHM_Y12MIL | BUS | 4 | 6 | 5 | 10 | 5 | 14 | 6 | 15 | 12 | 12 | 12 | 12 |  | 50 Ohms-3 | TOP=L2:L3=L2/L4:L6=L5/L7:BOTTOM=L7 |
| SSD9_CLK0_OE_N | 50OHM_Y12MIL | BUS | 5 | 6 | 5 | 10 | 5 | 14 | 6 | 15 | 12 | 12 | 12 | 12 |  | 50 Ohms-3 | TOP=L2:L3=L2/L4:L6=L5/L7:BOTTOM=L7 |
| SSD9_CLK0_OE_N | 50OHM_Y12MIL | BUS | 6 | 6 | 5 | 10 | 5 | 14 | 6 | 15 | 12 | 12 | 12 | 12 |  | 50 Ohms-3 | TOP=L2:L3=L2/L4:L6=L5/L7:BOTTOM=L7 |
| SSD9_CLK0_OE_N | 50OHM_Y12MIL | BUS | 7 | 6 | 5 | 10 | 5 | 14 | 6 | 15 | 12 | 12 | 12 | 12 |  | 50 Ohms-3 | TOP=L2:L3=L2/L4:L6=L5/L7:BOTTOM=L7 |
| SSD9_CLK0_OE_N | 50OHM_Y12MIL | BUS | 8 | 6.75 | 5 | 10 | 5 | 14 | 6 | 15 | 12 | 12 | 12 | 12 |  | 50 Ohms-3 | TOP=L2:L3=L2/L4:L6=L5/L7:BOTTOM=L7 |
| SSD9_CLK0_OE_R_N | 50OHM_Y12MIL | BUS | 1 | 6.75 | 5 | 10 | 5 | 14 | 6 | 15 | 12 | 12 | 12 | 12 |  | 50 Ohms-3 | TOP=L2:L3=L2/L4:L6=L5/L7:BOTTOM=L7 |
| SSD9_CLK0_OE_R_N | 50OHM_Y12MIL | BUS | 2 | 6 | 5 | 10 | 5 | 14 | 6 | 15 | 12 | 12 | 12 | 12 |  | 50 Ohms-3 | TOP=L2:L3=L2/L4:L6=L5/L7:BOTTOM=L7 |
| SSD9_CLK0_OE_R_N | 50OHM_Y12MIL | BUS | 3 | 6 | 5 | 10 | 5 | 14 | 6 | 15 | 12 | 12 | 12 | 12 |  | 50 Ohms-3 | TOP=L2:L3=L2/L4:L6=L5/L7:BOTTOM=L7 |
| SSD9_CLK0_OE_R_N | 50OHM_Y12MIL | BUS | 4 | 6 | 5 | 10 | 5 | 14 | 6 | 15 | 12 | 12 | 12 | 12 |  | 50 Ohms-3 | TOP=L2:L3=L2/L4:L6=L5/L7:BOTTOM=L7 |
| SSD9_CLK0_OE_R_N | 50OHM_Y12MIL | BUS | 5 | 6 | 5 | 10 | 5 | 14 | 6 | 15 | 12 | 12 | 12 | 12 |  | 50 Ohms-3 | TOP=L2:L3=L2/L4:L6=L5/L7:BOTTOM=L7 |
| SSD9_CLK0_OE_R_N | 50OHM_Y12MIL | BUS | 6 | 6 | 5 | 10 | 5 | 14 | 6 | 15 | 12 | 12 | 12 | 12 |  | 50 Ohms-3 | TOP=L2:L3=L2/L4:L6=L5/L7:BOTTOM=L7 |
| SSD9_CLK0_OE_R_N | 50OHM_Y12MIL | BUS | 7 | 6 | 5 | 10 | 5 | 14 | 6 | 15 | 12 | 12 | 12 | 12 |  | 50 Ohms-3 | TOP=L2:L3=L2/L4:L6=L5/L7:BOTTOM=L7 |
| SSD9_CLK0_OE_R_N | 50OHM_Y12MIL | BUS | 8 | 6.75 | 5 | 10 | 5 | 14 | 6 | 15 | 12 | 12 | 12 | 12 |  | 50 Ohms-3 | TOP=L2:L3=L2/L4:L6=L5/L7:BOTTOM=L7 |
| SSD9_PERST_N | 50OHM_Y12MIL | BUS | 1 | 6.75 | 5 | 10 | 5 | 14 | 6 | 15 | 12 | 12 | 12 | 12 |  | 50 Ohms-3 | TOP=L2:L3=L2/L4:L6=L5/L7:BOTTOM=L7 |
| SSD9_PERST_N | 50OHM_Y12MIL | BUS | 2 | 6 | 5 | 10 | 5 | 14 | 6 | 15 | 12 | 12 | 12 | 12 |  | 50 Ohms-3 | TOP=L2:L3=L2/L4:L6=L5/L7:BOTTOM=L7 |
| SSD9_PERST_N | 50OHM_Y12MIL | BUS | 3 | 6 | 5 | 10 | 5 | 14 | 6 | 15 | 12 | 12 | 12 | 12 |  | 50 Ohms-3 | TOP=L2:L3=L2/L4:L6=L5/L7:BOTTOM=L7 |
| SSD9_PERST_N | 50OHM_Y12MIL | BUS | 4 | 6 | 5 | 10 | 5 | 14 | 6 | 15 | 12 | 12 | 12 | 12 |  | 50 Ohms-3 | TOP=L2:L3=L2/L4:L6=L5/L7:BOTTOM=L7 |
| SSD9_PERST_N | 50OHM_Y12MIL | BUS | 5 | 6 | 5 | 10 | 5 | 14 | 6 | 15 | 12 | 12 | 12 | 12 |  | 50 Ohms-3 | TOP=L2:L3=L2/L4:L6=L5/L7:BOTTOM=L7 |
| SSD9_PERST_N | 50OHM_Y12MIL | BUS | 6 | 6 | 5 | 10 | 5 | 14 | 6 | 15 | 12 | 12 | 12 | 12 |  | 50 Ohms-3 | TOP=L2:L3=L2/L4:L6=L5/L7:BOTTOM=L7 |
| SSD9_PERST_N | 50OHM_Y12MIL | BUS | 7 | 6 | 5 | 10 | 5 | 14 | 6 | 15 | 12 | 12 | 12 | 12 |  | 50 Ohms-3 | TOP=L2:L3=L2/L4:L6=L5/L7:BOTTOM=L7 |
| SSD9_PERST_N | 50OHM_Y12MIL | BUS | 8 | 6.75 | 5 | 10 | 5 | 14 | 6 | 15 | 12 | 12 | 12 | 12 |  | 50 Ohms-3 | TOP=L2:L3=L2/L4:L6=L5/L7:BOTTOM=L7 |
| SSD9_PWREN | 50OHM_Y12MIL | BUS | 1 | 6.75 | 5 | 10 | 5 | 14 | 6 | 15 | 12 | 12 | 12 | 12 |  | 50 Ohms-3 | TOP=L2:L3=L2/L4:L6=L5/L7:BOTTOM=L7 |
| SSD9_PWREN | 50OHM_Y12MIL | BUS | 2 | 6 | 5 | 10 | 5 | 14 | 6 | 15 | 12 | 12 | 12 | 12 |  | 50 Ohms-3 | TOP=L2:L3=L2/L4:L6=L5/L7:BOTTOM=L7 |
| SSD9_PWREN | 50OHM_Y12MIL | BUS | 3 | 6 | 5 | 10 | 5 | 14 | 6 | 15 | 12 | 12 | 12 | 12 |  | 50 Ohms-3 | TOP=L2:L3=L2/L4:L6=L5/L7:BOTTOM=L7 |
| SSD9_PWREN | 50OHM_Y12MIL | BUS | 4 | 6 | 5 | 10 | 5 | 14 | 6 | 15 | 12 | 12 | 12 | 12 |  | 50 Ohms-3 | TOP=L2:L3=L2/L4:L6=L5/L7:BOTTOM=L7 |
| SSD9_PWREN | 50OHM_Y12MIL | BUS | 5 | 6 | 5 | 10 | 5 | 14 | 6 | 15 | 12 | 12 | 12 | 12 |  | 50 Ohms-3 | TOP=L2:L3=L2/L4:L6=L5/L7:BOTTOM=L7 |
| SSD9_PWREN | 50OHM_Y12MIL | BUS | 6 | 6 | 5 | 10 | 5 | 14 | 6 | 15 | 12 | 12 | 12 | 12 |  | 50 Ohms-3 | TOP=L2:L3=L2/L4:L6=L5/L7:BOTTOM=L7 |
| SSD9_PWREN | 50OHM_Y12MIL | BUS | 7 | 6 | 5 | 10 | 5 | 14 | 6 | 15 | 12 | 12 | 12 | 12 |  | 50 Ohms-3 | TOP=L2:L3=L2/L4:L6=L5/L7:BOTTOM=L7 |
| SSD9_PWREN | 50OHM_Y12MIL | BUS | 8 | 6.75 | 5 | 10 | 5 | 14 | 6 | 15 | 12 | 12 | 12 | 12 |  | 50 Ohms-3 | TOP=L2:L3=L2/L4:L6=L5/L7:BOTTOM=L7 |
| SSD9_PWREN_R | 50OHM_Y12MIL | BUS | 1 | 6.75 | 5 | 10 | 5 | 14 | 6 | 15 | 12 | 12 | 12 | 12 |  | 50 Ohms-3 | TOP=L2:L3=L2/L4:L6=L5/L7:BOTTOM=L7 |
| SSD9_PWREN_R | 50OHM_Y12MIL | BUS | 2 | 6 | 5 | 10 | 5 | 14 | 6 | 15 | 12 | 12 | 12 | 12 |  | 50 Ohms-3 | TOP=L2:L3=L2/L4:L6=L5/L7:BOTTOM=L7 |
| SSD9_PWREN_R | 50OHM_Y12MIL | BUS | 3 | 6 | 5 | 10 | 5 | 14 | 6 | 15 | 12 | 12 | 12 | 12 |  | 50 Ohms-3 | TOP=L2:L3=L2/L4:L6=L5/L7:BOTTOM=L7 |
| SSD9_PWREN_R | 50OHM_Y12MIL | BUS | 4 | 6 | 5 | 10 | 5 | 14 | 6 | 15 | 12 | 12 | 12 | 12 |  | 50 Ohms-3 | TOP=L2:L3=L2/L4:L6=L5/L7:BOTTOM=L7 |
| SSD9_PWREN_R | 50OHM_Y12MIL | BUS | 5 | 6 | 5 | 10 | 5 | 14 | 6 | 15 | 12 | 12 | 12 | 12 |  | 50 Ohms-3 | TOP=L2:L3=L2/L4:L6=L5/L7:BOTTOM=L7 |
| SSD9_PWREN_R | 50OHM_Y12MIL | BUS | 6 | 6 | 5 | 10 | 5 | 14 | 6 | 15 | 12 | 12 | 12 | 12 |  | 50 Ohms-3 | TOP=L2:L3=L2/L4:L6=L5/L7:BOTTOM=L7 |
| SSD9_PWREN_R | 50OHM_Y12MIL | BUS | 7 | 6 | 5 | 10 | 5 | 14 | 6 | 15 | 12 | 12 | 12 | 12 |  | 50 Ohms-3 | TOP=L2:L3=L2/L4:L6=L5/L7:BOTTOM=L7 |
| SSD9_PWREN_R | 50OHM_Y12MIL | BUS | 8 | 6.75 | 5 | 10 | 5 | 14 | 6 | 15 | 12 | 12 | 12 | 12 |  | 50 Ohms-3 | TOP=L2:L3=L2/L4:L6=L5/L7:BOTTOM=L7 |
| SW_SSD0_N | 50OHM_Y12MIL | BUS | 1 | 6.75 | 5 | 10 | 5 | 14 | 6 | 15 | 12 | 12 | 12 | 12 |  | 50 Ohms-3 | TOP=L2:L3=L2/L4:L6=L5/L7:BOTTOM=L7 |
| SW_SSD0_N | 50OHM_Y12MIL | BUS | 2 | 6 | 5 | 10 | 5 | 14 | 6 | 15 | 12 | 12 | 12 | 12 |  | 50 Ohms-3 | TOP=L2:L3=L2/L4:L6=L5/L7:BOTTOM=L7 |
| SW_SSD0_N | 50OHM_Y12MIL | BUS | 3 | 6 | 5 | 10 | 5 | 14 | 6 | 15 | 12 | 12 | 12 | 12 |  | 50 Ohms-3 | TOP=L2:L3=L2/L4:L6=L5/L7:BOTTOM=L7 |
| SW_SSD0_N | 50OHM_Y12MIL | BUS | 4 | 6 | 5 | 10 | 5 | 14 | 6 | 15 | 12 | 12 | 12 | 12 |  | 50 Ohms-3 | TOP=L2:L3=L2/L4:L6=L5/L7:BOTTOM=L7 |
| SW_SSD0_N | 50OHM_Y12MIL | BUS | 5 | 6 | 5 | 10 | 5 | 14 | 6 | 15 | 12 | 12 | 12 | 12 |  | 50 Ohms-3 | TOP=L2:L3=L2/L4:L6=L5/L7:BOTTOM=L7 |
| SW_SSD0_N | 50OHM_Y12MIL | BUS | 6 | 6 | 5 | 10 | 5 | 14 | 6 | 15 | 12 | 12 | 12 | 12 |  | 50 Ohms-3 | TOP=L2:L3=L2/L4:L6=L5/L7:BOTTOM=L7 |
| SW_SSD0_N | 50OHM_Y12MIL | BUS | 7 | 6 | 5 | 10 | 5 | 14 | 6 | 15 | 12 | 12 | 12 | 12 |  | 50 Ohms-3 | TOP=L2:L3=L2/L4:L6=L5/L7:BOTTOM=L7 |
| SW_SSD0_N | 50OHM_Y12MIL | BUS | 8 | 6.75 | 5 | 10 | 5 | 14 | 6 | 15 | 12 | 12 | 12 | 12 |  | 50 Ohms-3 | TOP=L2:L3=L2/L4:L6=L5/L7:BOTTOM=L7 |
| SW_SSD0_R | 50OHM_Y12MIL | BUS | 1 | 6.75 | 5 | 10 | 5 | 14 | 6 | 15 | 12 | 12 | 12 | 12 |  | 50 Ohms-3 | TOP=L2:L3=L2/L4:L6=L5/L7:BOTTOM=L7 |
| SW_SSD0_R | 50OHM_Y12MIL | BUS | 2 | 6 | 5 | 10 | 5 | 14 | 6 | 15 | 12 | 12 | 12 | 12 |  | 50 Ohms-3 | TOP=L2:L3=L2/L4:L6=L5/L7:BOTTOM=L7 |
| SW_SSD0_R | 50OHM_Y12MIL | BUS | 3 | 6 | 5 | 10 | 5 | 14 | 6 | 15 | 12 | 12 | 12 | 12 |  | 50 Ohms-3 | TOP=L2:L3=L2/L4:L6=L5/L7:BOTTOM=L7 |
| SW_SSD0_R | 50OHM_Y12MIL | BUS | 4 | 6 | 5 | 10 | 5 | 14 | 6 | 15 | 12 | 12 | 12 | 12 |  | 50 Ohms-3 | TOP=L2:L3=L2/L4:L6=L5/L7:BOTTOM=L7 |
| SW_SSD0_R | 50OHM_Y12MIL | BUS | 5 | 6 | 5 | 10 | 5 | 14 | 6 | 15 | 12 | 12 | 12 | 12 |  | 50 Ohms-3 | TOP=L2:L3=L2/L4:L6=L5/L7:BOTTOM=L7 |
| SW_SSD0_R | 50OHM_Y12MIL | BUS | 6 | 6 | 5 | 10 | 5 | 14 | 6 | 15 | 12 | 12 | 12 | 12 |  | 50 Ohms-3 | TOP=L2:L3=L2/L4:L6=L5/L7:BOTTOM=L7 |
| SW_SSD0_R | 50OHM_Y12MIL | BUS | 7 | 6 | 5 | 10 | 5 | 14 | 6 | 15 | 12 | 12 | 12 | 12 |  | 50 Ohms-3 | TOP=L2:L3=L2/L4:L6=L5/L7:BOTTOM=L7 |
| SW_SSD0_R | 50OHM_Y12MIL | BUS | 8 | 6.75 | 5 | 10 | 5 | 14 | 6 | 15 | 12 | 12 | 12 | 12 |  | 50 Ohms-3 | TOP=L2:L3=L2/L4:L6=L5/L7:BOTTOM=L7 |
| SW_SSD1_N | 50OHM_Y12MIL | BUS | 1 | 6.75 | 5 | 10 | 5 | 14 | 6 | 15 | 12 | 12 | 12 | 12 |  | 50 Ohms-3 | TOP=L2:L3=L2/L4:L6=L5/L7:BOTTOM=L7 |
| SW_SSD1_N | 50OHM_Y12MIL | BUS | 2 | 6 | 5 | 10 | 5 | 14 | 6 | 15 | 12 | 12 | 12 | 12 |  | 50 Ohms-3 | TOP=L2:L3=L2/L4:L6=L5/L7:BOTTOM=L7 |
| SW_SSD1_N | 50OHM_Y12MIL | BUS | 3 | 6 | 5 | 10 | 5 | 14 | 6 | 15 | 12 | 12 | 12 | 12 |  | 50 Ohms-3 | TOP=L2:L3=L2/L4:L6=L5/L7:BOTTOM=L7 |
| SW_SSD1_N | 50OHM_Y12MIL | BUS | 4 | 6 | 5 | 10 | 5 | 14 | 6 | 15 | 12 | 12 | 12 | 12 |  | 50 Ohms-3 | TOP=L2:L3=L2/L4:L6=L5/L7:BOTTOM=L7 |
| SW_SSD1_N | 50OHM_Y12MIL | BUS | 5 | 6 | 5 | 10 | 5 | 14 | 6 | 15 | 12 | 12 | 12 | 12 |  | 50 Ohms-3 | TOP=L2:L3=L2/L4:L6=L5/L7:BOTTOM=L7 |
| SW_SSD1_N | 50OHM_Y12MIL | BUS | 6 | 6 | 5 | 10 | 5 | 14 | 6 | 15 | 12 | 12 | 12 | 12 |  | 50 Ohms-3 | TOP=L2:L3=L2/L4:L6=L5/L7:BOTTOM=L7 |
| SW_SSD1_N | 50OHM_Y12MIL | BUS | 7 | 6 | 5 | 10 | 5 | 14 | 6 | 15 | 12 | 12 | 12 | 12 |  | 50 Ohms-3 | TOP=L2:L3=L2/L4:L6=L5/L7:BOTTOM=L7 |
| SW_SSD1_N | 50OHM_Y12MIL | BUS | 8 | 6.75 | 5 | 10 | 5 | 14 | 6 | 15 | 12 | 12 | 12 | 12 |  | 50 Ohms-3 | TOP=L2:L3=L2/L4:L6=L5/L7:BOTTOM=L7 |
| SW_SSD1_R | 50OHM_Y12MIL | BUS | 1 | 6.75 | 5 | 10 | 5 | 14 | 6 | 15 | 12 | 12 | 12 | 12 |  | 50 Ohms-3 | TOP=L2:L3=L2/L4:L6=L5/L7:BOTTOM=L7 |
| SW_SSD1_R | 50OHM_Y12MIL | BUS | 2 | 6 | 5 | 10 | 5 | 14 | 6 | 15 | 12 | 12 | 12 | 12 |  | 50 Ohms-3 | TOP=L2:L3=L2/L4:L6=L5/L7:BOTTOM=L7 |
| SW_SSD1_R | 50OHM_Y12MIL | BUS | 3 | 6 | 5 | 10 | 5 | 14 | 6 | 15 | 12 | 12 | 12 | 12 |  | 50 Ohms-3 | TOP=L2:L3=L2/L4:L6=L5/L7:BOTTOM=L7 |
| SW_SSD1_R | 50OHM_Y12MIL | BUS | 4 | 6 | 5 | 10 | 5 | 14 | 6 | 15 | 12 | 12 | 12 | 12 |  | 50 Ohms-3 | TOP=L2:L3=L2/L4:L6=L5/L7:BOTTOM=L7 |
| SW_SSD1_R | 50OHM_Y12MIL | BUS | 5 | 6 | 5 | 10 | 5 | 14 | 6 | 15 | 12 | 12 | 12 | 12 |  | 50 Ohms-3 | TOP=L2:L3=L2/L4:L6=L5/L7:BOTTOM=L7 |
| SW_SSD1_R | 50OHM_Y12MIL | BUS | 6 | 6 | 5 | 10 | 5 | 14 | 6 | 15 | 12 | 12 | 12 | 12 |  | 50 Ohms-3 | TOP=L2:L3=L2/L4:L6=L5/L7:BOTTOM=L7 |
| SW_SSD1_R | 50OHM_Y12MIL | BUS | 7 | 6 | 5 | 10 | 5 | 14 | 6 | 15 | 12 | 12 | 12 | 12 |  | 50 Ohms-3 | TOP=L2:L3=L2/L4:L6=L5/L7:BOTTOM=L7 |
| SW_SSD1_R | 50OHM_Y12MIL | BUS | 8 | 6.75 | 5 | 10 | 5 | 14 | 6 | 15 | 12 | 12 | 12 | 12 |  | 50 Ohms-3 | TOP=L2:L3=L2/L4:L6=L5/L7:BOTTOM=L7 |
| SW_SSD10_N | 50OHM_Y12MIL | BUS | 1 | 6.75 | 5 | 10 | 5 | 14 | 6 | 15 | 12 | 12 | 12 | 12 |  | 50 Ohms-3 | TOP=L2:L3=L2/L4:L6=L5/L7:BOTTOM=L7 |
| SW_SSD10_N | 50OHM_Y12MIL | BUS | 2 | 6 | 5 | 10 | 5 | 14 | 6 | 15 | 12 | 12 | 12 | 12 |  | 50 Ohms-3 | TOP=L2:L3=L2/L4:L6=L5/L7:BOTTOM=L7 |
| SW_SSD10_N | 50OHM_Y12MIL | BUS | 3 | 6 | 5 | 10 | 5 | 14 | 6 | 15 | 12 | 12 | 12 | 12 |  | 50 Ohms-3 | TOP=L2:L3=L2/L4:L6=L5/L7:BOTTOM=L7 |
| SW_SSD10_N | 50OHM_Y12MIL | BUS | 4 | 6 | 5 | 10 | 5 | 14 | 6 | 15 | 12 | 12 | 12 | 12 |  | 50 Ohms-3 | TOP=L2:L3=L2/L4:L6=L5/L7:BOTTOM=L7 |
| SW_SSD10_N | 50OHM_Y12MIL | BUS | 5 | 6 | 5 | 10 | 5 | 14 | 6 | 15 | 12 | 12 | 12 | 12 |  | 50 Ohms-3 | TOP=L2:L3=L2/L4:L6=L5/L7:BOTTOM=L7 |
| SW_SSD10_N | 50OHM_Y12MIL | BUS | 6 | 6 | 5 | 10 | 5 | 14 | 6 | 15 | 12 | 12 | 12 | 12 |  | 50 Ohms-3 | TOP=L2:L3=L2/L4:L6=L5/L7:BOTTOM=L7 |
| SW_SSD10_N | 50OHM_Y12MIL | BUS | 7 | 6 | 5 | 10 | 5 | 14 | 6 | 15 | 12 | 12 | 12 | 12 |  | 50 Ohms-3 | TOP=L2:L3=L2/L4:L6=L5/L7:BOTTOM=L7 |
| SW_SSD10_N | 50OHM_Y12MIL | BUS | 8 | 6.75 | 5 | 10 | 5 | 14 | 6 | 15 | 12 | 12 | 12 | 12 |  | 50 Ohms-3 | TOP=L2:L3=L2/L4:L6=L5/L7:BOTTOM=L7 |
| SW_SSD10_R | 50OHM_Y12MIL | BUS | 1 | 6.75 | 5 | 10 | 5 | 14 | 6 | 15 | 12 | 12 | 12 | 12 |  | 50 Ohms-3 | TOP=L2:L3=L2/L4:L6=L5/L7:BOTTOM=L7 |
| SW_SSD10_R | 50OHM_Y12MIL | BUS | 2 | 6 | 5 | 10 | 5 | 14 | 6 | 15 | 12 | 12 | 12 | 12 |  | 50 Ohms-3 | TOP=L2:L3=L2/L4:L6=L5/L7:BOTTOM=L7 |
| SW_SSD10_R | 50OHM_Y12MIL | BUS | 3 | 6 | 5 | 10 | 5 | 14 | 6 | 15 | 12 | 12 | 12 | 12 |  | 50 Ohms-3 | TOP=L2:L3=L2/L4:L6=L5/L7:BOTTOM=L7 |
| SW_SSD10_R | 50OHM_Y12MIL | BUS | 4 | 6 | 5 | 10 | 5 | 14 | 6 | 15 | 12 | 12 | 12 | 12 |  | 50 Ohms-3 | TOP=L2:L3=L2/L4:L6=L5/L7:BOTTOM=L7 |
| SW_SSD10_R | 50OHM_Y12MIL | BUS | 5 | 6 | 5 | 10 | 5 | 14 | 6 | 15 | 12 | 12 | 12 | 12 |  | 50 Ohms-3 | TOP=L2:L3=L2/L4:L6=L5/L7:BOTTOM=L7 |
| SW_SSD10_R | 50OHM_Y12MIL | BUS | 6 | 6 | 5 | 10 | 5 | 14 | 6 | 15 | 12 | 12 | 12 | 12 |  | 50 Ohms-3 | TOP=L2:L3=L2/L4:L6=L5/L7:BOTTOM=L7 |
| SW_SSD10_R | 50OHM_Y12MIL | BUS | 7 | 6 | 5 | 10 | 5 | 14 | 6 | 15 | 12 | 12 | 12 | 12 |  | 50 Ohms-3 | TOP=L2:L3=L2/L4:L6=L5/L7:BOTTOM=L7 |
| SW_SSD10_R | 50OHM_Y12MIL | BUS | 8 | 6.75 | 5 | 10 | 5 | 14 | 6 | 15 | 12 | 12 | 12 | 12 |  | 50 Ohms-3 | TOP=L2:L3=L2/L4:L6=L5/L7:BOTTOM=L7 |
| SW_SSD11_N | 50OHM_Y12MIL | BUS | 1 | 6.75 | 5 | 10 | 5 | 14 | 6 | 15 | 12 | 12 | 12 | 12 |  | 50 Ohms-3 | TOP=L2:L3=L2/L4:L6=L5/L7:BOTTOM=L7 |
| SW_SSD11_N | 50OHM_Y12MIL | BUS | 2 | 6 | 5 | 10 | 5 | 14 | 6 | 15 | 12 | 12 | 12 | 12 |  | 50 Ohms-3 | TOP=L2:L3=L2/L4:L6=L5/L7:BOTTOM=L7 |
| SW_SSD11_N | 50OHM_Y12MIL | BUS | 3 | 6 | 5 | 10 | 5 | 14 | 6 | 15 | 12 | 12 | 12 | 12 |  | 50 Ohms-3 | TOP=L2:L3=L2/L4:L6=L5/L7:BOTTOM=L7 |
| SW_SSD11_N | 50OHM_Y12MIL | BUS | 4 | 6 | 5 | 10 | 5 | 14 | 6 | 15 | 12 | 12 | 12 | 12 |  | 50 Ohms-3 | TOP=L2:L3=L2/L4:L6=L5/L7:BOTTOM=L7 |
| SW_SSD11_N | 50OHM_Y12MIL | BUS | 5 | 6 | 5 | 10 | 5 | 14 | 6 | 15 | 12 | 12 | 12 | 12 |  | 50 Ohms-3 | TOP=L2:L3=L2/L4:L6=L5/L7:BOTTOM=L7 |
| SW_SSD11_N | 50OHM_Y12MIL | BUS | 6 | 6 | 5 | 10 | 5 | 14 | 6 | 15 | 12 | 12 | 12 | 12 |  | 50 Ohms-3 | TOP=L2:L3=L2/L4:L6=L5/L7:BOTTOM=L7 |
| SW_SSD11_N | 50OHM_Y12MIL | BUS | 7 | 6 | 5 | 10 | 5 | 14 | 6 | 15 | 12 | 12 | 12 | 12 |  | 50 Ohms-3 | TOP=L2:L3=L2/L4:L6=L5/L7:BOTTOM=L7 |
| SW_SSD11_N | 50OHM_Y12MIL | BUS | 8 | 6.75 | 5 | 10 | 5 | 14 | 6 | 15 | 12 | 12 | 12 | 12 |  | 50 Ohms-3 | TOP=L2:L3=L2/L4:L6=L5/L7:BOTTOM=L7 |
| SW_SSD11_R | 50OHM_Y12MIL | BUS | 1 | 6.75 | 5 | 10 | 5 | 14 | 6 | 15 | 12 | 12 | 12 | 12 |  | 50 Ohms-3 | TOP=L2:L3=L2/L4:L6=L5/L7:BOTTOM=L7 |
| SW_SSD11_R | 50OHM_Y12MIL | BUS | 2 | 6 | 5 | 10 | 5 | 14 | 6 | 15 | 12 | 12 | 12 | 12 |  | 50 Ohms-3 | TOP=L2:L3=L2/L4:L6=L5/L7:BOTTOM=L7 |
| SW_SSD11_R | 50OHM_Y12MIL | BUS | 3 | 6 | 5 | 10 | 5 | 14 | 6 | 15 | 12 | 12 | 12 | 12 |  | 50 Ohms-3 | TOP=L2:L3=L2/L4:L6=L5/L7:BOTTOM=L7 |
| SW_SSD11_R | 50OHM_Y12MIL | BUS | 4 | 6 | 5 | 10 | 5 | 14 | 6 | 15 | 12 | 12 | 12 | 12 |  | 50 Ohms-3 | TOP=L2:L3=L2/L4:L6=L5/L7:BOTTOM=L7 |
| SW_SSD11_R | 50OHM_Y12MIL | BUS | 5 | 6 | 5 | 10 | 5 | 14 | 6 | 15 | 12 | 12 | 12 | 12 |  | 50 Ohms-3 | TOP=L2:L3=L2/L4:L6=L5/L7:BOTTOM=L7 |
| SW_SSD11_R | 50OHM_Y12MIL | BUS | 6 | 6 | 5 | 10 | 5 | 14 | 6 | 15 | 12 | 12 | 12 | 12 |  | 50 Ohms-3 | TOP=L2:L3=L2/L4:L6=L5/L7:BOTTOM=L7 |
| SW_SSD11_R | 50OHM_Y12MIL | BUS | 7 | 6 | 5 | 10 | 5 | 14 | 6 | 15 | 12 | 12 | 12 | 12 |  | 50 Ohms-3 | TOP=L2:L3=L2/L4:L6=L5/L7:BOTTOM=L7 |
| SW_SSD11_R | 50OHM_Y12MIL | BUS | 8 | 6.75 | 5 | 10 | 5 | 14 | 6 | 15 | 12 | 12 | 12 | 12 |  | 50 Ohms-3 | TOP=L2:L3=L2/L4:L6=L5/L7:BOTTOM=L7 |
| SW_SSD12_N | 50OHM_Y12MIL | BUS | 1 | 6.75 | 5 | 10 | 5 | 14 | 6 | 15 | 12 | 12 | 12 | 12 |  | 50 Ohms-3 | TOP=L2:L3=L2/L4:L6=L5/L7:BOTTOM=L7 |
| SW_SSD12_N | 50OHM_Y12MIL | BUS | 2 | 6 | 5 | 10 | 5 | 14 | 6 | 15 | 12 | 12 | 12 | 12 |  | 50 Ohms-3 | TOP=L2:L3=L2/L4:L6=L5/L7:BOTTOM=L7 |
| SW_SSD12_N | 50OHM_Y12MIL | BUS | 3 | 6 | 5 | 10 | 5 | 14 | 6 | 15 | 12 | 12 | 12 | 12 |  | 50 Ohms-3 | TOP=L2:L3=L2/L4:L6=L5/L7:BOTTOM=L7 |
| SW_SSD12_N | 50OHM_Y12MIL | BUS | 4 | 6 | 5 | 10 | 5 | 14 | 6 | 15 | 12 | 12 | 12 | 12 |  | 50 Ohms-3 | TOP=L2:L3=L2/L4:L6=L5/L7:BOTTOM=L7 |
| SW_SSD12_N | 50OHM_Y12MIL | BUS | 5 | 6 | 5 | 10 | 5 | 14 | 6 | 15 | 12 | 12 | 12 | 12 |  | 50 Ohms-3 | TOP=L2:L3=L2/L4:L6=L5/L7:BOTTOM=L7 |
| SW_SSD12_N | 50OHM_Y12MIL | BUS | 6 | 6 | 5 | 10 | 5 | 14 | 6 | 15 | 12 | 12 | 12 | 12 |  | 50 Ohms-3 | TOP=L2:L3=L2/L4:L6=L5/L7:BOTTOM=L7 |
| SW_SSD12_N | 50OHM_Y12MIL | BUS | 7 | 6 | 5 | 10 | 5 | 14 | 6 | 15 | 12 | 12 | 12 | 12 |  | 50 Ohms-3 | TOP=L2:L3=L2/L4:L6=L5/L7:BOTTOM=L7 |
| SW_SSD12_N | 50OHM_Y12MIL | BUS | 8 | 6.75 | 5 | 10 | 5 | 14 | 6 | 15 | 12 | 12 | 12 | 12 |  | 50 Ohms-3 | TOP=L2:L3=L2/L4:L6=L5/L7:BOTTOM=L7 |
| SW_SSD12_R | 50OHM_Y12MIL | BUS | 1 | 6.75 | 5 | 10 | 5 | 14 | 6 | 15 | 12 | 12 | 12 | 12 |  | 50 Ohms-3 | TOP=L2:L3=L2/L4:L6=L5/L7:BOTTOM=L7 |
| SW_SSD12_R | 50OHM_Y12MIL | BUS | 2 | 6 | 5 | 10 | 5 | 14 | 6 | 15 | 12 | 12 | 12 | 12 |  | 50 Ohms-3 | TOP=L2:L3=L2/L4:L6=L5/L7:BOTTOM=L7 |
| SW_SSD12_R | 50OHM_Y12MIL | BUS | 3 | 6 | 5 | 10 | 5 | 14 | 6 | 15 | 12 | 12 | 12 | 12 |  | 50 Ohms-3 | TOP=L2:L3=L2/L4:L6=L5/L7:BOTTOM=L7 |
| SW_SSD12_R | 50OHM_Y12MIL | BUS | 4 | 6 | 5 | 10 | 5 | 14 | 6 | 15 | 12 | 12 | 12 | 12 |  | 50 Ohms-3 | TOP=L2:L3=L2/L4:L6=L5/L7:BOTTOM=L7 |
| SW_SSD12_R | 50OHM_Y12MIL | BUS | 5 | 6 | 5 | 10 | 5 | 14 | 6 | 15 | 12 | 12 | 12 | 12 |  | 50 Ohms-3 | TOP=L2:L3=L2/L4:L6=L5/L7:BOTTOM=L7 |
| SW_SSD12_R | 50OHM_Y12MIL | BUS | 6 | 6 | 5 | 10 | 5 | 14 | 6 | 15 | 12 | 12 | 12 | 12 |  | 50 Ohms-3 | TOP=L2:L3=L2/L4:L6=L5/L7:BOTTOM=L7 |
| SW_SSD12_R | 50OHM_Y12MIL | BUS | 7 | 6 | 5 | 10 | 5 | 14 | 6 | 15 | 12 | 12 | 12 | 12 |  | 50 Ohms-3 | TOP=L2:L3=L2/L4:L6=L5/L7:BOTTOM=L7 |
| SW_SSD12_R | 50OHM_Y12MIL | BUS | 8 | 6.75 | 5 | 10 | 5 | 14 | 6 | 15 | 12 | 12 | 12 | 12 |  | 50 Ohms-3 | TOP=L2:L3=L2/L4:L6=L5/L7:BOTTOM=L7 |
| SW_SSD13_N | 50OHM_Y12MIL | BUS | 1 | 6.75 | 5 | 10 | 5 | 14 | 6 | 15 | 12 | 12 | 12 | 12 |  | 50 Ohms-3 | TOP=L2:L3=L2/L4:L6=L5/L7:BOTTOM=L7 |
| SW_SSD13_N | 50OHM_Y12MIL | BUS | 2 | 6 | 5 | 10 | 5 | 14 | 6 | 15 | 12 | 12 | 12 | 12 |  | 50 Ohms-3 | TOP=L2:L3=L2/L4:L6=L5/L7:BOTTOM=L7 |
| SW_SSD13_N | 50OHM_Y12MIL | BUS | 3 | 6 | 5 | 10 | 5 | 14 | 6 | 15 | 12 | 12 | 12 | 12 |  | 50 Ohms-3 | TOP=L2:L3=L2/L4:L6=L5/L7:BOTTOM=L7 |
| SW_SSD13_N | 50OHM_Y12MIL | BUS | 4 | 6 | 5 | 10 | 5 | 14 | 6 | 15 | 12 | 12 | 12 | 12 |  | 50 Ohms-3 | TOP=L2:L3=L2/L4:L6=L5/L7:BOTTOM=L7 |
| SW_SSD13_N | 50OHM_Y12MIL | BUS | 5 | 6 | 5 | 10 | 5 | 14 | 6 | 15 | 12 | 12 | 12 | 12 |  | 50 Ohms-3 | TOP=L2:L3=L2/L4:L6=L5/L7:BOTTOM=L7 |
| SW_SSD13_N | 50OHM_Y12MIL | BUS | 6 | 6 | 5 | 10 | 5 | 14 | 6 | 15 | 12 | 12 | 12 | 12 |  | 50 Ohms-3 | TOP=L2:L3=L2/L4:L6=L5/L7:BOTTOM=L7 |
| SW_SSD13_N | 50OHM_Y12MIL | BUS | 7 | 6 | 5 | 10 | 5 | 14 | 6 | 15 | 12 | 12 | 12 | 12 |  | 50 Ohms-3 | TOP=L2:L3=L2/L4:L6=L5/L7:BOTTOM=L7 |
| SW_SSD13_N | 50OHM_Y12MIL | BUS | 8 | 6.75 | 5 | 10 | 5 | 14 | 6 | 15 | 12 | 12 | 12 | 12 |  | 50 Ohms-3 | TOP=L2:L3=L2/L4:L6=L5/L7:BOTTOM=L7 |
| SW_SSD13_R | 50OHM_Y12MIL | BUS | 1 | 6.75 | 5 | 10 | 5 | 14 | 6 | 15 | 12 | 12 | 12 | 12 |  | 50 Ohms-3 | TOP=L2:L3=L2/L4:L6=L5/L7:BOTTOM=L7 |
| SW_SSD13_R | 50OHM_Y12MIL | BUS | 2 | 6 | 5 | 10 | 5 | 14 | 6 | 15 | 12 | 12 | 12 | 12 |  | 50 Ohms-3 | TOP=L2:L3=L2/L4:L6=L5/L7:BOTTOM=L7 |
| SW_SSD13_R | 50OHM_Y12MIL | BUS | 3 | 6 | 5 | 10 | 5 | 14 | 6 | 15 | 12 | 12 | 12 | 12 |  | 50 Ohms-3 | TOP=L2:L3=L2/L4:L6=L5/L7:BOTTOM=L7 |
| SW_SSD13_R | 50OHM_Y12MIL | BUS | 4 | 6 | 5 | 10 | 5 | 14 | 6 | 15 | 12 | 12 | 12 | 12 |  | 50 Ohms-3 | TOP=L2:L3=L2/L4:L6=L5/L7:BOTTOM=L7 |
| SW_SSD13_R | 50OHM_Y12MIL | BUS | 5 | 6 | 5 | 10 | 5 | 14 | 6 | 15 | 12 | 12 | 12 | 12 |  | 50 Ohms-3 | TOP=L2:L3=L2/L4:L6=L5/L7:BOTTOM=L7 |
| SW_SSD13_R | 50OHM_Y12MIL | BUS | 6 | 6 | 5 | 10 | 5 | 14 | 6 | 15 | 12 | 12 | 12 | 12 |  | 50 Ohms-3 | TOP=L2:L3=L2/L4:L6=L5/L7:BOTTOM=L7 |
| SW_SSD13_R | 50OHM_Y12MIL | BUS | 7 | 6 | 5 | 10 | 5 | 14 | 6 | 15 | 12 | 12 | 12 | 12 |  | 50 Ohms-3 | TOP=L2:L3=L2/L4:L6=L5/L7:BOTTOM=L7 |
| SW_SSD13_R | 50OHM_Y12MIL | BUS | 8 | 6.75 | 5 | 10 | 5 | 14 | 6 | 15 | 12 | 12 | 12 | 12 |  | 50 Ohms-3 | TOP=L2:L3=L2/L4:L6=L5/L7:BOTTOM=L7 |
| SW_SSD14_N | 50OHM_Y12MIL | BUS | 1 | 6.75 | 5 | 10 | 5 | 14 | 6 | 15 | 12 | 12 | 12 | 12 |  | 50 Ohms-3 | TOP=L2:L3=L2/L4:L6=L5/L7:BOTTOM=L7 |
| SW_SSD14_N | 50OHM_Y12MIL | BUS | 2 | 6 | 5 | 10 | 5 | 14 | 6 | 15 | 12 | 12 | 12 | 12 |  | 50 Ohms-3 | TOP=L2:L3=L2/L4:L6=L5/L7:BOTTOM=L7 |
| SW_SSD14_N | 50OHM_Y12MIL | BUS | 3 | 6 | 5 | 10 | 5 | 14 | 6 | 15 | 12 | 12 | 12 | 12 |  | 50 Ohms-3 | TOP=L2:L3=L2/L4:L6=L5/L7:BOTTOM=L7 |
| SW_SSD14_N | 50OHM_Y12MIL | BUS | 4 | 6 | 5 | 10 | 5 | 14 | 6 | 15 | 12 | 12 | 12 | 12 |  | 50 Ohms-3 | TOP=L2:L3=L2/L4:L6=L5/L7:BOTTOM=L7 |
| SW_SSD14_N | 50OHM_Y12MIL | BUS | 5 | 6 | 5 | 10 | 5 | 14 | 6 | 15 | 12 | 12 | 12 | 12 |  | 50 Ohms-3 | TOP=L2:L3=L2/L4:L6=L5/L7:BOTTOM=L7 |
| SW_SSD14_N | 50OHM_Y12MIL | BUS | 6 | 6 | 5 | 10 | 5 | 14 | 6 | 15 | 12 | 12 | 12 | 12 |  | 50 Ohms-3 | TOP=L2:L3=L2/L4:L6=L5/L7:BOTTOM=L7 |
| SW_SSD14_N | 50OHM_Y12MIL | BUS | 7 | 6 | 5 | 10 | 5 | 14 | 6 | 15 | 12 | 12 | 12 | 12 |  | 50 Ohms-3 | TOP=L2:L3=L2/L4:L6=L5/L7:BOTTOM=L7 |
| SW_SSD14_N | 50OHM_Y12MIL | BUS | 8 | 6.75 | 5 | 10 | 5 | 14 | 6 | 15 | 12 | 12 | 12 | 12 |  | 50 Ohms-3 | TOP=L2:L3=L2/L4:L6=L5/L7:BOTTOM=L7 |
| SW_SSD14_R | 50OHM_Y12MIL | BUS | 1 | 6.75 | 5 | 10 | 5 | 14 | 6 | 15 | 12 | 12 | 12 | 12 |  | 50 Ohms-3 | TOP=L2:L3=L2/L4:L6=L5/L7:BOTTOM=L7 |
| SW_SSD14_R | 50OHM_Y12MIL | BUS | 2 | 6 | 5 | 10 | 5 | 14 | 6 | 15 | 12 | 12 | 12 | 12 |  | 50 Ohms-3 | TOP=L2:L3=L2/L4:L6=L5/L7:BOTTOM=L7 |
| SW_SSD14_R | 50OHM_Y12MIL | BUS | 3 | 6 | 5 | 10 | 5 | 14 | 6 | 15 | 12 | 12 | 12 | 12 |  | 50 Ohms-3 | TOP=L2:L3=L2/L4:L6=L5/L7:BOTTOM=L7 |
| SW_SSD14_R | 50OHM_Y12MIL | BUS | 4 | 6 | 5 | 10 | 5 | 14 | 6 | 15 | 12 | 12 | 12 | 12 |  | 50 Ohms-3 | TOP=L2:L3=L2/L4:L6=L5/L7:BOTTOM=L7 |
| SW_SSD14_R | 50OHM_Y12MIL | BUS | 5 | 6 | 5 | 10 | 5 | 14 | 6 | 15 | 12 | 12 | 12 | 12 |  | 50 Ohms-3 | TOP=L2:L3=L2/L4:L6=L5/L7:BOTTOM=L7 |
| SW_SSD14_R | 50OHM_Y12MIL | BUS | 6 | 6 | 5 | 10 | 5 | 14 | 6 | 15 | 12 | 12 | 12 | 12 |  | 50 Ohms-3 | TOP=L2:L3=L2/L4:L6=L5/L7:BOTTOM=L7 |
| SW_SSD14_R | 50OHM_Y12MIL | BUS | 7 | 6 | 5 | 10 | 5 | 14 | 6 | 15 | 12 | 12 | 12 | 12 |  | 50 Ohms-3 | TOP=L2:L3=L2/L4:L6=L5/L7:BOTTOM=L7 |
| SW_SSD14_R | 50OHM_Y12MIL | BUS | 8 | 6.75 | 5 | 10 | 5 | 14 | 6 | 15 | 12 | 12 | 12 | 12 |  | 50 Ohms-3 | TOP=L2:L3=L2/L4:L6=L5/L7:BOTTOM=L7 |
| SW_SSD2_N | 50OHM_Y12MIL | BUS | 1 | 6.75 | 5 | 10 | 5 | 14 | 6 | 15 | 12 | 12 | 12 | 12 |  | 50 Ohms-3 | TOP=L2:L3=L2/L4:L6=L5/L7:BOTTOM=L7 |
| SW_SSD2_N | 50OHM_Y12MIL | BUS | 2 | 6 | 5 | 10 | 5 | 14 | 6 | 15 | 12 | 12 | 12 | 12 |  | 50 Ohms-3 | TOP=L2:L3=L2/L4:L6=L5/L7:BOTTOM=L7 |
| SW_SSD2_N | 50OHM_Y12MIL | BUS | 3 | 6 | 5 | 10 | 5 | 14 | 6 | 15 | 12 | 12 | 12 | 12 |  | 50 Ohms-3 | TOP=L2:L3=L2/L4:L6=L5/L7:BOTTOM=L7 |
| SW_SSD2_N | 50OHM_Y12MIL | BUS | 4 | 6 | 5 | 10 | 5 | 14 | 6 | 15 | 12 | 12 | 12 | 12 |  | 50 Ohms-3 | TOP=L2:L3=L2/L4:L6=L5/L7:BOTTOM=L7 |
| SW_SSD2_N | 50OHM_Y12MIL | BUS | 5 | 6 | 5 | 10 | 5 | 14 | 6 | 15 | 12 | 12 | 12 | 12 |  | 50 Ohms-3 | TOP=L2:L3=L2/L4:L6=L5/L7:BOTTOM=L7 |
| SW_SSD2_N | 50OHM_Y12MIL | BUS | 6 | 6 | 5 | 10 | 5 | 14 | 6 | 15 | 12 | 12 | 12 | 12 |  | 50 Ohms-3 | TOP=L2:L3=L2/L4:L6=L5/L7:BOTTOM=L7 |
| SW_SSD2_N | 50OHM_Y12MIL | BUS | 7 | 6 | 5 | 10 | 5 | 14 | 6 | 15 | 12 | 12 | 12 | 12 |  | 50 Ohms-3 | TOP=L2:L3=L2/L4:L6=L5/L7:BOTTOM=L7 |
| SW_SSD2_N | 50OHM_Y12MIL | BUS | 8 | 6.75 | 5 | 10 | 5 | 14 | 6 | 15 | 12 | 12 | 12 | 12 |  | 50 Ohms-3 | TOP=L2:L3=L2/L4:L6=L5/L7:BOTTOM=L7 |
| SW_SSD2_R | 50OHM_Y12MIL | BUS | 1 | 6.75 | 5 | 10 | 5 | 14 | 6 | 15 | 12 | 12 | 12 | 12 |  | 50 Ohms-3 | TOP=L2:L3=L2/L4:L6=L5/L7:BOTTOM=L7 |
| SW_SSD2_R | 50OHM_Y12MIL | BUS | 2 | 6 | 5 | 10 | 5 | 14 | 6 | 15 | 12 | 12 | 12 | 12 |  | 50 Ohms-3 | TOP=L2:L3=L2/L4:L6=L5/L7:BOTTOM=L7 |
| SW_SSD2_R | 50OHM_Y12MIL | BUS | 3 | 6 | 5 | 10 | 5 | 14 | 6 | 15 | 12 | 12 | 12 | 12 |  | 50 Ohms-3 | TOP=L2:L3=L2/L4:L6=L5/L7:BOTTOM=L7 |
| SW_SSD2_R | 50OHM_Y12MIL | BUS | 4 | 6 | 5 | 10 | 5 | 14 | 6 | 15 | 12 | 12 | 12 | 12 |  | 50 Ohms-3 | TOP=L2:L3=L2/L4:L6=L5/L7:BOTTOM=L7 |
| SW_SSD2_R | 50OHM_Y12MIL | BUS | 5 | 6 | 5 | 10 | 5 | 14 | 6 | 15 | 12 | 12 | 12 | 12 |  | 50 Ohms-3 | TOP=L2:L3=L2/L4:L6=L5/L7:BOTTOM=L7 |
| SW_SSD2_R | 50OHM_Y12MIL | BUS | 6 | 6 | 5 | 10 | 5 | 14 | 6 | 15 | 12 | 12 | 12 | 12 |  | 50 Ohms-3 | TOP=L2:L3=L2/L4:L6=L5/L7:BOTTOM=L7 |
| SW_SSD2_R | 50OHM_Y12MIL | BUS | 7 | 6 | 5 | 10 | 5 | 14 | 6 | 15 | 12 | 12 | 12 | 12 |  | 50 Ohms-3 | TOP=L2:L3=L2/L4:L6=L5/L7:BOTTOM=L7 |
| SW_SSD2_R | 50OHM_Y12MIL | BUS | 8 | 6.75 | 5 | 10 | 5 | 14 | 6 | 15 | 12 | 12 | 12 | 12 |  | 50 Ohms-3 | TOP=L2:L3=L2/L4:L6=L5/L7:BOTTOM=L7 |
| SW_SSD3_N | 50OHM_Y12MIL | BUS | 1 | 6.75 | 5 | 10 | 5 | 14 | 6 | 15 | 12 | 12 | 12 | 12 |  | 50 Ohms-3 | TOP=L2:L3=L2/L4:L6=L5/L7:BOTTOM=L7 |
| SW_SSD3_N | 50OHM_Y12MIL | BUS | 2 | 6 | 5 | 10 | 5 | 14 | 6 | 15 | 12 | 12 | 12 | 12 |  | 50 Ohms-3 | TOP=L2:L3=L2/L4:L6=L5/L7:BOTTOM=L7 |
| SW_SSD3_N | 50OHM_Y12MIL | BUS | 3 | 6 | 5 | 10 | 5 | 14 | 6 | 15 | 12 | 12 | 12 | 12 |  | 50 Ohms-3 | TOP=L2:L3=L2/L4:L6=L5/L7:BOTTOM=L7 |
| SW_SSD3_N | 50OHM_Y12MIL | BUS | 4 | 6 | 5 | 10 | 5 | 14 | 6 | 15 | 12 | 12 | 12 | 12 |  | 50 Ohms-3 | TOP=L2:L3=L2/L4:L6=L5/L7:BOTTOM=L7 |
| SW_SSD3_N | 50OHM_Y12MIL | BUS | 5 | 6 | 5 | 10 | 5 | 14 | 6 | 15 | 12 | 12 | 12 | 12 |  | 50 Ohms-3 | TOP=L2:L3=L2/L4:L6=L5/L7:BOTTOM=L7 |
| SW_SSD3_N | 50OHM_Y12MIL | BUS | 6 | 6 | 5 | 10 | 5 | 14 | 6 | 15 | 12 | 12 | 12 | 12 |  | 50 Ohms-3 | TOP=L2:L3=L2/L4:L6=L5/L7:BOTTOM=L7 |
| SW_SSD3_N | 50OHM_Y12MIL | BUS | 7 | 6 | 5 | 10 | 5 | 14 | 6 | 15 | 12 | 12 | 12 | 12 |  | 50 Ohms-3 | TOP=L2:L3=L2/L4:L6=L5/L7:BOTTOM=L7 |
| SW_SSD3_N | 50OHM_Y12MIL | BUS | 8 | 6.75 | 5 | 10 | 5 | 14 | 6 | 15 | 12 | 12 | 12 | 12 |  | 50 Ohms-3 | TOP=L2:L3=L2/L4:L6=L5/L7:BOTTOM=L7 |
| SW_SSD3_R | 50OHM_Y12MIL | BUS | 1 | 6.75 | 5 | 10 | 5 | 14 | 6 | 15 | 12 | 12 | 12 | 12 |  | 50 Ohms-3 | TOP=L2:L3=L2/L4:L6=L5/L7:BOTTOM=L7 |
| SW_SSD3_R | 50OHM_Y12MIL | BUS | 2 | 6 | 5 | 10 | 5 | 14 | 6 | 15 | 12 | 12 | 12 | 12 |  | 50 Ohms-3 | TOP=L2:L3=L2/L4:L6=L5/L7:BOTTOM=L7 |
| SW_SSD3_R | 50OHM_Y12MIL | BUS | 3 | 6 | 5 | 10 | 5 | 14 | 6 | 15 | 12 | 12 | 12 | 12 |  | 50 Ohms-3 | TOP=L2:L3=L2/L4:L6=L5/L7:BOTTOM=L7 |
| SW_SSD3_R | 50OHM_Y12MIL | BUS | 4 | 6 | 5 | 10 | 5 | 14 | 6 | 15 | 12 | 12 | 12 | 12 |  | 50 Ohms-3 | TOP=L2:L3=L2/L4:L6=L5/L7:BOTTOM=L7 |
| SW_SSD3_R | 50OHM_Y12MIL | BUS | 5 | 6 | 5 | 10 | 5 | 14 | 6 | 15 | 12 | 12 | 12 | 12 |  | 50 Ohms-3 | TOP=L2:L3=L2/L4:L6=L5/L7:BOTTOM=L7 |
| SW_SSD3_R | 50OHM_Y12MIL | BUS | 6 | 6 | 5 | 10 | 5 | 14 | 6 | 15 | 12 | 12 | 12 | 12 |  | 50 Ohms-3 | TOP=L2:L3=L2/L4:L6=L5/L7:BOTTOM=L7 |
| SW_SSD3_R | 50OHM_Y12MIL | BUS | 7 | 6 | 5 | 10 | 5 | 14 | 6 | 15 | 12 | 12 | 12 | 12 |  | 50 Ohms-3 | TOP=L2:L3=L2/L4:L6=L5/L7:BOTTOM=L7 |
| SW_SSD3_R | 50OHM_Y12MIL | BUS | 8 | 6.75 | 5 | 10 | 5 | 14 | 6 | 15 | 12 | 12 | 12 | 12 |  | 50 Ohms-3 | TOP=L2:L3=L2/L4:L6=L5/L7:BOTTOM=L7 |
| SW_SSD4_N | 50OHM_Y12MIL | BUS | 1 | 6.75 | 5 | 10 | 5 | 14 | 6 | 15 | 12 | 12 | 12 | 12 |  | 50 Ohms-3 | TOP=L2:L3=L2/L4:L6=L5/L7:BOTTOM=L7 |
| SW_SSD4_N | 50OHM_Y12MIL | BUS | 2 | 6 | 5 | 10 | 5 | 14 | 6 | 15 | 12 | 12 | 12 | 12 |  | 50 Ohms-3 | TOP=L2:L3=L2/L4:L6=L5/L7:BOTTOM=L7 |
| SW_SSD4_N | 50OHM_Y12MIL | BUS | 3 | 6 | 5 | 10 | 5 | 14 | 6 | 15 | 12 | 12 | 12 | 12 |  | 50 Ohms-3 | TOP=L2:L3=L2/L4:L6=L5/L7:BOTTOM=L7 |
| SW_SSD4_N | 50OHM_Y12MIL | BUS | 4 | 6 | 5 | 10 | 5 | 14 | 6 | 15 | 12 | 12 | 12 | 12 |  | 50 Ohms-3 | TOP=L2:L3=L2/L4:L6=L5/L7:BOTTOM=L7 |
| SW_SSD4_N | 50OHM_Y12MIL | BUS | 5 | 6 | 5 | 10 | 5 | 14 | 6 | 15 | 12 | 12 | 12 | 12 |  | 50 Ohms-3 | TOP=L2:L3=L2/L4:L6=L5/L7:BOTTOM=L7 |
| SW_SSD4_N | 50OHM_Y12MIL | BUS | 6 | 6 | 5 | 10 | 5 | 14 | 6 | 15 | 12 | 12 | 12 | 12 |  | 50 Ohms-3 | TOP=L2:L3=L2/L4:L6=L5/L7:BOTTOM=L7 |
| SW_SSD4_N | 50OHM_Y12MIL | BUS | 7 | 6 | 5 | 10 | 5 | 14 | 6 | 15 | 12 | 12 | 12 | 12 |  | 50 Ohms-3 | TOP=L2:L3=L2/L4:L6=L5/L7:BOTTOM=L7 |
| SW_SSD4_N | 50OHM_Y12MIL | BUS | 8 | 6.75 | 5 | 10 | 5 | 14 | 6 | 15 | 12 | 12 | 12 | 12 |  | 50 Ohms-3 | TOP=L2:L3=L2/L4:L6=L5/L7:BOTTOM=L7 |
| SW_SSD4_R | 50OHM_Y12MIL | BUS | 1 | 6.75 | 5 | 10 | 5 | 14 | 6 | 15 | 12 | 12 | 12 | 12 |  | 50 Ohms-3 | TOP=L2:L3=L2/L4:L6=L5/L7:BOTTOM=L7 |
| SW_SSD4_R | 50OHM_Y12MIL | BUS | 2 | 6 | 5 | 10 | 5 | 14 | 6 | 15 | 12 | 12 | 12 | 12 |  | 50 Ohms-3 | TOP=L2:L3=L2/L4:L6=L5/L7:BOTTOM=L7 |
| SW_SSD4_R | 50OHM_Y12MIL | BUS | 3 | 6 | 5 | 10 | 5 | 14 | 6 | 15 | 12 | 12 | 12 | 12 |  | 50 Ohms-3 | TOP=L2:L3=L2/L4:L6=L5/L7:BOTTOM=L7 |
| SW_SSD4_R | 50OHM_Y12MIL | BUS | 4 | 6 | 5 | 10 | 5 | 14 | 6 | 15 | 12 | 12 | 12 | 12 |  | 50 Ohms-3 | TOP=L2:L3=L2/L4:L6=L5/L7:BOTTOM=L7 |
| SW_SSD4_R | 50OHM_Y12MIL | BUS | 5 | 6 | 5 | 10 | 5 | 14 | 6 | 15 | 12 | 12 | 12 | 12 |  | 50 Ohms-3 | TOP=L2:L3=L2/L4:L6=L5/L7:BOTTOM=L7 |
| SW_SSD4_R | 50OHM_Y12MIL | BUS | 6 | 6 | 5 | 10 | 5 | 14 | 6 | 15 | 12 | 12 | 12 | 12 |  | 50 Ohms-3 | TOP=L2:L3=L2/L4:L6=L5/L7:BOTTOM=L7 |
| SW_SSD4_R | 50OHM_Y12MIL | BUS | 7 | 6 | 5 | 10 | 5 | 14 | 6 | 15 | 12 | 12 | 12 | 12 |  | 50 Ohms-3 | TOP=L2:L3=L2/L4:L6=L5/L7:BOTTOM=L7 |
| SW_SSD4_R | 50OHM_Y12MIL | BUS | 8 | 6.75 | 5 | 10 | 5 | 14 | 6 | 15 | 12 | 12 | 12 | 12 |  | 50 Ohms-3 | TOP=L2:L3=L2/L4:L6=L5/L7:BOTTOM=L7 |
| SW_SSD5_N | 50OHM_Y12MIL | BUS | 1 | 6.75 | 5 | 10 | 5 | 14 | 6 | 15 | 12 | 12 | 12 | 12 |  | 50 Ohms-3 | TOP=L2:L3=L2/L4:L6=L5/L7:BOTTOM=L7 |
| SW_SSD5_N | 50OHM_Y12MIL | BUS | 2 | 6 | 5 | 10 | 5 | 14 | 6 | 15 | 12 | 12 | 12 | 12 |  | 50 Ohms-3 | TOP=L2:L3=L2/L4:L6=L5/L7:BOTTOM=L7 |
| SW_SSD5_N | 50OHM_Y12MIL | BUS | 3 | 6 | 5 | 10 | 5 | 14 | 6 | 15 | 12 | 12 | 12 | 12 |  | 50 Ohms-3 | TOP=L2:L3=L2/L4:L6=L5/L7:BOTTOM=L7 |
| SW_SSD5_N | 50OHM_Y12MIL | BUS | 4 | 6 | 5 | 10 | 5 | 14 | 6 | 15 | 12 | 12 | 12 | 12 |  | 50 Ohms-3 | TOP=L2:L3=L2/L4:L6=L5/L7:BOTTOM=L7 |
| SW_SSD5_N | 50OHM_Y12MIL | BUS | 5 | 6 | 5 | 10 | 5 | 14 | 6 | 15 | 12 | 12 | 12 | 12 |  | 50 Ohms-3 | TOP=L2:L3=L2/L4:L6=L5/L7:BOTTOM=L7 |
| SW_SSD5_N | 50OHM_Y12MIL | BUS | 6 | 6 | 5 | 10 | 5 | 14 | 6 | 15 | 12 | 12 | 12 | 12 |  | 50 Ohms-3 | TOP=L2:L3=L2/L4:L6=L5/L7:BOTTOM=L7 |
| SW_SSD5_N | 50OHM_Y12MIL | BUS | 7 | 6 | 5 | 10 | 5 | 14 | 6 | 15 | 12 | 12 | 12 | 12 |  | 50 Ohms-3 | TOP=L2:L3=L2/L4:L6=L5/L7:BOTTOM=L7 |
| SW_SSD5_N | 50OHM_Y12MIL | BUS | 8 | 6.75 | 5 | 10 | 5 | 14 | 6 | 15 | 12 | 12 | 12 | 12 |  | 50 Ohms-3 | TOP=L2:L3=L2/L4:L6=L5/L7:BOTTOM=L7 |
| SW_SSD5_R | 50OHM_Y12MIL | BUS | 1 | 6.75 | 5 | 10 | 5 | 14 | 6 | 15 | 12 | 12 | 12 | 12 |  | 50 Ohms-3 | TOP=L2:L3=L2/L4:L6=L5/L7:BOTTOM=L7 |
| SW_SSD5_R | 50OHM_Y12MIL | BUS | 2 | 6 | 5 | 10 | 5 | 14 | 6 | 15 | 12 | 12 | 12 | 12 |  | 50 Ohms-3 | TOP=L2:L3=L2/L4:L6=L5/L7:BOTTOM=L7 |
| SW_SSD5_R | 50OHM_Y12MIL | BUS | 3 | 6 | 5 | 10 | 5 | 14 | 6 | 15 | 12 | 12 | 12 | 12 |  | 50 Ohms-3 | TOP=L2:L3=L2/L4:L6=L5/L7:BOTTOM=L7 |
| SW_SSD5_R | 50OHM_Y12MIL | BUS | 4 | 6 | 5 | 10 | 5 | 14 | 6 | 15 | 12 | 12 | 12 | 12 |  | 50 Ohms-3 | TOP=L2:L3=L2/L4:L6=L5/L7:BOTTOM=L7 |
| SW_SSD5_R | 50OHM_Y12MIL | BUS | 5 | 6 | 5 | 10 | 5 | 14 | 6 | 15 | 12 | 12 | 12 | 12 |  | 50 Ohms-3 | TOP=L2:L3=L2/L4:L6=L5/L7:BOTTOM=L7 |
| SW_SSD5_R | 50OHM_Y12MIL | BUS | 6 | 6 | 5 | 10 | 5 | 14 | 6 | 15 | 12 | 12 | 12 | 12 |  | 50 Ohms-3 | TOP=L2:L3=L2/L4:L6=L5/L7:BOTTOM=L7 |
| SW_SSD5_R | 50OHM_Y12MIL | BUS | 7 | 6 | 5 | 10 | 5 | 14 | 6 | 15 | 12 | 12 | 12 | 12 |  | 50 Ohms-3 | TOP=L2:L3=L2/L4:L6=L5/L7:BOTTOM=L7 |
| SW_SSD5_R | 50OHM_Y12MIL | BUS | 8 | 6.75 | 5 | 10 | 5 | 14 | 6 | 15 | 12 | 12 | 12 | 12 |  | 50 Ohms-3 | TOP=L2:L3=L2/L4:L6=L5/L7:BOTTOM=L7 |
| SW_SSD6_N | 50OHM_Y12MIL | BUS | 1 | 6.75 | 5 | 10 | 5 | 14 | 6 | 15 | 12 | 12 | 12 | 12 |  | 50 Ohms-3 | TOP=L2:L3=L2/L4:L6=L5/L7:BOTTOM=L7 |
| SW_SSD6_N | 50OHM_Y12MIL | BUS | 2 | 6 | 5 | 10 | 5 | 14 | 6 | 15 | 12 | 12 | 12 | 12 |  | 50 Ohms-3 | TOP=L2:L3=L2/L4:L6=L5/L7:BOTTOM=L7 |
| SW_SSD6_N | 50OHM_Y12MIL | BUS | 3 | 6 | 5 | 10 | 5 | 14 | 6 | 15 | 12 | 12 | 12 | 12 |  | 50 Ohms-3 | TOP=L2:L3=L2/L4:L6=L5/L7:BOTTOM=L7 |
| SW_SSD6_N | 50OHM_Y12MIL | BUS | 4 | 6 | 5 | 10 | 5 | 14 | 6 | 15 | 12 | 12 | 12 | 12 |  | 50 Ohms-3 | TOP=L2:L3=L2/L4:L6=L5/L7:BOTTOM=L7 |
| SW_SSD6_N | 50OHM_Y12MIL | BUS | 5 | 6 | 5 | 10 | 5 | 14 | 6 | 15 | 12 | 12 | 12 | 12 |  | 50 Ohms-3 | TOP=L2:L3=L2/L4:L6=L5/L7:BOTTOM=L7 |
| SW_SSD6_N | 50OHM_Y12MIL | BUS | 6 | 6 | 5 | 10 | 5 | 14 | 6 | 15 | 12 | 12 | 12 | 12 |  | 50 Ohms-3 | TOP=L2:L3=L2/L4:L6=L5/L7:BOTTOM=L7 |
| SW_SSD6_N | 50OHM_Y12MIL | BUS | 7 | 6 | 5 | 10 | 5 | 14 | 6 | 15 | 12 | 12 | 12 | 12 |  | 50 Ohms-3 | TOP=L2:L3=L2/L4:L6=L5/L7:BOTTOM=L7 |
| SW_SSD6_N | 50OHM_Y12MIL | BUS | 8 | 6.75 | 5 | 10 | 5 | 14 | 6 | 15 | 12 | 12 | 12 | 12 |  | 50 Ohms-3 | TOP=L2:L3=L2/L4:L6=L5/L7:BOTTOM=L7 |
| SW_SSD6_R | 50OHM_Y12MIL | BUS | 1 | 6.75 | 5 | 10 | 5 | 14 | 6 | 15 | 12 | 12 | 12 | 12 |  | 50 Ohms-3 | TOP=L2:L3=L2/L4:L6=L5/L7:BOTTOM=L7 |
| SW_SSD6_R | 50OHM_Y12MIL | BUS | 2 | 6 | 5 | 10 | 5 | 14 | 6 | 15 | 12 | 12 | 12 | 12 |  | 50 Ohms-3 | TOP=L2:L3=L2/L4:L6=L5/L7:BOTTOM=L7 |
| SW_SSD6_R | 50OHM_Y12MIL | BUS | 3 | 6 | 5 | 10 | 5 | 14 | 6 | 15 | 12 | 12 | 12 | 12 |  | 50 Ohms-3 | TOP=L2:L3=L2/L4:L6=L5/L7:BOTTOM=L7 |
| SW_SSD6_R | 50OHM_Y12MIL | BUS | 4 | 6 | 5 | 10 | 5 | 14 | 6 | 15 | 12 | 12 | 12 | 12 |  | 50 Ohms-3 | TOP=L2:L3=L2/L4:L6=L5/L7:BOTTOM=L7 |
| SW_SSD6_R | 50OHM_Y12MIL | BUS | 5 | 6 | 5 | 10 | 5 | 14 | 6 | 15 | 12 | 12 | 12 | 12 |  | 50 Ohms-3 | TOP=L2:L3=L2/L4:L6=L5/L7:BOTTOM=L7 |
| SW_SSD6_R | 50OHM_Y12MIL | BUS | 6 | 6 | 5 | 10 | 5 | 14 | 6 | 15 | 12 | 12 | 12 | 12 |  | 50 Ohms-3 | TOP=L2:L3=L2/L4:L6=L5/L7:BOTTOM=L7 |
| SW_SSD6_R | 50OHM_Y12MIL | BUS | 7 | 6 | 5 | 10 | 5 | 14 | 6 | 15 | 12 | 12 | 12 | 12 |  | 50 Ohms-3 | TOP=L2:L3=L2/L4:L6=L5/L7:BOTTOM=L7 |
| SW_SSD6_R | 50OHM_Y12MIL | BUS | 8 | 6.75 | 5 | 10 | 5 | 14 | 6 | 15 | 12 | 12 | 12 | 12 |  | 50 Ohms-3 | TOP=L2:L3=L2/L4:L6=L5/L7:BOTTOM=L7 |
| SW_SSD7_N | 50OHM_Y12MIL | BUS | 1 | 6.75 | 5 | 10 | 5 | 14 | 6 | 15 | 12 | 12 | 12 | 12 |  | 50 Ohms-3 | TOP=L2:L3=L2/L4:L6=L5/L7:BOTTOM=L7 |
| SW_SSD7_N | 50OHM_Y12MIL | BUS | 2 | 6 | 5 | 10 | 5 | 14 | 6 | 15 | 12 | 12 | 12 | 12 |  | 50 Ohms-3 | TOP=L2:L3=L2/L4:L6=L5/L7:BOTTOM=L7 |
| SW_SSD7_N | 50OHM_Y12MIL | BUS | 3 | 6 | 5 | 10 | 5 | 14 | 6 | 15 | 12 | 12 | 12 | 12 |  | 50 Ohms-3 | TOP=L2:L3=L2/L4:L6=L5/L7:BOTTOM=L7 |
| SW_SSD7_N | 50OHM_Y12MIL | BUS | 4 | 6 | 5 | 10 | 5 | 14 | 6 | 15 | 12 | 12 | 12 | 12 |  | 50 Ohms-3 | TOP=L2:L3=L2/L4:L6=L5/L7:BOTTOM=L7 |
| SW_SSD7_N | 50OHM_Y12MIL | BUS | 5 | 6 | 5 | 10 | 5 | 14 | 6 | 15 | 12 | 12 | 12 | 12 |  | 50 Ohms-3 | TOP=L2:L3=L2/L4:L6=L5/L7:BOTTOM=L7 |
| SW_SSD7_N | 50OHM_Y12MIL | BUS | 6 | 6 | 5 | 10 | 5 | 14 | 6 | 15 | 12 | 12 | 12 | 12 |  | 50 Ohms-3 | TOP=L2:L3=L2/L4:L6=L5/L7:BOTTOM=L7 |
| SW_SSD7_N | 50OHM_Y12MIL | BUS | 7 | 6 | 5 | 10 | 5 | 14 | 6 | 15 | 12 | 12 | 12 | 12 |  | 50 Ohms-3 | TOP=L2:L3=L2/L4:L6=L5/L7:BOTTOM=L7 |
| SW_SSD7_N | 50OHM_Y12MIL | BUS | 8 | 6.75 | 5 | 10 | 5 | 14 | 6 | 15 | 12 | 12 | 12 | 12 |  | 50 Ohms-3 | TOP=L2:L3=L2/L4:L6=L5/L7:BOTTOM=L7 |
| SW_SSD7_R | 50OHM_Y12MIL | BUS | 1 | 6.75 | 5 | 10 | 5 | 14 | 6 | 15 | 12 | 12 | 12 | 12 |  | 50 Ohms-3 | TOP=L2:L3=L2/L4:L6=L5/L7:BOTTOM=L7 |
| SW_SSD7_R | 50OHM_Y12MIL | BUS | 2 | 6 | 5 | 10 | 5 | 14 | 6 | 15 | 12 | 12 | 12 | 12 |  | 50 Ohms-3 | TOP=L2:L3=L2/L4:L6=L5/L7:BOTTOM=L7 |
| SW_SSD7_R | 50OHM_Y12MIL | BUS | 3 | 6 | 5 | 10 | 5 | 14 | 6 | 15 | 12 | 12 | 12 | 12 |  | 50 Ohms-3 | TOP=L2:L3=L2/L4:L6=L5/L7:BOTTOM=L7 |
| SW_SSD7_R | 50OHM_Y12MIL | BUS | 4 | 6 | 5 | 10 | 5 | 14 | 6 | 15 | 12 | 12 | 12 | 12 |  | 50 Ohms-3 | TOP=L2:L3=L2/L4:L6=L5/L7:BOTTOM=L7 |
| SW_SSD7_R | 50OHM_Y12MIL | BUS | 5 | 6 | 5 | 10 | 5 | 14 | 6 | 15 | 12 | 12 | 12 | 12 |  | 50 Ohms-3 | TOP=L2:L3=L2/L4:L6=L5/L7:BOTTOM=L7 |
| SW_SSD7_R | 50OHM_Y12MIL | BUS | 6 | 6 | 5 | 10 | 5 | 14 | 6 | 15 | 12 | 12 | 12 | 12 |  | 50 Ohms-3 | TOP=L2:L3=L2/L4:L6=L5/L7:BOTTOM=L7 |
| SW_SSD7_R | 50OHM_Y12MIL | BUS | 7 | 6 | 5 | 10 | 5 | 14 | 6 | 15 | 12 | 12 | 12 | 12 |  | 50 Ohms-3 | TOP=L2:L3=L2/L4:L6=L5/L7:BOTTOM=L7 |
| SW_SSD7_R | 50OHM_Y12MIL | BUS | 8 | 6.75 | 5 | 10 | 5 | 14 | 6 | 15 | 12 | 12 | 12 | 12 |  | 50 Ohms-3 | TOP=L2:L3=L2/L4:L6=L5/L7:BOTTOM=L7 |
| SW_SSD8_N | 50OHM_Y12MIL | BUS | 1 | 6.75 | 5 | 10 | 5 | 14 | 6 | 15 | 12 | 12 | 12 | 12 |  | 50 Ohms-3 | TOP=L2:L3=L2/L4:L6=L5/L7:BOTTOM=L7 |
| SW_SSD8_N | 50OHM_Y12MIL | BUS | 2 | 6 | 5 | 10 | 5 | 14 | 6 | 15 | 12 | 12 | 12 | 12 |  | 50 Ohms-3 | TOP=L2:L3=L2/L4:L6=L5/L7:BOTTOM=L7 |
| SW_SSD8_N | 50OHM_Y12MIL | BUS | 3 | 6 | 5 | 10 | 5 | 14 | 6 | 15 | 12 | 12 | 12 | 12 |  | 50 Ohms-3 | TOP=L2:L3=L2/L4:L6=L5/L7:BOTTOM=L7 |
| SW_SSD8_N | 50OHM_Y12MIL | BUS | 4 | 6 | 5 | 10 | 5 | 14 | 6 | 15 | 12 | 12 | 12 | 12 |  | 50 Ohms-3 | TOP=L2:L3=L2/L4:L6=L5/L7:BOTTOM=L7 |
| SW_SSD8_N | 50OHM_Y12MIL | BUS | 5 | 6 | 5 | 10 | 5 | 14 | 6 | 15 | 12 | 12 | 12 | 12 |  | 50 Ohms-3 | TOP=L2:L3=L2/L4:L6=L5/L7:BOTTOM=L7 |
| SW_SSD8_N | 50OHM_Y12MIL | BUS | 6 | 6 | 5 | 10 | 5 | 14 | 6 | 15 | 12 | 12 | 12 | 12 |  | 50 Ohms-3 | TOP=L2:L3=L2/L4:L6=L5/L7:BOTTOM=L7 |
| SW_SSD8_N | 50OHM_Y12MIL | BUS | 7 | 6 | 5 | 10 | 5 | 14 | 6 | 15 | 12 | 12 | 12 | 12 |  | 50 Ohms-3 | TOP=L2:L3=L2/L4:L6=L5/L7:BOTTOM=L7 |
| SW_SSD8_N | 50OHM_Y12MIL | BUS | 8 | 6.75 | 5 | 10 | 5 | 14 | 6 | 15 | 12 | 12 | 12 | 12 |  | 50 Ohms-3 | TOP=L2:L3=L2/L4:L6=L5/L7:BOTTOM=L7 |
| SW_SSD8_R | 50OHM_Y12MIL | BUS | 1 | 6.75 | 5 | 10 | 5 | 14 | 6 | 15 | 12 | 12 | 12 | 12 |  | 50 Ohms-3 | TOP=L2:L3=L2/L4:L6=L5/L7:BOTTOM=L7 |
| SW_SSD8_R | 50OHM_Y12MIL | BUS | 2 | 6 | 5 | 10 | 5 | 14 | 6 | 15 | 12 | 12 | 12 | 12 |  | 50 Ohms-3 | TOP=L2:L3=L2/L4:L6=L5/L7:BOTTOM=L7 |
| SW_SSD8_R | 50OHM_Y12MIL | BUS | 3 | 6 | 5 | 10 | 5 | 14 | 6 | 15 | 12 | 12 | 12 | 12 |  | 50 Ohms-3 | TOP=L2:L3=L2/L4:L6=L5/L7:BOTTOM=L7 |
| SW_SSD8_R | 50OHM_Y12MIL | BUS | 4 | 6 | 5 | 10 | 5 | 14 | 6 | 15 | 12 | 12 | 12 | 12 |  | 50 Ohms-3 | TOP=L2:L3=L2/L4:L6=L5/L7:BOTTOM=L7 |
| SW_SSD8_R | 50OHM_Y12MIL | BUS | 5 | 6 | 5 | 10 | 5 | 14 | 6 | 15 | 12 | 12 | 12 | 12 |  | 50 Ohms-3 | TOP=L2:L3=L2/L4:L6=L5/L7:BOTTOM=L7 |
| SW_SSD8_R | 50OHM_Y12MIL | BUS | 6 | 6 | 5 | 10 | 5 | 14 | 6 | 15 | 12 | 12 | 12 | 12 |  | 50 Ohms-3 | TOP=L2:L3=L2/L4:L6=L5/L7:BOTTOM=L7 |
| SW_SSD8_R | 50OHM_Y12MIL | BUS | 7 | 6 | 5 | 10 | 5 | 14 | 6 | 15 | 12 | 12 | 12 | 12 |  | 50 Ohms-3 | TOP=L2:L3=L2/L4:L6=L5/L7:BOTTOM=L7 |
| SW_SSD8_R | 50OHM_Y12MIL | BUS | 8 | 6.75 | 5 | 10 | 5 | 14 | 6 | 15 | 12 | 12 | 12 | 12 |  | 50 Ohms-3 | TOP=L2:L3=L2/L4:L6=L5/L7:BOTTOM=L7 |
| SW_SSD9_N | 50OHM_Y12MIL | BUS | 1 | 6.75 | 5 | 10 | 5 | 14 | 6 | 15 | 12 | 12 | 12 | 12 |  | 50 Ohms-3 | TOP=L2:L3=L2/L4:L6=L5/L7:BOTTOM=L7 |
| SW_SSD9_N | 50OHM_Y12MIL | BUS | 2 | 6 | 5 | 10 | 5 | 14 | 6 | 15 | 12 | 12 | 12 | 12 |  | 50 Ohms-3 | TOP=L2:L3=L2/L4:L6=L5/L7:BOTTOM=L7 |
| SW_SSD9_N | 50OHM_Y12MIL | BUS | 3 | 6 | 5 | 10 | 5 | 14 | 6 | 15 | 12 | 12 | 12 | 12 |  | 50 Ohms-3 | TOP=L2:L3=L2/L4:L6=L5/L7:BOTTOM=L7 |
| SW_SSD9_N | 50OHM_Y12MIL | BUS | 4 | 6 | 5 | 10 | 5 | 14 | 6 | 15 | 12 | 12 | 12 | 12 |  | 50 Ohms-3 | TOP=L2:L3=L2/L4:L6=L5/L7:BOTTOM=L7 |
| SW_SSD9_N | 50OHM_Y12MIL | BUS | 5 | 6 | 5 | 10 | 5 | 14 | 6 | 15 | 12 | 12 | 12 | 12 |  | 50 Ohms-3 | TOP=L2:L3=L2/L4:L6=L5/L7:BOTTOM=L7 |
| SW_SSD9_N | 50OHM_Y12MIL | BUS | 6 | 6 | 5 | 10 | 5 | 14 | 6 | 15 | 12 | 12 | 12 | 12 |  | 50 Ohms-3 | TOP=L2:L3=L2/L4:L6=L5/L7:BOTTOM=L7 |
| SW_SSD9_N | 50OHM_Y12MIL | BUS | 7 | 6 | 5 | 10 | 5 | 14 | 6 | 15 | 12 | 12 | 12 | 12 |  | 50 Ohms-3 | TOP=L2:L3=L2/L4:L6=L5/L7:BOTTOM=L7 |
| SW_SSD9_N | 50OHM_Y12MIL | BUS | 8 | 6.75 | 5 | 10 | 5 | 14 | 6 | 15 | 12 | 12 | 12 | 12 |  | 50 Ohms-3 | TOP=L2:L3=L2/L4:L6=L5/L7:BOTTOM=L7 |
| SW_SSD9_R | 50OHM_Y12MIL | BUS | 1 | 6.75 | 5 | 10 | 5 | 14 | 6 | 15 | 12 | 12 | 12 | 12 |  | 50 Ohms-3 | TOP=L2:L3=L2/L4:L6=L5/L7:BOTTOM=L7 |
| SW_SSD9_R | 50OHM_Y12MIL | BUS | 2 | 6 | 5 | 10 | 5 | 14 | 6 | 15 | 12 | 12 | 12 | 12 |  | 50 Ohms-3 | TOP=L2:L3=L2/L4:L6=L5/L7:BOTTOM=L7 |
| SW_SSD9_R | 50OHM_Y12MIL | BUS | 3 | 6 | 5 | 10 | 5 | 14 | 6 | 15 | 12 | 12 | 12 | 12 |  | 50 Ohms-3 | TOP=L2:L3=L2/L4:L6=L5/L7:BOTTOM=L7 |
| SW_SSD9_R | 50OHM_Y12MIL | BUS | 4 | 6 | 5 | 10 | 5 | 14 | 6 | 15 | 12 | 12 | 12 | 12 |  | 50 Ohms-3 | TOP=L2:L3=L2/L4:L6=L5/L7:BOTTOM=L7 |
| SW_SSD9_R | 50OHM_Y12MIL | BUS | 5 | 6 | 5 | 10 | 5 | 14 | 6 | 15 | 12 | 12 | 12 | 12 |  | 50 Ohms-3 | TOP=L2:L3=L2/L4:L6=L5/L7:BOTTOM=L7 |
| SW_SSD9_R | 50OHM_Y12MIL | BUS | 6 | 6 | 5 | 10 | 5 | 14 | 6 | 15 | 12 | 12 | 12 | 12 |  | 50 Ohms-3 | TOP=L2:L3=L2/L4:L6=L5/L7:BOTTOM=L7 |
| SW_SSD9_R | 50OHM_Y12MIL | BUS | 7 | 6 | 5 | 10 | 5 | 14 | 6 | 15 | 12 | 12 | 12 | 12 |  | 50 Ohms-3 | TOP=L2:L3=L2/L4:L6=L5/L7:BOTTOM=L7 |
| SW_SSD9_R | 50OHM_Y12MIL | BUS | 8 | 6.75 | 5 | 10 | 5 | 14 | 6 | 15 | 12 | 12 | 12 | 12 |  | 50 Ohms-3 | TOP=L2:L3=L2/L4:L6=L5/L7:BOTTOM=L7 |
| TRAY_ID | 50OHM_Y12MIL | BUS | 1 | 6.75 | 5 | 10 | 5 | 14 | 6 | 15 | 12 | 12 | 12 | 12 |  | 50 Ohms-3 | TOP=L2:L3=L2/L4:L6=L5/L7:BOTTOM=L7 |
| TRAY_ID | 50OHM_Y12MIL | BUS | 2 | 6 | 5 | 10 | 5 | 14 | 6 | 15 | 12 | 12 | 12 | 12 |  | 50 Ohms-3 | TOP=L2:L3=L2/L4:L6=L5/L7:BOTTOM=L7 |
| TRAY_ID | 50OHM_Y12MIL | BUS | 3 | 6 | 5 | 10 | 5 | 14 | 6 | 15 | 12 | 12 | 12 | 12 |  | 50 Ohms-3 | TOP=L2:L3=L2/L4:L6=L5/L7:BOTTOM=L7 |
| TRAY_ID | 50OHM_Y12MIL | BUS | 4 | 6 | 5 | 10 | 5 | 14 | 6 | 15 | 12 | 12 | 12 | 12 |  | 50 Ohms-3 | TOP=L2:L3=L2/L4:L6=L5/L7:BOTTOM=L7 |
| TRAY_ID | 50OHM_Y12MIL | BUS | 5 | 6 | 5 | 10 | 5 | 14 | 6 | 15 | 12 | 12 | 12 | 12 |  | 50 Ohms-3 | TOP=L2:L3=L2/L4:L6=L5/L7:BOTTOM=L7 |
| TRAY_ID | 50OHM_Y12MIL | BUS | 6 | 6 | 5 | 10 | 5 | 14 | 6 | 15 | 12 | 12 | 12 | 12 |  | 50 Ohms-3 | TOP=L2:L3=L2/L4:L6=L5/L7:BOTTOM=L7 |
| TRAY_ID | 50OHM_Y12MIL | BUS | 7 | 6 | 5 | 10 | 5 | 14 | 6 | 15 | 12 | 12 | 12 | 12 |  | 50 Ohms-3 | TOP=L2:L3=L2/L4:L6=L5/L7:BOTTOM=L7 |
| TRAY_ID | 50OHM_Y12MIL | BUS | 8 | 6.75 | 5 | 10 | 5 | 14 | 6 | 15 | 12 | 12 | 12 | 12 |  | 50 Ohms-3 | TOP=L2:L3=L2/L4:L6=L5/L7:BOTTOM=L7 |
| TRAY_ID_R | 50OHM_Y12MIL | BUS | 1 | 6.75 | 5 | 10 | 5 | 14 | 6 | 15 | 12 | 12 | 12 | 12 |  | 50 Ohms-3 | TOP=L2:L3=L2/L4:L6=L5/L7:BOTTOM=L7 |
| TRAY_ID_R | 50OHM_Y12MIL | BUS | 2 | 6 | 5 | 10 | 5 | 14 | 6 | 15 | 12 | 12 | 12 | 12 |  | 50 Ohms-3 | TOP=L2:L3=L2/L4:L6=L5/L7:BOTTOM=L7 |
| TRAY_ID_R | 50OHM_Y12MIL | BUS | 3 | 6 | 5 | 10 | 5 | 14 | 6 | 15 | 12 | 12 | 12 | 12 |  | 50 Ohms-3 | TOP=L2:L3=L2/L4:L6=L5/L7:BOTTOM=L7 |
| TRAY_ID_R | 50OHM_Y12MIL | BUS | 4 | 6 | 5 | 10 | 5 | 14 | 6 | 15 | 12 | 12 | 12 | 12 |  | 50 Ohms-3 | TOP=L2:L3=L2/L4:L6=L5/L7:BOTTOM=L7 |
| TRAY_ID_R | 50OHM_Y12MIL | BUS | 5 | 6 | 5 | 10 | 5 | 14 | 6 | 15 | 12 | 12 | 12 | 12 |  | 50 Ohms-3 | TOP=L2:L3=L2/L4:L6=L5/L7:BOTTOM=L7 |
| TRAY_ID_R | 50OHM_Y12MIL | BUS | 6 | 6 | 5 | 10 | 5 | 14 | 6 | 15 | 12 | 12 | 12 | 12 |  | 50 Ohms-3 | TOP=L2:L3=L2/L4:L6=L5/L7:BOTTOM=L7 |
| TRAY_ID_R | 50OHM_Y12MIL | BUS | 7 | 6 | 5 | 10 | 5 | 14 | 6 | 15 | 12 | 12 | 12 | 12 |  | 50 Ohms-3 | TOP=L2:L3=L2/L4:L6=L5/L7:BOTTOM=L7 |
| TRAY_ID_R | 50OHM_Y12MIL | BUS | 8 | 6.75 | 5 | 10 | 5 | 14 | 6 | 15 | 12 | 12 | 12 | 12 |  | 50 Ohms-3 | TOP=L2:L3=L2/L4:L6=L5/L7:BOTTOM=L7 |
| VOL_SEN_ADDR | 50OHM_Y12MIL | BUS | 1 | 6.75 | 5 | 10 | 5 | 14 | 6 | 15 | 12 | 12 | 12 | 12 |  | 50 Ohms-3 | TOP=L2:L3=L2/L4:L6=L5/L7:BOTTOM=L7 |
| VOL_SEN_ADDR | 50OHM_Y12MIL | BUS | 2 | 6 | 5 | 10 | 5 | 14 | 6 | 15 | 12 | 12 | 12 | 12 |  | 50 Ohms-3 | TOP=L2:L3=L2/L4:L6=L5/L7:BOTTOM=L7 |
| VOL_SEN_ADDR | 50OHM_Y12MIL | BUS | 3 | 6 | 5 | 10 | 5 | 14 | 6 | 15 | 12 | 12 | 12 | 12 |  | 50 Ohms-3 | TOP=L2:L3=L2/L4:L6=L5/L7:BOTTOM=L7 |
| VOL_SEN_ADDR | 50OHM_Y12MIL | BUS | 4 | 6 | 5 | 10 | 5 | 14 | 6 | 15 | 12 | 12 | 12 | 12 |  | 50 Ohms-3 | TOP=L2:L3=L2/L4:L6=L5/L7:BOTTOM=L7 |
| VOL_SEN_ADDR | 50OHM_Y12MIL | BUS | 5 | 6 | 5 | 10 | 5 | 14 | 6 | 15 | 12 | 12 | 12 | 12 |  | 50 Ohms-3 | TOP=L2:L3=L2/L4:L6=L5/L7:BOTTOM=L7 |
| VOL_SEN_ADDR | 50OHM_Y12MIL | BUS | 6 | 6 | 5 | 10 | 5 | 14 | 6 | 15 | 12 | 12 | 12 | 12 |  | 50 Ohms-3 | TOP=L2:L3=L2/L4:L6=L5/L7:BOTTOM=L7 |
| VOL_SEN_ADDR | 50OHM_Y12MIL | BUS | 7 | 6 | 5 | 10 | 5 | 14 | 6 | 15 | 12 | 12 | 12 | 12 |  | 50 Ohms-3 | TOP=L2:L3=L2/L4:L6=L5/L7:BOTTOM=L7 |
| VOL_SEN_ADDR | 50OHM_Y12MIL | BUS | 8 | 6.75 | 5 | 10 | 5 | 14 | 6 | 15 | 12 | 12 | 12 | 12 |  | 50 Ohms-3 | TOP=L2:L3=L2/L4:L6=L5/L7:BOTTOM=L7 |
| VOL_SEN_ALERT | 50OHM_Y12MIL | BUS | 1 | 6.75 | 5 | 10 | 5 | 14 | 6 | 15 | 12 | 12 | 12 | 12 |  | 50 Ohms-3 | TOP=L2:L3=L2/L4:L6=L5/L7:BOTTOM=L7 |
| VOL_SEN_ALERT | 50OHM_Y12MIL | BUS | 2 | 6 | 5 | 10 | 5 | 14 | 6 | 15 | 12 | 12 | 12 | 12 |  | 50 Ohms-3 | TOP=L2:L3=L2/L4:L6=L5/L7:BOTTOM=L7 |
| VOL_SEN_ALERT | 50OHM_Y12MIL | BUS | 3 | 6 | 5 | 10 | 5 | 14 | 6 | 15 | 12 | 12 | 12 | 12 |  | 50 Ohms-3 | TOP=L2:L3=L2/L4:L6=L5/L7:BOTTOM=L7 |
| VOL_SEN_ALERT | 50OHM_Y12MIL | BUS | 4 | 6 | 5 | 10 | 5 | 14 | 6 | 15 | 12 | 12 | 12 | 12 |  | 50 Ohms-3 | TOP=L2:L3=L2/L4:L6=L5/L7:BOTTOM=L7 |
| VOL_SEN_ALERT | 50OHM_Y12MIL | BUS | 5 | 6 | 5 | 10 | 5 | 14 | 6 | 15 | 12 | 12 | 12 | 12 |  | 50 Ohms-3 | TOP=L2:L3=L2/L4:L6=L5/L7:BOTTOM=L7 |
| VOL_SEN_ALERT | 50OHM_Y12MIL | BUS | 6 | 6 | 5 | 10 | 5 | 14 | 6 | 15 | 12 | 12 | 12 | 12 |  | 50 Ohms-3 | TOP=L2:L3=L2/L4:L6=L5/L7:BOTTOM=L7 |
| VOL_SEN_ALERT | 50OHM_Y12MIL | BUS | 7 | 6 | 5 | 10 | 5 | 14 | 6 | 15 | 12 | 12 | 12 | 12 |  | 50 Ohms-3 | TOP=L2:L3=L2/L4:L6=L5/L7:BOTTOM=L7 |
| VOL_SEN_ALERT | 50OHM_Y12MIL | BUS | 8 | 6.75 | 5 | 10 | 5 | 14 | 6 | 15 | 12 | 12 | 12 | 12 |  | 50 Ohms-3 | TOP=L2:L3=L2/L4:L6=L5/L7:BOTTOM=L7 |
| VOL_SEN_SCL | 50OHM_Y12MIL | BUS | 1 | 6.75 | 5 | 10 | 5 | 14 | 6 | 15 | 12 | 12 | 12 | 12 |  | 50 Ohms-3 | TOP=L2:L3=L2/L4:L6=L5/L7:BOTTOM=L7 |
| VOL_SEN_SCL | 50OHM_Y12MIL | BUS | 2 | 6 | 5 | 10 | 5 | 14 | 6 | 15 | 12 | 12 | 12 | 12 |  | 50 Ohms-3 | TOP=L2:L3=L2/L4:L6=L5/L7:BOTTOM=L7 |
| VOL_SEN_SCL | 50OHM_Y12MIL | BUS | 3 | 6 | 5 | 10 | 5 | 14 | 6 | 15 | 12 | 12 | 12 | 12 |  | 50 Ohms-3 | TOP=L2:L3=L2/L4:L6=L5/L7:BOTTOM=L7 |
| VOL_SEN_SCL | 50OHM_Y12MIL | BUS | 4 | 6 | 5 | 10 | 5 | 14 | 6 | 15 | 12 | 12 | 12 | 12 |  | 50 Ohms-3 | TOP=L2:L3=L2/L4:L6=L5/L7:BOTTOM=L7 |
| VOL_SEN_SCL | 50OHM_Y12MIL | BUS | 5 | 6 | 5 | 10 | 5 | 14 | 6 | 15 | 12 | 12 | 12 | 12 |  | 50 Ohms-3 | TOP=L2:L3=L2/L4:L6=L5/L7:BOTTOM=L7 |
| VOL_SEN_SCL | 50OHM_Y12MIL | BUS | 6 | 6 | 5 | 10 | 5 | 14 | 6 | 15 | 12 | 12 | 12 | 12 |  | 50 Ohms-3 | TOP=L2:L3=L2/L4:L6=L5/L7:BOTTOM=L7 |
| VOL_SEN_SCL | 50OHM_Y12MIL | BUS | 7 | 6 | 5 | 10 | 5 | 14 | 6 | 15 | 12 | 12 | 12 | 12 |  | 50 Ohms-3 | TOP=L2:L3=L2/L4:L6=L5/L7:BOTTOM=L7 |
| VOL_SEN_SCL | 50OHM_Y12MIL | BUS | 8 | 6.75 | 5 | 10 | 5 | 14 | 6 | 15 | 12 | 12 | 12 | 12 |  | 50 Ohms-3 | TOP=L2:L3=L2/L4:L6=L5/L7:BOTTOM=L7 |
| VOL_SEN_SDA | 50OHM_Y12MIL | BUS | 1 | 6.75 | 5 | 10 | 5 | 14 | 6 | 15 | 12 | 12 | 12 | 12 |  | 50 Ohms-3 | TOP=L2:L3=L2/L4:L6=L5/L7:BOTTOM=L7 |
| VOL_SEN_SDA | 50OHM_Y12MIL | BUS | 2 | 6 | 5 | 10 | 5 | 14 | 6 | 15 | 12 | 12 | 12 | 12 |  | 50 Ohms-3 | TOP=L2:L3=L2/L4:L6=L5/L7:BOTTOM=L7 |
| VOL_SEN_SDA | 50OHM_Y12MIL | BUS | 3 | 6 | 5 | 10 | 5 | 14 | 6 | 15 | 12 | 12 | 12 | 12 |  | 50 Ohms-3 | TOP=L2:L3=L2/L4:L6=L5/L7:BOTTOM=L7 |
| VOL_SEN_SDA | 50OHM_Y12MIL | BUS | 4 | 6 | 5 | 10 | 5 | 14 | 6 | 15 | 12 | 12 | 12 | 12 |  | 50 Ohms-3 | TOP=L2:L3=L2/L4:L6=L5/L7:BOTTOM=L7 |
| VOL_SEN_SDA | 50OHM_Y12MIL | BUS | 5 | 6 | 5 | 10 | 5 | 14 | 6 | 15 | 12 | 12 | 12 | 12 |  | 50 Ohms-3 | TOP=L2:L3=L2/L4:L6=L5/L7:BOTTOM=L7 |
| VOL_SEN_SDA | 50OHM_Y12MIL | BUS | 6 | 6 | 5 | 10 | 5 | 14 | 6 | 15 | 12 | 12 | 12 | 12 |  | 50 Ohms-3 | TOP=L2:L3=L2/L4:L6=L5/L7:BOTTOM=L7 |
| VOL_SEN_SDA | 50OHM_Y12MIL | BUS | 7 | 6 | 5 | 10 | 5 | 14 | 6 | 15 | 12 | 12 | 12 | 12 |  | 50 Ohms-3 | TOP=L2:L3=L2/L4:L6=L5/L7:BOTTOM=L7 |
| VOL_SEN_SDA | 50OHM_Y12MIL | BUS | 8 | 6.75 | 5 | 10 | 5 | 14 | 6 | 15 | 12 | 12 | 12 | 12 |  | 50 Ohms-3 | TOP=L2:L3=L2/L4:L6=L5/L7:BOTTOM=L7 |
| N70914768 | 50OHM_Y5MIL | BUS | 1 | 6.75 | 5 | 10 | 5 | 14 | 6 | 5 | 12 | 12 | 12 | 12 |  | 50 Ohms-1 | TOP=L2:L3=L2/L4:L6=L5/L7:BOTTOM=L7 |
| N70914768 | 50OHM_Y5MIL | BUS | 2 | 6 | 5 | 10 | 5 | 14 | 6 | 5 | 12 | 12 | 12 | 12 |  | 50 Ohms-1 | TOP=L2:L3=L2/L4:L6=L5/L7:BOTTOM=L7 |
| N70914768 | 50OHM_Y5MIL | BUS | 3 | 6 | 5 | 10 | 5 | 14 | 6 | 5 | 12 | 12 | 12 | 12 |  | 50 Ohms-1 | TOP=L2:L3=L2/L4:L6=L5/L7:BOTTOM=L7 |
| N70914768 | 50OHM_Y5MIL | BUS | 4 | 6 | 5 | 10 | 5 | 14 | 6 | 5 | 12 | 12 | 12 | 12 |  | 50 Ohms-1 | TOP=L2:L3=L2/L4:L6=L5/L7:BOTTOM=L7 |
| N70914768 | 50OHM_Y5MIL | BUS | 5 | 6 | 5 | 10 | 5 | 14 | 6 | 5 | 12 | 12 | 12 | 12 |  | 50 Ohms-1 | TOP=L2:L3=L2/L4:L6=L5/L7:BOTTOM=L7 |
| N70914768 | 50OHM_Y5MIL | BUS | 6 | 6 | 5 | 10 | 5 | 14 | 6 | 5 | 12 | 12 | 12 | 12 |  | 50 Ohms-1 | TOP=L2:L3=L2/L4:L6=L5/L7:BOTTOM=L7 |
| N70914768 | 50OHM_Y5MIL | BUS | 7 | 6 | 5 | 10 | 5 | 14 | 6 | 2 | 12 | 12 | 12 | 12 |  | 50 Ohms-1 | TOP=L2:L3=L2/L4:L6=L5/L7:BOTTOM=L7 |
| N70914768 | 50OHM_Y5MIL | BUS | 8 | 6.75 | 5 | 10 | 5 | 14 | 6 | 5 | 12 | 12 | 12 | 12 |  | 50 Ohms-1 | TOP=L2:L3=L2/L4:L6=L5/L7:BOTTOM=L7 |
| N70929042 | 50OHM_Y5MIL | BUS | 1 | 6.75 | 5 | 10 | 5 | 14 | 6 | 5 | 12 | 12 | 12 | 12 |  | 50 Ohms-1 | TOP=L2:L3=L2/L4:L6=L5/L7:BOTTOM=L7 |
| N70929042 | 50OHM_Y5MIL | BUS | 2 | 6 | 5 | 10 | 5 | 14 | 6 | 5 | 12 | 12 | 12 | 12 |  | 50 Ohms-1 | TOP=L2:L3=L2/L4:L6=L5/L7:BOTTOM=L7 |
| N70929042 | 50OHM_Y5MIL | BUS | 3 | 6 | 5 | 10 | 5 | 14 | 6 | 5 | 12 | 12 | 12 | 12 |  | 50 Ohms-1 | TOP=L2:L3=L2/L4:L6=L5/L7:BOTTOM=L7 |
| N70929042 | 50OHM_Y5MIL | BUS | 4 | 6 | 5 | 10 | 5 | 14 | 6 | 5 | 12 | 12 | 12 | 12 |  | 50 Ohms-1 | TOP=L2:L3=L2/L4:L6=L5/L7:BOTTOM=L7 |
| N70929042 | 50OHM_Y5MIL | BUS | 5 | 6 | 5 | 10 | 5 | 14 | 6 | 5 | 12 | 12 | 12 | 12 |  | 50 Ohms-1 | TOP=L2:L3=L2/L4:L6=L5/L7:BOTTOM=L7 |
| N70929042 | 50OHM_Y5MIL | BUS | 6 | 6 | 5 | 10 | 5 | 14 | 6 | 5 | 12 | 12 | 12 | 12 |  | 50 Ohms-1 | TOP=L2:L3=L2/L4:L6=L5/L7:BOTTOM=L7 |
| N70929042 | 50OHM_Y5MIL | BUS | 7 | 6 | 5 | 10 | 5 | 14 | 6 | 2 | 12 | 12 | 12 | 12 |  | 50 Ohms-1 | TOP=L2:L3=L2/L4:L6=L5/L7:BOTTOM=L7 |
| N70929042 | 50OHM_Y5MIL | BUS | 8 | 6.75 | 5 | 10 | 5 | 14 | 6 | 5 | 12 | 12 | 12 | 12 |  | 50 Ohms-1 | TOP=L2:L3=L2/L4:L6=L5/L7:BOTTOM=L7 |
| N70930468 | 50OHM_Y5MIL | BUS | 1 | 6.75 | 5 | 10 | 5 | 14 | 6 | 5 | 12 | 12 | 12 | 12 |  | 50 Ohms-1 | TOP=L2:L3=L2/L4:L6=L5/L7:BOTTOM=L7 |
| N70930468 | 50OHM_Y5MIL | BUS | 2 | 6 | 5 | 10 | 5 | 14 | 6 | 5 | 12 | 12 | 12 | 12 |  | 50 Ohms-1 | TOP=L2:L3=L2/L4:L6=L5/L7:BOTTOM=L7 |
| N70930468 | 50OHM_Y5MIL | BUS | 3 | 6 | 5 | 10 | 5 | 14 | 6 | 5 | 12 | 12 | 12 | 12 |  | 50 Ohms-1 | TOP=L2:L3=L2/L4:L6=L5/L7:BOTTOM=L7 |
| N70930468 | 50OHM_Y5MIL | BUS | 4 | 6 | 5 | 10 | 5 | 14 | 6 | 5 | 12 | 12 | 12 | 12 |  | 50 Ohms-1 | TOP=L2:L3=L2/L4:L6=L5/L7:BOTTOM=L7 |
| N70930468 | 50OHM_Y5MIL | BUS | 5 | 6 | 5 | 10 | 5 | 14 | 6 | 5 | 12 | 12 | 12 | 12 |  | 50 Ohms-1 | TOP=L2:L3=L2/L4:L6=L5/L7:BOTTOM=L7 |
| N70930468 | 50OHM_Y5MIL | BUS | 6 | 6 | 5 | 10 | 5 | 14 | 6 | 5 | 12 | 12 | 12 | 12 |  | 50 Ohms-1 | TOP=L2:L3=L2/L4:L6=L5/L7:BOTTOM=L7 |
| N70930468 | 50OHM_Y5MIL | BUS | 7 | 6 | 5 | 10 | 5 | 14 | 6 | 2 | 12 | 12 | 12 | 12 |  | 50 Ohms-1 | TOP=L2:L3=L2/L4:L6=L5/L7:BOTTOM=L7 |
| N70930468 | 50OHM_Y5MIL | BUS | 8 | 6.75 | 5 | 10 | 5 | 14 | 6 | 5 | 12 | 12 | 12 | 12 |  | 50 Ohms-1 | TOP=L2:L3=L2/L4:L6=L5/L7:BOTTOM=L7 |
| BMC_I2C_SCL_BUF_8 | BMC_I2C_BUF_8-DIFF1 | PAIR | 1 | 6.75 | 5 | 10 | 5 | 14 | 6 | 15 | 12 | 12 | 12 | 12 | 15 |  |  |
| BMC_I2C_SCL_BUF_8 | BMC_I2C_BUF_8-DIFF1 | PAIR | 2 | 6 | 5 | 10 | 5 | 14 | 6 | 15 | 12 | 12 | 12 | 12 | 15 |  |  |
| BMC_I2C_SCL_BUF_8 | BMC_I2C_BUF_8-DIFF1 | PAIR | 3 | 6 | 5 | 10 | 5 | 14 | 6 | 15 | 12 | 12 | 12 | 12 | 15 |  |  |
| BMC_I2C_SCL_BUF_8 | BMC_I2C_BUF_8-DIFF1 | PAIR | 4 | 6 | 5 | 10 | 5 | 14 | 6 | 15 | 12 | 12 | 12 | 12 | 15 |  |  |
| BMC_I2C_SCL_BUF_8 | BMC_I2C_BUF_8-DIFF1 | PAIR | 5 | 6 | 5 | 10 | 5 | 14 | 6 | 15 | 12 | 12 | 12 | 12 | 15 |  |  |
| BMC_I2C_SCL_BUF_8 | BMC_I2C_BUF_8-DIFF1 | PAIR | 6 | 6 | 5 | 10 | 5 | 14 | 6 | 15 | 12 | 12 | 12 | 12 | 15 |  |  |
| BMC_I2C_SCL_BUF_8 | BMC_I2C_BUF_8-DIFF1 | PAIR | 7 | 6 | 5 | 10 | 5 | 14 | 6 | 15 | 12 | 12 | 12 | 12 | 15 |  |  |
| BMC_I2C_SCL_BUF_8 | BMC_I2C_BUF_8-DIFF1 | PAIR | 8 | 6.75 | 5 | 10 | 5 | 14 | 6 | 15 | 12 | 12 | 12 | 12 | 15 |  |  |
| BMC_I2C_SDA_BUF_8 | BMC_I2C_BUF_8-DIFF1 | PAIR | 1 | 6.75 | 5 | 10 | 5 | 14 | 6 | 15 | 12 | 12 | 12 | 12 | 15 |  |  |
| BMC_I2C_SDA_BUF_8 | BMC_I2C_BUF_8-DIFF1 | PAIR | 2 | 6 | 5 | 10 | 5 | 14 | 6 | 15 | 12 | 12 | 12 | 12 | 15 |  |  |
| BMC_I2C_SDA_BUF_8 | BMC_I2C_BUF_8-DIFF1 | PAIR | 3 | 6 | 5 | 10 | 5 | 14 | 6 | 15 | 12 | 12 | 12 | 12 | 15 |  |  |
| BMC_I2C_SDA_BUF_8 | BMC_I2C_BUF_8-DIFF1 | PAIR | 4 | 6 | 5 | 10 | 5 | 14 | 6 | 15 | 12 | 12 | 12 | 12 | 15 |  |  |
| BMC_I2C_SDA_BUF_8 | BMC_I2C_BUF_8-DIFF1 | PAIR | 5 | 6 | 5 | 10 | 5 | 14 | 6 | 15 | 12 | 12 | 12 | 12 | 15 |  |  |
| BMC_I2C_SDA_BUF_8 | BMC_I2C_BUF_8-DIFF1 | PAIR | 6 | 6 | 5 | 10 | 5 | 14 | 6 | 15 | 12 | 12 | 12 | 12 | 15 |  |  |
| BMC_I2C_SDA_BUF_8 | BMC_I2C_BUF_8-DIFF1 | PAIR | 7 | 6 | 5 | 10 | 5 | 14 | 6 | 15 | 12 | 12 | 12 | 12 | 15 |  |  |
| BMC_I2C_SDA_BUF_8 | BMC_I2C_BUF_8-DIFF1 | PAIR | 8 | 6.75 | 5 | 10 | 5 | 14 | 6 | 15 | 12 | 12 | 12 | 12 | 15 |  |  |
| BMC_I2C_SCL_BUF_9 | BMC_I2C_BUF_9-DIFF1 | PAIR | 1 | 6.75 | 5 | 10 | 5 | 14 | 6 | 15 | 12 | 12 | 12 | 12 | 15 |  |  |
| BMC_I2C_SCL_BUF_9 | BMC_I2C_BUF_9-DIFF1 | PAIR | 2 | 6 | 5 | 10 | 5 | 14 | 6 | 15 | 12 | 12 | 12 | 12 | 15 |  |  |
| BMC_I2C_SCL_BUF_9 | BMC_I2C_BUF_9-DIFF1 | PAIR | 3 | 6 | 5 | 10 | 5 | 14 | 6 | 15 | 12 | 12 | 12 | 12 | 15 |  |  |
| BMC_I2C_SCL_BUF_9 | BMC_I2C_BUF_9-DIFF1 | PAIR | 4 | 6 | 5 | 10 | 5 | 14 | 6 | 15 | 12 | 12 | 12 | 12 | 15 |  |  |
| BMC_I2C_SCL_BUF_9 | BMC_I2C_BUF_9-DIFF1 | PAIR | 5 | 6 | 5 | 10 | 5 | 14 | 6 | 15 | 12 | 12 | 12 | 12 | 15 |  |  |
| BMC_I2C_SCL_BUF_9 | BMC_I2C_BUF_9-DIFF1 | PAIR | 6 | 6 | 5 | 10 | 5 | 14 | 6 | 15 | 12 | 12 | 12 | 12 | 15 |  |  |
| BMC_I2C_SCL_BUF_9 | BMC_I2C_BUF_9-DIFF1 | PAIR | 7 | 6 | 5 | 10 | 5 | 14 | 6 | 15 | 12 | 12 | 12 | 12 | 15 |  |  |
| BMC_I2C_SCL_BUF_9 | BMC_I2C_BUF_9-DIFF1 | PAIR | 8 | 6.75 | 5 | 10 | 5 | 14 | 6 | 15 | 12 | 12 | 12 | 12 | 15 |  |  |
| BMC_I2C_SDA_BUF_9 | BMC_I2C_BUF_9-DIFF1 | PAIR | 1 | 6.75 | 5 | 10 | 5 | 14 | 6 | 15 | 12 | 12 | 12 | 12 | 15 |  |  |
| BMC_I2C_SDA_BUF_9 | BMC_I2C_BUF_9-DIFF1 | PAIR | 2 | 6 | 5 | 10 | 5 | 14 | 6 | 15 | 12 | 12 | 12 | 12 | 15 |  |  |
| BMC_I2C_SDA_BUF_9 | BMC_I2C_BUF_9-DIFF1 | PAIR | 3 | 6 | 5 | 10 | 5 | 14 | 6 | 15 | 12 | 12 | 12 | 12 | 15 |  |  |
| BMC_I2C_SDA_BUF_9 | BMC_I2C_BUF_9-DIFF1 | PAIR | 4 | 6 | 5 | 10 | 5 | 14 | 6 | 15 | 12 | 12 | 12 | 12 | 15 |  |  |
| BMC_I2C_SDA_BUF_9 | BMC_I2C_BUF_9-DIFF1 | PAIR | 5 | 6 | 5 | 10 | 5 | 14 | 6 | 15 | 12 | 12 | 12 | 12 | 15 |  |  |
| BMC_I2C_SDA_BUF_9 | BMC_I2C_BUF_9-DIFF1 | PAIR | 6 | 6 | 5 | 10 | 5 | 14 | 6 | 15 | 12 | 12 | 12 | 12 | 15 |  |  |
| BMC_I2C_SDA_BUF_9 | BMC_I2C_BUF_9-DIFF1 | PAIR | 7 | 6 | 5 | 10 | 5 | 14 | 6 | 15 | 12 | 12 | 12 | 12 | 15 |  |  |
| BMC_I2C_SDA_BUF_9 | BMC_I2C_BUF_9-DIFF1 | PAIR | 8 | 6.75 | 5 | 10 | 5 | 14 | 6 | 15 | 12 | 12 | 12 | 12 | 15 |  |  |
| I2C_SCL_BUF_9_EU1_R | I2C_9_CLKBUF_EU1_R-DIFF1 | PAIR | 1 | 6.75 | 5 | 10 | 5 | 14 | 6 | 15 | 12 | 12 | 12 | 12 | 15 |  |  |
| I2C_SCL_BUF_9_EU1_R | I2C_9_CLKBUF_EU1_R-DIFF1 | PAIR | 2 | 6 | 5 | 10 | 5 | 14 | 6 | 15 | 12 | 12 | 12 | 12 | 15 |  |  |
| I2C_SCL_BUF_9_EU1_R | I2C_9_CLKBUF_EU1_R-DIFF1 | PAIR | 3 | 6 | 5 | 10 | 5 | 14 | 6 | 15 | 12 | 12 | 12 | 12 | 15 |  |  |
| I2C_SCL_BUF_9_EU1_R | I2C_9_CLKBUF_EU1_R-DIFF1 | PAIR | 4 | 6 | 5 | 10 | 5 | 14 | 6 | 15 | 12 | 12 | 12 | 12 | 15 |  |  |
| I2C_SCL_BUF_9_EU1_R | I2C_9_CLKBUF_EU1_R-DIFF1 | PAIR | 5 | 6 | 5 | 10 | 5 | 14 | 6 | 15 | 12 | 12 | 12 | 12 | 15 |  |  |
| I2C_SCL_BUF_9_EU1_R | I2C_9_CLKBUF_EU1_R-DIFF1 | PAIR | 6 | 6 | 5 | 10 | 5 | 14 | 6 | 15 | 12 | 12 | 12 | 12 | 15 |  |  |
| I2C_SCL_BUF_9_EU1_R | I2C_9_CLKBUF_EU1_R-DIFF1 | PAIR | 7 | 6 | 5 | 10 | 5 | 14 | 6 | 15 | 12 | 12 | 12 | 12 | 15 |  |  |
| I2C_SCL_BUF_9_EU1_R | I2C_9_CLKBUF_EU1_R-DIFF1 | PAIR | 8 | 6.75 | 5 | 10 | 5 | 14 | 6 | 15 | 12 | 12 | 12 | 12 | 15 |  |  |
| I2C_SDA_BUF_9_EU1_R | I2C_9_CLKBUF_EU1_R-DIFF1 | PAIR | 1 | 6.75 | 5 | 10 | 5 | 14 | 6 | 15 | 12 | 12 | 12 | 12 | 15 |  |  |
| I2C_SDA_BUF_9_EU1_R | I2C_9_CLKBUF_EU1_R-DIFF1 | PAIR | 2 | 6 | 5 | 10 | 5 | 14 | 6 | 15 | 12 | 12 | 12 | 12 | 15 |  |  |
| I2C_SDA_BUF_9_EU1_R | I2C_9_CLKBUF_EU1_R-DIFF1 | PAIR | 3 | 6 | 5 | 10 | 5 | 14 | 6 | 15 | 12 | 12 | 12 | 12 | 15 |  |  |
| I2C_SDA_BUF_9_EU1_R | I2C_9_CLKBUF_EU1_R-DIFF1 | PAIR | 4 | 6 | 5 | 10 | 5 | 14 | 6 | 15 | 12 | 12 | 12 | 12 | 15 |  |  |
| I2C_SDA_BUF_9_EU1_R | I2C_9_CLKBUF_EU1_R-DIFF1 | PAIR | 5 | 6 | 5 | 10 | 5 | 14 | 6 | 15 | 12 | 12 | 12 | 12 | 15 |  |  |
| I2C_SDA_BUF_9_EU1_R | I2C_9_CLKBUF_EU1_R-DIFF1 | PAIR | 6 | 6 | 5 | 10 | 5 | 14 | 6 | 15 | 12 | 12 | 12 | 12 | 15 |  |  |
| I2C_SDA_BUF_9_EU1_R | I2C_9_CLKBUF_EU1_R-DIFF1 | PAIR | 7 | 6 | 5 | 10 | 5 | 14 | 6 | 15 | 12 | 12 | 12 | 12 | 15 |  |  |
| I2C_SDA_BUF_9_EU1_R | I2C_9_CLKBUF_EU1_R-DIFF1 | PAIR | 8 | 6.75 | 5 | 10 | 5 | 14 | 6 | 15 | 12 | 12 | 12 | 12 | 15 |  |  |
| I2C_SCL_BUF_9_EU2_R | I2C_9_CLKBUF_EU2_R-DIFF1 | PAIR | 1 | 6.75 | 5 | 10 | 5 | 14 | 6 | 15 | 12 | 12 | 12 | 12 | 15 |  |  |
| I2C_SCL_BUF_9_EU2_R | I2C_9_CLKBUF_EU2_R-DIFF1 | PAIR | 2 | 6 | 5 | 10 | 5 | 14 | 6 | 15 | 12 | 12 | 12 | 12 | 15 |  |  |
| I2C_SCL_BUF_9_EU2_R | I2C_9_CLKBUF_EU2_R-DIFF1 | PAIR | 3 | 6 | 5 | 10 | 5 | 14 | 6 | 15 | 12 | 12 | 12 | 12 | 15 |  |  |
| I2C_SCL_BUF_9_EU2_R | I2C_9_CLKBUF_EU2_R-DIFF1 | PAIR | 4 | 6 | 5 | 10 | 5 | 14 | 6 | 15 | 12 | 12 | 12 | 12 | 15 |  |  |
| I2C_SCL_BUF_9_EU2_R | I2C_9_CLKBUF_EU2_R-DIFF1 | PAIR | 5 | 6 | 5 | 10 | 5 | 14 | 6 | 15 | 12 | 12 | 12 | 12 | 15 |  |  |
| I2C_SCL_BUF_9_EU2_R | I2C_9_CLKBUF_EU2_R-DIFF1 | PAIR | 6 | 6 | 5 | 10 | 5 | 14 | 6 | 15 | 12 | 12 | 12 | 12 | 15 |  |  |
| I2C_SCL_BUF_9_EU2_R | I2C_9_CLKBUF_EU2_R-DIFF1 | PAIR | 7 | 6 | 5 | 10 | 5 | 14 | 6 | 15 | 12 | 12 | 12 | 12 | 15 |  |  |
| I2C_SCL_BUF_9_EU2_R | I2C_9_CLKBUF_EU2_R-DIFF1 | PAIR | 8 | 6.75 | 5 | 10 | 5 | 14 | 6 | 15 | 12 | 12 | 12 | 12 | 15 |  |  |
| I2C_SDA_BUF_9_EU2_R | I2C_9_CLKBUF_EU2_R-DIFF1 | PAIR | 1 | 6.75 | 5 | 10 | 5 | 14 | 6 | 15 | 12 | 12 | 12 | 12 | 15 |  |  |
| I2C_SDA_BUF_9_EU2_R | I2C_9_CLKBUF_EU2_R-DIFF1 | PAIR | 2 | 6 | 5 | 10 | 5 | 14 | 6 | 15 | 12 | 12 | 12 | 12 | 15 |  |  |
| I2C_SDA_BUF_9_EU2_R | I2C_9_CLKBUF_EU2_R-DIFF1 | PAIR | 3 | 6 | 5 | 10 | 5 | 14 | 6 | 15 | 12 | 12 | 12 | 12 | 15 |  |  |
| I2C_SDA_BUF_9_EU2_R | I2C_9_CLKBUF_EU2_R-DIFF1 | PAIR | 4 | 6 | 5 | 10 | 5 | 14 | 6 | 15 | 12 | 12 | 12 | 12 | 15 |  |  |
| I2C_SDA_BUF_9_EU2_R | I2C_9_CLKBUF_EU2_R-DIFF1 | PAIR | 5 | 6 | 5 | 10 | 5 | 14 | 6 | 15 | 12 | 12 | 12 | 12 | 15 |  |  |
| I2C_SDA_BUF_9_EU2_R | I2C_9_CLKBUF_EU2_R-DIFF1 | PAIR | 6 | 6 | 5 | 10 | 5 | 14 | 6 | 15 | 12 | 12 | 12 | 12 | 15 |  |  |
| I2C_SDA_BUF_9_EU2_R | I2C_9_CLKBUF_EU2_R-DIFF1 | PAIR | 7 | 6 | 5 | 10 | 5 | 14 | 6 | 15 | 12 | 12 | 12 | 12 | 15 |  |  |
| I2C_SDA_BUF_9_EU2_R | I2C_9_CLKBUF_EU2_R-DIFF1 | PAIR | 8 | 6.75 | 5 | 10 | 5 | 14 | 6 | 15 | 12 | 12 | 12 | 12 | 15 |  |  |
| I2C_SCL_BUF_8_EU3_R | I2C_9_CLKBUF_EU3_R-DIFF1 | PAIR | 1 | 6.75 | 5 | 10 | 5 | 14 | 6 | 15 | 12 | 12 | 12 | 12 | 15 |  |  |
| I2C_SCL_BUF_8_EU3_R | I2C_9_CLKBUF_EU3_R-DIFF1 | PAIR | 2 | 6 | 5 | 10 | 5 | 14 | 6 | 15 | 12 | 12 | 12 | 12 | 15 |  |  |
| I2C_SCL_BUF_8_EU3_R | I2C_9_CLKBUF_EU3_R-DIFF1 | PAIR | 3 | 6 | 5 | 10 | 5 | 14 | 6 | 15 | 12 | 12 | 12 | 12 | 15 |  |  |
| I2C_SCL_BUF_8_EU3_R | I2C_9_CLKBUF_EU3_R-DIFF1 | PAIR | 4 | 6 | 5 | 10 | 5 | 14 | 6 | 15 | 12 | 12 | 12 | 12 | 15 |  |  |
| I2C_SCL_BUF_8_EU3_R | I2C_9_CLKBUF_EU3_R-DIFF1 | PAIR | 5 | 6 | 5 | 10 | 5 | 14 | 6 | 15 | 12 | 12 | 12 | 12 | 15 |  |  |
| I2C_SCL_BUF_8_EU3_R | I2C_9_CLKBUF_EU3_R-DIFF1 | PAIR | 6 | 6 | 5 | 10 | 5 | 14 | 6 | 15 | 12 | 12 | 12 | 12 | 15 |  |  |
| I2C_SCL_BUF_8_EU3_R | I2C_9_CLKBUF_EU3_R-DIFF1 | PAIR | 7 | 6 | 5 | 10 | 5 | 14 | 6 | 15 | 12 | 12 | 12 | 12 | 15 |  |  |
| I2C_SCL_BUF_8_EU3_R | I2C_9_CLKBUF_EU3_R-DIFF1 | PAIR | 8 | 6.75 | 5 | 10 | 5 | 14 | 6 | 15 | 12 | 12 | 12 | 12 | 15 |  |  |
| I2C_SDA_BUF_8_EU3_R | I2C_9_CLKBUF_EU3_R-DIFF1 | PAIR | 1 | 6.75 | 5 | 10 | 5 | 14 | 6 | 15 | 12 | 12 | 12 | 12 | 15 |  |  |
| I2C_SDA_BUF_8_EU3_R | I2C_9_CLKBUF_EU3_R-DIFF1 | PAIR | 2 | 6 | 5 | 10 | 5 | 14 | 6 | 15 | 12 | 12 | 12 | 12 | 15 |  |  |
| I2C_SDA_BUF_8_EU3_R | I2C_9_CLKBUF_EU3_R-DIFF1 | PAIR | 3 | 6 | 5 | 10 | 5 | 14 | 6 | 15 | 12 | 12 | 12 | 12 | 15 |  |  |
| I2C_SDA_BUF_8_EU3_R | I2C_9_CLKBUF_EU3_R-DIFF1 | PAIR | 4 | 6 | 5 | 10 | 5 | 14 | 6 | 15 | 12 | 12 | 12 | 12 | 15 |  |  |
| I2C_SDA_BUF_8_EU3_R | I2C_9_CLKBUF_EU3_R-DIFF1 | PAIR | 5 | 6 | 5 | 10 | 5 | 14 | 6 | 15 | 12 | 12 | 12 | 12 | 15 |  |  |
| I2C_SDA_BUF_8_EU3_R | I2C_9_CLKBUF_EU3_R-DIFF1 | PAIR | 6 | 6 | 5 | 10 | 5 | 14 | 6 | 15 | 12 | 12 | 12 | 12 | 15 |  |  |
| I2C_SDA_BUF_8_EU3_R | I2C_9_CLKBUF_EU3_R-DIFF1 | PAIR | 7 | 6 | 5 | 10 | 5 | 14 | 6 | 15 | 12 | 12 | 12 | 12 | 15 |  |  |
| I2C_SDA_BUF_8_EU3_R | I2C_9_CLKBUF_EU3_R-DIFF1 | PAIR | 8 | 6.75 | 5 | 10 | 5 | 14 | 6 | 15 | 12 | 12 | 12 | 12 | 15 |  |  |
| I2C_SCL_BUF_8_EU4_R | I2C_9_CLKBUF_EU4_R-DIFF1 | PAIR | 1 | 6.75 | 5 | 10 | 5 | 14 | 6 | 15 | 12 | 12 | 12 | 12 | 15 |  |  |
| I2C_SCL_BUF_8_EU4_R | I2C_9_CLKBUF_EU4_R-DIFF1 | PAIR | 2 | 6 | 5 | 10 | 5 | 14 | 6 | 15 | 12 | 12 | 12 | 12 | 15 |  |  |
| I2C_SCL_BUF_8_EU4_R | I2C_9_CLKBUF_EU4_R-DIFF1 | PAIR | 3 | 6 | 5 | 10 | 5 | 14 | 6 | 15 | 12 | 12 | 12 | 12 | 15 |  |  |
| I2C_SCL_BUF_8_EU4_R | I2C_9_CLKBUF_EU4_R-DIFF1 | PAIR | 4 | 6 | 5 | 10 | 5 | 14 | 6 | 15 | 12 | 12 | 12 | 12 | 15 |  |  |
| I2C_SCL_BUF_8_EU4_R | I2C_9_CLKBUF_EU4_R-DIFF1 | PAIR | 5 | 6 | 5 | 10 | 5 | 14 | 6 | 15 | 12 | 12 | 12 | 12 | 15 |  |  |
| I2C_SCL_BUF_8_EU4_R | I2C_9_CLKBUF_EU4_R-DIFF1 | PAIR | 6 | 6 | 5 | 10 | 5 | 14 | 6 | 15 | 12 | 12 | 12 | 12 | 15 |  |  |
| I2C_SCL_BUF_8_EU4_R | I2C_9_CLKBUF_EU4_R-DIFF1 | PAIR | 7 | 6 | 5 | 10 | 5 | 14 | 6 | 15 | 12 | 12 | 12 | 12 | 15 |  |  |
| I2C_SCL_BUF_8_EU4_R | I2C_9_CLKBUF_EU4_R-DIFF1 | PAIR | 8 | 6.75 | 5 | 10 | 5 | 14 | 6 | 15 | 12 | 12 | 12 | 12 | 15 |  |  |
| I2C_SDA_BUF_8_EU4_R | I2C_9_CLKBUF_EU4_R-DIFF1 | PAIR | 1 | 6.75 | 5 | 10 | 5 | 14 | 6 | 15 | 12 | 12 | 12 | 12 | 15 |  |  |
| I2C_SDA_BUF_8_EU4_R | I2C_9_CLKBUF_EU4_R-DIFF1 | PAIR | 2 | 6 | 5 | 10 | 5 | 14 | 6 | 15 | 12 | 12 | 12 | 12 | 15 |  |  |
| I2C_SDA_BUF_8_EU4_R | I2C_9_CLKBUF_EU4_R-DIFF1 | PAIR | 3 | 6 | 5 | 10 | 5 | 14 | 6 | 15 | 12 | 12 | 12 | 12 | 15 |  |  |
| I2C_SDA_BUF_8_EU4_R | I2C_9_CLKBUF_EU4_R-DIFF1 | PAIR | 4 | 6 | 5 | 10 | 5 | 14 | 6 | 15 | 12 | 12 | 12 | 12 | 15 |  |  |
| I2C_SDA_BUF_8_EU4_R | I2C_9_CLKBUF_EU4_R-DIFF1 | PAIR | 5 | 6 | 5 | 10 | 5 | 14 | 6 | 15 | 12 | 12 | 12 | 12 | 15 |  |  |
| I2C_SDA_BUF_8_EU4_R | I2C_9_CLKBUF_EU4_R-DIFF1 | PAIR | 6 | 6 | 5 | 10 | 5 | 14 | 6 | 15 | 12 | 12 | 12 | 12 | 15 |  |  |
| I2C_SDA_BUF_8_EU4_R | I2C_9_CLKBUF_EU4_R-DIFF1 | PAIR | 7 | 6 | 5 | 10 | 5 | 14 | 6 | 15 | 12 | 12 | 12 | 12 | 15 |  |  |
| I2C_SDA_BUF_8_EU4_R | I2C_9_CLKBUF_EU4_R-DIFF1 | PAIR | 8 | 6.75 | 5 | 10 | 5 | 14 | 6 | 15 | 12 | 12 | 12 | 12 | 15 |  |  |
| I2C8_SCL_R_SW_EU16 | I2C_9_R_SW_EU16-DIFF1 | PAIR | 1 | 6.75 | 5 | 10 | 5 | 14 | 6 | 15 | 12 | 12 | 12 | 12 | 15 |  |  |
| I2C8_SCL_R_SW_EU16 | I2C_9_R_SW_EU16-DIFF1 | PAIR | 2 | 6 | 5 | 10 | 5 | 14 | 6 | 15 | 12 | 12 | 12 | 12 | 15 |  |  |
| I2C8_SCL_R_SW_EU16 | I2C_9_R_SW_EU16-DIFF1 | PAIR | 3 | 6 | 5 | 10 | 5 | 14 | 6 | 15 | 12 | 12 | 12 | 12 | 15 |  |  |
| I2C8_SCL_R_SW_EU16 | I2C_9_R_SW_EU16-DIFF1 | PAIR | 4 | 6 | 5 | 10 | 5 | 14 | 6 | 15 | 12 | 12 | 12 | 12 | 15 |  |  |
| I2C8_SCL_R_SW_EU16 | I2C_9_R_SW_EU16-DIFF1 | PAIR | 5 | 6 | 5 | 10 | 5 | 14 | 6 | 15 | 12 | 12 | 12 | 12 | 15 |  |  |
| I2C8_SCL_R_SW_EU16 | I2C_9_R_SW_EU16-DIFF1 | PAIR | 6 | 6 | 5 | 10 | 5 | 14 | 6 | 15 | 12 | 12 | 12 | 12 | 15 |  |  |
| I2C8_SCL_R_SW_EU16 | I2C_9_R_SW_EU16-DIFF1 | PAIR | 7 | 6 | 5 | 10 | 5 | 14 | 6 | 15 | 12 | 12 | 12 | 12 | 15 |  |  |
| I2C8_SCL_R_SW_EU16 | I2C_9_R_SW_EU16-DIFF1 | PAIR | 8 | 6.75 | 5 | 10 | 5 | 14 | 6 | 15 | 12 | 12 | 12 | 12 | 15 |  |  |
| I2C8_SDA_R_SW_EU16 | I2C_9_R_SW_EU16-DIFF1 | PAIR | 1 | 6.75 | 5 | 10 | 5 | 14 | 6 | 15 | 12 | 12 | 12 | 12 | 15 |  |  |
| I2C8_SDA_R_SW_EU16 | I2C_9_R_SW_EU16-DIFF1 | PAIR | 2 | 6 | 5 | 10 | 5 | 14 | 6 | 15 | 12 | 12 | 12 | 12 | 15 |  |  |
| I2C8_SDA_R_SW_EU16 | I2C_9_R_SW_EU16-DIFF1 | PAIR | 3 | 6 | 5 | 10 | 5 | 14 | 6 | 15 | 12 | 12 | 12 | 12 | 15 |  |  |
| I2C8_SDA_R_SW_EU16 | I2C_9_R_SW_EU16-DIFF1 | PAIR | 4 | 6 | 5 | 10 | 5 | 14 | 6 | 15 | 12 | 12 | 12 | 12 | 15 |  |  |
| I2C8_SDA_R_SW_EU16 | I2C_9_R_SW_EU16-DIFF1 | PAIR | 5 | 6 | 5 | 10 | 5 | 14 | 6 | 15 | 12 | 12 | 12 | 12 | 15 |  |  |
| I2C8_SDA_R_SW_EU16 | I2C_9_R_SW_EU16-DIFF1 | PAIR | 6 | 6 | 5 | 10 | 5 | 14 | 6 | 15 | 12 | 12 | 12 | 12 | 15 |  |  |
| I2C8_SDA_R_SW_EU16 | I2C_9_R_SW_EU16-DIFF1 | PAIR | 7 | 6 | 5 | 10 | 5 | 14 | 6 | 15 | 12 | 12 | 12 | 12 | 15 |  |  |
| I2C8_SDA_R_SW_EU16 | I2C_9_R_SW_EU16-DIFF1 | PAIR | 8 | 6.75 | 5 | 10 | 5 | 14 | 6 | 15 | 12 | 12 | 12 | 12 | 15 |  |  |
| I2C8_SCL_R_SW_EU17 | I2C_9_R_SW_EU17-DIFF1 | PAIR | 1 | 6.75 | 5 | 10 | 5 | 14 | 6 | 15 | 12 | 12 | 12 | 12 | 15 |  |  |
| I2C8_SCL_R_SW_EU17 | I2C_9_R_SW_EU17-DIFF1 | PAIR | 2 | 6 | 5 | 10 | 5 | 14 | 6 | 15 | 12 | 12 | 12 | 12 | 15 |  |  |
| I2C8_SCL_R_SW_EU17 | I2C_9_R_SW_EU17-DIFF1 | PAIR | 3 | 6 | 5 | 10 | 5 | 14 | 6 | 15 | 12 | 12 | 12 | 12 | 15 |  |  |
| I2C8_SCL_R_SW_EU17 | I2C_9_R_SW_EU17-DIFF1 | PAIR | 4 | 6 | 5 | 10 | 5 | 14 | 6 | 15 | 12 | 12 | 12 | 12 | 15 |  |  |
| I2C8_SCL_R_SW_EU17 | I2C_9_R_SW_EU17-DIFF1 | PAIR | 5 | 6 | 5 | 10 | 5 | 14 | 6 | 15 | 12 | 12 | 12 | 12 | 15 |  |  |
| I2C8_SCL_R_SW_EU17 | I2C_9_R_SW_EU17-DIFF1 | PAIR | 6 | 6 | 5 | 10 | 5 | 14 | 6 | 15 | 12 | 12 | 12 | 12 | 15 |  |  |
| I2C8_SCL_R_SW_EU17 | I2C_9_R_SW_EU17-DIFF1 | PAIR | 7 | 6 | 5 | 10 | 5 | 14 | 6 | 15 | 12 | 12 | 12 | 12 | 15 |  |  |
| I2C8_SCL_R_SW_EU17 | I2C_9_R_SW_EU17-DIFF1 | PAIR | 8 | 6.75 | 5 | 10 | 5 | 14 | 6 | 15 | 12 | 12 | 12 | 12 | 15 |  |  |
| I2C8_SDA_R_SW_EU17 | I2C_9_R_SW_EU17-DIFF1 | PAIR | 1 | 6.75 | 5 | 10 | 5 | 14 | 6 | 15 | 12 | 12 | 12 | 12 | 15 |  |  |
| I2C8_SDA_R_SW_EU17 | I2C_9_R_SW_EU17-DIFF1 | PAIR | 2 | 6 | 5 | 10 | 5 | 14 | 6 | 15 | 12 | 12 | 12 | 12 | 15 |  |  |
| I2C8_SDA_R_SW_EU17 | I2C_9_R_SW_EU17-DIFF1 | PAIR | 3 | 6 | 5 | 10 | 5 | 14 | 6 | 15 | 12 | 12 | 12 | 12 | 15 |  |  |
| I2C8_SDA_R_SW_EU17 | I2C_9_R_SW_EU17-DIFF1 | PAIR | 4 | 6 | 5 | 10 | 5 | 14 | 6 | 15 | 12 | 12 | 12 | 12 | 15 |  |  |
| I2C8_SDA_R_SW_EU17 | I2C_9_R_SW_EU17-DIFF1 | PAIR | 5 | 6 | 5 | 10 | 5 | 14 | 6 | 15 | 12 | 12 | 12 | 12 | 15 |  |  |
| I2C8_SDA_R_SW_EU17 | I2C_9_R_SW_EU17-DIFF1 | PAIR | 6 | 6 | 5 | 10 | 5 | 14 | 6 | 15 | 12 | 12 | 12 | 12 | 15 |  |  |
| I2C8_SDA_R_SW_EU17 | I2C_9_R_SW_EU17-DIFF1 | PAIR | 7 | 6 | 5 | 10 | 5 | 14 | 6 | 15 | 12 | 12 | 12 | 12 | 15 |  |  |
| I2C8_SDA_R_SW_EU17 | I2C_9_R_SW_EU17-DIFF1 | PAIR | 8 | 6.75 | 5 | 10 | 5 | 14 | 6 | 15 | 12 | 12 | 12 | 12 | 15 |  |  |
| I2C_B_SCL | I2C_B-DIFF1 | PAIR | 1 | 6.75 | 5 | 10 | 5 | 14 | 6 | 15 | 12 | 12 | 12 | 12 | 15 |  |  |
| I2C_B_SCL | I2C_B-DIFF1 | PAIR | 2 | 6 | 5 | 10 | 5 | 14 | 6 | 15 | 12 | 12 | 12 | 12 | 15 |  |  |
| I2C_B_SCL | I2C_B-DIFF1 | PAIR | 3 | 6 | 5 | 10 | 5 | 14 | 6 | 15 | 12 | 12 | 12 | 12 | 15 |  |  |
| I2C_B_SCL | I2C_B-DIFF1 | PAIR | 4 | 6 | 5 | 10 | 5 | 14 | 6 | 15 | 12 | 12 | 12 | 12 | 15 |  |  |
| I2C_B_SCL | I2C_B-DIFF1 | PAIR | 5 | 6 | 5 | 10 | 5 | 14 | 6 | 15 | 12 | 12 | 12 | 12 | 15 |  |  |
| I2C_B_SCL | I2C_B-DIFF1 | PAIR | 6 | 6 | 5 | 10 | 5 | 14 | 6 | 15 | 12 | 12 | 12 | 12 | 15 |  |  |
| I2C_B_SCL | I2C_B-DIFF1 | PAIR | 7 | 6 | 5 | 10 | 5 | 14 | 6 | 15 | 12 | 12 | 12 | 12 | 15 |  |  |
| I2C_B_SCL | I2C_B-DIFF1 | PAIR | 8 | 6.75 | 5 | 10 | 5 | 14 | 6 | 15 | 12 | 12 | 12 | 12 | 15 |  |  |
| I2C_B_SDA | I2C_B-DIFF1 | PAIR | 1 | 6.75 | 5 | 10 | 5 | 14 | 6 | 15 | 12 | 12 | 12 | 12 | 15 |  |  |
| I2C_B_SDA | I2C_B-DIFF1 | PAIR | 2 | 6 | 5 | 10 | 5 | 14 | 6 | 15 | 12 | 12 | 12 | 12 | 15 |  |  |
| I2C_B_SDA | I2C_B-DIFF1 | PAIR | 3 | 6 | 5 | 10 | 5 | 14 | 6 | 15 | 12 | 12 | 12 | 12 | 15 |  |  |
| I2C_B_SDA | I2C_B-DIFF1 | PAIR | 4 | 6 | 5 | 10 | 5 | 14 | 6 | 15 | 12 | 12 | 12 | 12 | 15 |  |  |
| I2C_B_SDA | I2C_B-DIFF1 | PAIR | 5 | 6 | 5 | 10 | 5 | 14 | 6 | 15 | 12 | 12 | 12 | 12 | 15 |  |  |
| I2C_B_SDA | I2C_B-DIFF1 | PAIR | 6 | 6 | 5 | 10 | 5 | 14 | 6 | 15 | 12 | 12 | 12 | 12 | 15 |  |  |
| I2C_B_SDA | I2C_B-DIFF1 | PAIR | 7 | 6 | 5 | 10 | 5 | 14 | 6 | 15 | 12 | 12 | 12 | 12 | 15 |  |  |
| I2C_B_SDA | I2C_B-DIFF1 | PAIR | 8 | 6.75 | 5 | 10 | 5 | 14 | 6 | 15 | 12 | 12 | 12 | 12 | 15 |  |  |
| I2C_C_SCL | I2C_C-DIFF1 | PAIR | 1 | 6.75 | 5 | 10 | 5 | 14 | 6 | 15 | 12 | 12 | 12 | 12 | 15 |  |  |
| I2C_C_SCL | I2C_C-DIFF1 | PAIR | 2 | 6 | 5 | 10 | 5 | 14 | 6 | 15 | 12 | 12 | 12 | 12 | 15 |  |  |
| I2C_C_SCL | I2C_C-DIFF1 | PAIR | 3 | 6 | 5 | 10 | 5 | 14 | 6 | 15 | 12 | 12 | 12 | 12 | 15 |  |  |
| I2C_C_SCL | I2C_C-DIFF1 | PAIR | 4 | 6 | 5 | 10 | 5 | 14 | 6 | 15 | 12 | 12 | 12 | 12 | 15 |  |  |
| I2C_C_SCL | I2C_C-DIFF1 | PAIR | 5 | 6 | 5 | 10 | 5 | 14 | 6 | 15 | 12 | 12 | 12 | 12 | 15 |  |  |
| I2C_C_SCL | I2C_C-DIFF1 | PAIR | 6 | 6 | 5 | 10 | 5 | 14 | 6 | 15 | 12 | 12 | 12 | 12 | 15 |  |  |
| I2C_C_SCL | I2C_C-DIFF1 | PAIR | 7 | 6 | 5 | 10 | 5 | 14 | 6 | 15 | 12 | 12 | 12 | 12 | 15 |  |  |
| I2C_C_SCL | I2C_C-DIFF1 | PAIR | 8 | 6.75 | 5 | 10 | 5 | 14 | 6 | 15 | 12 | 12 | 12 | 12 | 15 |  |  |
| I2C_C_SDA | I2C_C-DIFF1 | PAIR | 1 | 6.75 | 5 | 10 | 5 | 14 | 6 | 15 | 12 | 12 | 12 | 12 | 15 |  |  |
| I2C_C_SDA | I2C_C-DIFF1 | PAIR | 2 | 6 | 5 | 10 | 5 | 14 | 6 | 15 | 12 | 12 | 12 | 12 | 15 |  |  |
| I2C_C_SDA | I2C_C-DIFF1 | PAIR | 3 | 6 | 5 | 10 | 5 | 14 | 6 | 15 | 12 | 12 | 12 | 12 | 15 |  |  |
| I2C_C_SDA | I2C_C-DIFF1 | PAIR | 4 | 6 | 5 | 10 | 5 | 14 | 6 | 15 | 12 | 12 | 12 | 12 | 15 |  |  |
| I2C_C_SDA | I2C_C-DIFF1 | PAIR | 5 | 6 | 5 | 10 | 5 | 14 | 6 | 15 | 12 | 12 | 12 | 12 | 15 |  |  |
| I2C_C_SDA | I2C_C-DIFF1 | PAIR | 6 | 6 | 5 | 10 | 5 | 14 | 6 | 15 | 12 | 12 | 12 | 12 | 15 |  |  |
| I2C_C_SDA | I2C_C-DIFF1 | PAIR | 7 | 6 | 5 | 10 | 5 | 14 | 6 | 15 | 12 | 12 | 12 | 12 | 15 |  |  |
| I2C_C_SDA | I2C_C-DIFF1 | PAIR | 8 | 6.75 | 5 | 10 | 5 | 14 | 6 | 15 | 12 | 12 | 12 | 12 | 15 |  |  |
| SCL_DR0_R | I2C_DR0_R-DIFF1 | PAIR | 1 | 6.75 | 5 | 10 | 5 | 14 | 6 | 15 | 12 | 12 | 12 | 12 | 15 |  |  |
| SCL_DR0_R | I2C_DR0_R-DIFF1 | PAIR | 2 | 6 | 5 | 10 | 5 | 14 | 6 | 15 | 12 | 12 | 12 | 12 | 15 |  |  |
| SCL_DR0_R | I2C_DR0_R-DIFF1 | PAIR | 3 | 6 | 5 | 10 | 5 | 14 | 6 | 15 | 12 | 12 | 12 | 12 | 15 |  |  |
| SCL_DR0_R | I2C_DR0_R-DIFF1 | PAIR | 4 | 6 | 5 | 10 | 5 | 14 | 6 | 15 | 12 | 12 | 12 | 12 | 15 |  |  |
| SCL_DR0_R | I2C_DR0_R-DIFF1 | PAIR | 5 | 6 | 5 | 10 | 5 | 14 | 6 | 15 | 12 | 12 | 12 | 12 | 15 |  |  |
| SCL_DR0_R | I2C_DR0_R-DIFF1 | PAIR | 6 | 6 | 5 | 10 | 5 | 14 | 6 | 15 | 12 | 12 | 12 | 12 | 15 |  |  |
| SCL_DR0_R | I2C_DR0_R-DIFF1 | PAIR | 7 | 6 | 5 | 10 | 5 | 14 | 6 | 15 | 12 | 12 | 12 | 12 | 15 |  |  |
| SCL_DR0_R | I2C_DR0_R-DIFF1 | PAIR | 8 | 6.75 | 5 | 10 | 5 | 14 | 6 | 15 | 12 | 12 | 12 | 12 | 15 |  |  |
| SDA_DR0_R | I2C_DR0_R-DIFF1 | PAIR | 1 | 6.75 | 5 | 10 | 5 | 14 | 6 | 15 | 12 | 12 | 12 | 12 | 15 |  |  |
| SDA_DR0_R | I2C_DR0_R-DIFF1 | PAIR | 2 | 6 | 5 | 10 | 5 | 14 | 6 | 15 | 12 | 12 | 12 | 12 | 15 |  |  |
| SDA_DR0_R | I2C_DR0_R-DIFF1 | PAIR | 3 | 6 | 5 | 10 | 5 | 14 | 6 | 15 | 12 | 12 | 12 | 12 | 15 |  |  |
| SDA_DR0_R | I2C_DR0_R-DIFF1 | PAIR | 4 | 6 | 5 | 10 | 5 | 14 | 6 | 15 | 12 | 12 | 12 | 12 | 15 |  |  |
| SDA_DR0_R | I2C_DR0_R-DIFF1 | PAIR | 5 | 6 | 5 | 10 | 5 | 14 | 6 | 15 | 12 | 12 | 12 | 12 | 15 |  |  |
| SDA_DR0_R | I2C_DR0_R-DIFF1 | PAIR | 6 | 6 | 5 | 10 | 5 | 14 | 6 | 15 | 12 | 12 | 12 | 12 | 15 |  |  |
| SDA_DR0_R | I2C_DR0_R-DIFF1 | PAIR | 7 | 6 | 5 | 10 | 5 | 14 | 6 | 15 | 12 | 12 | 12 | 12 | 15 |  |  |
| SDA_DR0_R | I2C_DR0_R-DIFF1 | PAIR | 8 | 6.75 | 5 | 10 | 5 | 14 | 6 | 15 | 12 | 12 | 12 | 12 | 15 |  |  |
| SCL_DR0 | I2C_DR0-DIFF1 | PAIR | 1 | 6.75 | 5 | 10 | 5 | 14 | 6 | 15 | 12 | 12 | 12 | 12 | 15 |  |  |
| SCL_DR0 | I2C_DR0-DIFF1 | PAIR | 2 | 6 | 5 | 10 | 5 | 14 | 6 | 15 | 12 | 12 | 12 | 12 | 15 |  |  |
| SCL_DR0 | I2C_DR0-DIFF1 | PAIR | 3 | 6 | 5 | 10 | 5 | 14 | 6 | 15 | 12 | 12 | 12 | 12 | 15 |  |  |
| SCL_DR0 | I2C_DR0-DIFF1 | PAIR | 4 | 6 | 5 | 10 | 5 | 14 | 6 | 15 | 12 | 12 | 12 | 12 | 15 |  |  |
| SCL_DR0 | I2C_DR0-DIFF1 | PAIR | 5 | 6 | 5 | 10 | 5 | 14 | 6 | 15 | 12 | 12 | 12 | 12 | 15 |  |  |
| SCL_DR0 | I2C_DR0-DIFF1 | PAIR | 6 | 6 | 5 | 10 | 5 | 14 | 6 | 15 | 12 | 12 | 12 | 12 | 15 |  |  |
| SCL_DR0 | I2C_DR0-DIFF1 | PAIR | 7 | 6 | 5 | 10 | 5 | 14 | 6 | 15 | 12 | 12 | 12 | 12 | 15 |  |  |
| SCL_DR0 | I2C_DR0-DIFF1 | PAIR | 8 | 6.75 | 5 | 10 | 5 | 14 | 6 | 15 | 12 | 12 | 12 | 12 | 15 |  |  |
| SDA_DR0 | I2C_DR0-DIFF1 | PAIR | 1 | 6.75 | 5 | 10 | 5 | 14 | 6 | 15 | 12 | 12 | 12 | 12 | 15 |  |  |
| SDA_DR0 | I2C_DR0-DIFF1 | PAIR | 2 | 6 | 5 | 10 | 5 | 14 | 6 | 15 | 12 | 12 | 12 | 12 | 15 |  |  |
| SDA_DR0 | I2C_DR0-DIFF1 | PAIR | 3 | 6 | 5 | 10 | 5 | 14 | 6 | 15 | 12 | 12 | 12 | 12 | 15 |  |  |
| SDA_DR0 | I2C_DR0-DIFF1 | PAIR | 4 | 6 | 5 | 10 | 5 | 14 | 6 | 15 | 12 | 12 | 12 | 12 | 15 |  |  |
| SDA_DR0 | I2C_DR0-DIFF1 | PAIR | 5 | 6 | 5 | 10 | 5 | 14 | 6 | 15 | 12 | 12 | 12 | 12 | 15 |  |  |
| SDA_DR0 | I2C_DR0-DIFF1 | PAIR | 6 | 6 | 5 | 10 | 5 | 14 | 6 | 15 | 12 | 12 | 12 | 12 | 15 |  |  |
| SDA_DR0 | I2C_DR0-DIFF1 | PAIR | 7 | 6 | 5 | 10 | 5 | 14 | 6 | 15 | 12 | 12 | 12 | 12 | 15 |  |  |
| SDA_DR0 | I2C_DR0-DIFF1 | PAIR | 8 | 6.75 | 5 | 10 | 5 | 14 | 6 | 15 | 12 | 12 | 12 | 12 | 15 |  |  |
| SCL_DR1_R | I2C_DR1_R-DIFF1 | PAIR | 1 | 6.75 | 5 | 10 | 5 | 14 | 6 | 15 | 12 | 12 | 12 | 12 | 15 |  |  |
| SCL_DR1_R | I2C_DR1_R-DIFF1 | PAIR | 2 | 6 | 5 | 10 | 5 | 14 | 6 | 15 | 12 | 12 | 12 | 12 | 15 |  |  |
| SCL_DR1_R | I2C_DR1_R-DIFF1 | PAIR | 3 | 6 | 5 | 10 | 5 | 14 | 6 | 15 | 12 | 12 | 12 | 12 | 15 |  |  |
| SCL_DR1_R | I2C_DR1_R-DIFF1 | PAIR | 4 | 6 | 5 | 10 | 5 | 14 | 6 | 15 | 12 | 12 | 12 | 12 | 15 |  |  |
| SCL_DR1_R | I2C_DR1_R-DIFF1 | PAIR | 5 | 6 | 5 | 10 | 5 | 14 | 6 | 15 | 12 | 12 | 12 | 12 | 15 |  |  |
| SCL_DR1_R | I2C_DR1_R-DIFF1 | PAIR | 6 | 6 | 5 | 10 | 5 | 14 | 6 | 15 | 12 | 12 | 12 | 12 | 15 |  |  |
| SCL_DR1_R | I2C_DR1_R-DIFF1 | PAIR | 7 | 6 | 5 | 10 | 5 | 14 | 6 | 15 | 12 | 12 | 12 | 12 | 15 |  |  |
| SCL_DR1_R | I2C_DR1_R-DIFF1 | PAIR | 8 | 6.75 | 5 | 10 | 5 | 14 | 6 | 15 | 12 | 12 | 12 | 12 | 15 |  |  |
| SDA_DR1_R | I2C_DR1_R-DIFF1 | PAIR | 1 | 6.75 | 5 | 10 | 5 | 14 | 6 | 15 | 12 | 12 | 12 | 12 | 15 |  |  |
| SDA_DR1_R | I2C_DR1_R-DIFF1 | PAIR | 2 | 6 | 5 | 10 | 5 | 14 | 6 | 15 | 12 | 12 | 12 | 12 | 15 |  |  |
| SDA_DR1_R | I2C_DR1_R-DIFF1 | PAIR | 3 | 6 | 5 | 10 | 5 | 14 | 6 | 15 | 12 | 12 | 12 | 12 | 15 |  |  |
| SDA_DR1_R | I2C_DR1_R-DIFF1 | PAIR | 4 | 6 | 5 | 10 | 5 | 14 | 6 | 15 | 12 | 12 | 12 | 12 | 15 |  |  |
| SDA_DR1_R | I2C_DR1_R-DIFF1 | PAIR | 5 | 6 | 5 | 10 | 5 | 14 | 6 | 15 | 12 | 12 | 12 | 12 | 15 |  |  |
| SDA_DR1_R | I2C_DR1_R-DIFF1 | PAIR | 6 | 6 | 5 | 10 | 5 | 14 | 6 | 15 | 12 | 12 | 12 | 12 | 15 |  |  |
| SDA_DR1_R | I2C_DR1_R-DIFF1 | PAIR | 7 | 6 | 5 | 10 | 5 | 14 | 6 | 15 | 12 | 12 | 12 | 12 | 15 |  |  |
| SDA_DR1_R | I2C_DR1_R-DIFF1 | PAIR | 8 | 6.75 | 5 | 10 | 5 | 14 | 6 | 15 | 12 | 12 | 12 | 12 | 15 |  |  |
| SCL_DR10_R | I2C_DR10_R-DIFF1 | PAIR | 1 | 6.75 | 5 | 10 | 5 | 14 | 6 | 15 | 12 | 12 | 12 | 12 | 15 |  |  |
| SCL_DR10_R | I2C_DR10_R-DIFF1 | PAIR | 2 | 6 | 5 | 10 | 5 | 14 | 6 | 15 | 12 | 12 | 12 | 12 | 15 |  |  |
| SCL_DR10_R | I2C_DR10_R-DIFF1 | PAIR | 3 | 6 | 5 | 10 | 5 | 14 | 6 | 15 | 12 | 12 | 12 | 12 | 15 |  |  |
| SCL_DR10_R | I2C_DR10_R-DIFF1 | PAIR | 4 | 6 | 5 | 10 | 5 | 14 | 6 | 15 | 12 | 12 | 12 | 12 | 15 |  |  |
| SCL_DR10_R | I2C_DR10_R-DIFF1 | PAIR | 5 | 6 | 5 | 10 | 5 | 14 | 6 | 15 | 12 | 12 | 12 | 12 | 15 |  |  |
| SCL_DR10_R | I2C_DR10_R-DIFF1 | PAIR | 6 | 6 | 5 | 10 | 5 | 14 | 6 | 15 | 12 | 12 | 12 | 12 | 15 |  |  |
| SCL_DR10_R | I2C_DR10_R-DIFF1 | PAIR | 7 | 6 | 5 | 10 | 5 | 14 | 6 | 15 | 12 | 12 | 12 | 12 | 15 |  |  |
| SCL_DR10_R | I2C_DR10_R-DIFF1 | PAIR | 8 | 6.75 | 5 | 10 | 5 | 14 | 6 | 15 | 12 | 12 | 12 | 12 | 15 |  |  |
| SDA_DR10_R | I2C_DR10_R-DIFF1 | PAIR | 1 | 6.75 | 5 | 10 | 5 | 14 | 6 | 15 | 12 | 12 | 12 | 12 | 15 |  |  |
| SDA_DR10_R | I2C_DR10_R-DIFF1 | PAIR | 2 | 6 | 5 | 10 | 5 | 14 | 6 | 15 | 12 | 12 | 12 | 12 | 15 |  |  |
| SDA_DR10_R | I2C_DR10_R-DIFF1 | PAIR | 3 | 6 | 5 | 10 | 5 | 14 | 6 | 15 | 12 | 12 | 12 | 12 | 15 |  |  |
| SDA_DR10_R | I2C_DR10_R-DIFF1 | PAIR | 4 | 6 | 5 | 10 | 5 | 14 | 6 | 15 | 12 | 12 | 12 | 12 | 15 |  |  |
| SDA_DR10_R | I2C_DR10_R-DIFF1 | PAIR | 5 | 6 | 5 | 10 | 5 | 14 | 6 | 15 | 12 | 12 | 12 | 12 | 15 |  |  |
| SDA_DR10_R | I2C_DR10_R-DIFF1 | PAIR | 6 | 6 | 5 | 10 | 5 | 14 | 6 | 15 | 12 | 12 | 12 | 12 | 15 |  |  |
| SDA_DR10_R | I2C_DR10_R-DIFF1 | PAIR | 7 | 6 | 5 | 10 | 5 | 14 | 6 | 15 | 12 | 12 | 12 | 12 | 15 |  |  |
| SDA_DR10_R | I2C_DR10_R-DIFF1 | PAIR | 8 | 6.75 | 5 | 10 | 5 | 14 | 6 | 15 | 12 | 12 | 12 | 12 | 15 |  |  |
| SCL_DR10 | I2C_DR10-DIFF1 | PAIR | 1 | 6.75 | 5 | 10 | 5 | 14 | 6 | 15 | 12 | 12 | 12 | 12 | 15 |  |  |
| SCL_DR10 | I2C_DR10-DIFF1 | PAIR | 2 | 6 | 5 | 10 | 5 | 14 | 6 | 15 | 12 | 12 | 12 | 12 | 15 |  |  |
| SCL_DR10 | I2C_DR10-DIFF1 | PAIR | 3 | 6 | 5 | 10 | 5 | 14 | 6 | 15 | 12 | 12 | 12 | 12 | 15 |  |  |
| SCL_DR10 | I2C_DR10-DIFF1 | PAIR | 4 | 6 | 5 | 10 | 5 | 14 | 6 | 15 | 12 | 12 | 12 | 12 | 15 |  |  |
| SCL_DR10 | I2C_DR10-DIFF1 | PAIR | 5 | 6 | 5 | 10 | 5 | 14 | 6 | 15 | 12 | 12 | 12 | 12 | 15 |  |  |
| SCL_DR10 | I2C_DR10-DIFF1 | PAIR | 6 | 6 | 5 | 10 | 5 | 14 | 6 | 15 | 12 | 12 | 12 | 12 | 15 |  |  |
| SCL_DR10 | I2C_DR10-DIFF1 | PAIR | 7 | 6 | 5 | 10 | 5 | 14 | 6 | 15 | 12 | 12 | 12 | 12 | 15 |  |  |
| SCL_DR10 | I2C_DR10-DIFF1 | PAIR | 8 | 6.75 | 5 | 10 | 5 | 14 | 6 | 15 | 12 | 12 | 12 | 12 | 15 |  |  |
| SDA_DR10 | I2C_DR10-DIFF1 | PAIR | 1 | 6.75 | 5 | 10 | 5 | 14 | 6 | 15 | 12 | 12 | 12 | 12 | 15 |  |  |
| SDA_DR10 | I2C_DR10-DIFF1 | PAIR | 2 | 6 | 5 | 10 | 5 | 14 | 6 | 15 | 12 | 12 | 12 | 12 | 15 |  |  |
| SDA_DR10 | I2C_DR10-DIFF1 | PAIR | 3 | 6 | 5 | 10 | 5 | 14 | 6 | 15 | 12 | 12 | 12 | 12 | 15 |  |  |
| SDA_DR10 | I2C_DR10-DIFF1 | PAIR | 4 | 6 | 5 | 10 | 5 | 14 | 6 | 15 | 12 | 12 | 12 | 12 | 15 |  |  |
| SDA_DR10 | I2C_DR10-DIFF1 | PAIR | 5 | 6 | 5 | 10 | 5 | 14 | 6 | 15 | 12 | 12 | 12 | 12 | 15 |  |  |
| SDA_DR10 | I2C_DR10-DIFF1 | PAIR | 6 | 6 | 5 | 10 | 5 | 14 | 6 | 15 | 12 | 12 | 12 | 12 | 15 |  |  |
| SDA_DR10 | I2C_DR10-DIFF1 | PAIR | 7 | 6 | 5 | 10 | 5 | 14 | 6 | 15 | 12 | 12 | 12 | 12 | 15 |  |  |
| SDA_DR10 | I2C_DR10-DIFF1 | PAIR | 8 | 6.75 | 5 | 10 | 5 | 14 | 6 | 15 | 12 | 12 | 12 | 12 | 15 |  |  |
| SCL_DR11_R | I2C_DR11_R-DIFF1 | PAIR | 1 | 6.75 | 5 | 10 | 5 | 14 | 6 | 15 | 12 | 12 | 12 | 12 | 15 |  |  |
| SCL_DR11_R | I2C_DR11_R-DIFF1 | PAIR | 2 | 6 | 5 | 10 | 5 | 14 | 6 | 15 | 12 | 12 | 12 | 12 | 15 |  |  |
| SCL_DR11_R | I2C_DR11_R-DIFF1 | PAIR | 3 | 6 | 5 | 10 | 5 | 14 | 6 | 15 | 12 | 12 | 12 | 12 | 15 |  |  |
| SCL_DR11_R | I2C_DR11_R-DIFF1 | PAIR | 4 | 6 | 5 | 10 | 5 | 14 | 6 | 15 | 12 | 12 | 12 | 12 | 15 |  |  |
| SCL_DR11_R | I2C_DR11_R-DIFF1 | PAIR | 5 | 6 | 5 | 10 | 5 | 14 | 6 | 15 | 12 | 12 | 12 | 12 | 15 |  |  |
| SCL_DR11_R | I2C_DR11_R-DIFF1 | PAIR | 6 | 6 | 5 | 10 | 5 | 14 | 6 | 15 | 12 | 12 | 12 | 12 | 15 |  |  |
| SCL_DR11_R | I2C_DR11_R-DIFF1 | PAIR | 7 | 6 | 5 | 10 | 5 | 14 | 6 | 15 | 12 | 12 | 12 | 12 | 15 |  |  |
| SCL_DR11_R | I2C_DR11_R-DIFF1 | PAIR | 8 | 6.75 | 5 | 10 | 5 | 14 | 6 | 15 | 12 | 12 | 12 | 12 | 15 |  |  |
| SDA_DR11_R | I2C_DR11_R-DIFF1 | PAIR | 1 | 6.75 | 5 | 10 | 5 | 14 | 6 | 15 | 12 | 12 | 12 | 12 | 15 |  |  |
| SDA_DR11_R | I2C_DR11_R-DIFF1 | PAIR | 2 | 6 | 5 | 10 | 5 | 14 | 6 | 15 | 12 | 12 | 12 | 12 | 15 |  |  |
| SDA_DR11_R | I2C_DR11_R-DIFF1 | PAIR | 3 | 6 | 5 | 10 | 5 | 14 | 6 | 15 | 12 | 12 | 12 | 12 | 15 |  |  |
| SDA_DR11_R | I2C_DR11_R-DIFF1 | PAIR | 4 | 6 | 5 | 10 | 5 | 14 | 6 | 15 | 12 | 12 | 12 | 12 | 15 |  |  |
| SDA_DR11_R | I2C_DR11_R-DIFF1 | PAIR | 5 | 6 | 5 | 10 | 5 | 14 | 6 | 15 | 12 | 12 | 12 | 12 | 15 |  |  |
| SDA_DR11_R | I2C_DR11_R-DIFF1 | PAIR | 6 | 6 | 5 | 10 | 5 | 14 | 6 | 15 | 12 | 12 | 12 | 12 | 15 |  |  |
| SDA_DR11_R | I2C_DR11_R-DIFF1 | PAIR | 7 | 6 | 5 | 10 | 5 | 14 | 6 | 15 | 12 | 12 | 12 | 12 | 15 |  |  |
| SDA_DR11_R | I2C_DR11_R-DIFF1 | PAIR | 8 | 6.75 | 5 | 10 | 5 | 14 | 6 | 15 | 12 | 12 | 12 | 12 | 15 |  |  |
| SCL_DR11 | I2C_DR11-DIFF1 | PAIR | 1 | 6.75 | 5 | 10 | 5 | 14 | 6 | 15 | 12 | 12 | 12 | 12 | 15 |  |  |
| SCL_DR11 | I2C_DR11-DIFF1 | PAIR | 2 | 6 | 5 | 10 | 5 | 14 | 6 | 15 | 12 | 12 | 12 | 12 | 15 |  |  |
| SCL_DR11 | I2C_DR11-DIFF1 | PAIR | 3 | 6 | 5 | 10 | 5 | 14 | 6 | 15 | 12 | 12 | 12 | 12 | 15 |  |  |
| SCL_DR11 | I2C_DR11-DIFF1 | PAIR | 4 | 6 | 5 | 10 | 5 | 14 | 6 | 15 | 12 | 12 | 12 | 12 | 15 |  |  |
| SCL_DR11 | I2C_DR11-DIFF1 | PAIR | 5 | 6 | 5 | 10 | 5 | 14 | 6 | 15 | 12 | 12 | 12 | 12 | 15 |  |  |
| SCL_DR11 | I2C_DR11-DIFF1 | PAIR | 6 | 6 | 5 | 10 | 5 | 14 | 6 | 15 | 12 | 12 | 12 | 12 | 15 |  |  |
| SCL_DR11 | I2C_DR11-DIFF1 | PAIR | 7 | 6 | 5 | 10 | 5 | 14 | 6 | 15 | 12 | 12 | 12 | 12 | 15 |  |  |
| SCL_DR11 | I2C_DR11-DIFF1 | PAIR | 8 | 6.75 | 5 | 10 | 5 | 14 | 6 | 15 | 12 | 12 | 12 | 12 | 15 |  |  |
| SDA_DR11 | I2C_DR11-DIFF1 | PAIR | 1 | 6.75 | 5 | 10 | 5 | 14 | 6 | 15 | 12 | 12 | 12 | 12 | 15 |  |  |
| SDA_DR11 | I2C_DR11-DIFF1 | PAIR | 2 | 6 | 5 | 10 | 5 | 14 | 6 | 15 | 12 | 12 | 12 | 12 | 15 |  |  |
| SDA_DR11 | I2C_DR11-DIFF1 | PAIR | 3 | 6 | 5 | 10 | 5 | 14 | 6 | 15 | 12 | 12 | 12 | 12 | 15 |  |  |
| SDA_DR11 | I2C_DR11-DIFF1 | PAIR | 4 | 6 | 5 | 10 | 5 | 14 | 6 | 15 | 12 | 12 | 12 | 12 | 15 |  |  |
| SDA_DR11 | I2C_DR11-DIFF1 | PAIR | 5 | 6 | 5 | 10 | 5 | 14 | 6 | 15 | 12 | 12 | 12 | 12 | 15 |  |  |
| SDA_DR11 | I2C_DR11-DIFF1 | PAIR | 6 | 6 | 5 | 10 | 5 | 14 | 6 | 15 | 12 | 12 | 12 | 12 | 15 |  |  |
| SDA_DR11 | I2C_DR11-DIFF1 | PAIR | 7 | 6 | 5 | 10 | 5 | 14 | 6 | 15 | 12 | 12 | 12 | 12 | 15 |  |  |
| SDA_DR11 | I2C_DR11-DIFF1 | PAIR | 8 | 6.75 | 5 | 10 | 5 | 14 | 6 | 15 | 12 | 12 | 12 | 12 | 15 |  |  |
| SCL_DR12_R | I2C_DR12_R-DIFF1 | PAIR | 1 | 6.75 | 5 | 10 | 5 | 14 | 6 | 15 | 12 | 12 | 12 | 12 | 15 |  |  |
| SCL_DR12_R | I2C_DR12_R-DIFF1 | PAIR | 2 | 6 | 5 | 10 | 5 | 14 | 6 | 15 | 12 | 12 | 12 | 12 | 15 |  |  |
| SCL_DR12_R | I2C_DR12_R-DIFF1 | PAIR | 3 | 6 | 5 | 10 | 5 | 14 | 6 | 15 | 12 | 12 | 12 | 12 | 15 |  |  |
| SCL_DR12_R | I2C_DR12_R-DIFF1 | PAIR | 4 | 6 | 5 | 10 | 5 | 14 | 6 | 15 | 12 | 12 | 12 | 12 | 15 |  |  |
| SCL_DR12_R | I2C_DR12_R-DIFF1 | PAIR | 5 | 6 | 5 | 10 | 5 | 14 | 6 | 15 | 12 | 12 | 12 | 12 | 15 |  |  |
| SCL_DR12_R | I2C_DR12_R-DIFF1 | PAIR | 6 | 6 | 5 | 10 | 5 | 14 | 6 | 15 | 12 | 12 | 12 | 12 | 15 |  |  |
| SCL_DR12_R | I2C_DR12_R-DIFF1 | PAIR | 7 | 6 | 5 | 10 | 5 | 14 | 6 | 15 | 12 | 12 | 12 | 12 | 15 |  |  |
| SCL_DR12_R | I2C_DR12_R-DIFF1 | PAIR | 8 | 6.75 | 5 | 10 | 5 | 14 | 6 | 15 | 12 | 12 | 12 | 12 | 15 |  |  |
| SDA_DR12_R | I2C_DR12_R-DIFF1 | PAIR | 1 | 6.75 | 5 | 10 | 5 | 14 | 6 | 15 | 12 | 12 | 12 | 12 | 15 |  |  |
| SDA_DR12_R | I2C_DR12_R-DIFF1 | PAIR | 2 | 6 | 5 | 10 | 5 | 14 | 6 | 15 | 12 | 12 | 12 | 12 | 15 |  |  |
| SDA_DR12_R | I2C_DR12_R-DIFF1 | PAIR | 3 | 6 | 5 | 10 | 5 | 14 | 6 | 15 | 12 | 12 | 12 | 12 | 15 |  |  |
| SDA_DR12_R | I2C_DR12_R-DIFF1 | PAIR | 4 | 6 | 5 | 10 | 5 | 14 | 6 | 15 | 12 | 12 | 12 | 12 | 15 |  |  |
| SDA_DR12_R | I2C_DR12_R-DIFF1 | PAIR | 5 | 6 | 5 | 10 | 5 | 14 | 6 | 15 | 12 | 12 | 12 | 12 | 15 |  |  |
| SDA_DR12_R | I2C_DR12_R-DIFF1 | PAIR | 6 | 6 | 5 | 10 | 5 | 14 | 6 | 15 | 12 | 12 | 12 | 12 | 15 |  |  |
| SDA_DR12_R | I2C_DR12_R-DIFF1 | PAIR | 7 | 6 | 5 | 10 | 5 | 14 | 6 | 15 | 12 | 12 | 12 | 12 | 15 |  |  |
| SDA_DR12_R | I2C_DR12_R-DIFF1 | PAIR | 8 | 6.75 | 5 | 10 | 5 | 14 | 6 | 15 | 12 | 12 | 12 | 12 | 15 |  |  |
| SCL_DR12 | I2C_DR12-DIFF1 | PAIR | 1 | 6.75 | 5 | 10 | 5 | 14 | 6 | 15 | 12 | 12 | 12 | 12 | 15 |  |  |
| SCL_DR12 | I2C_DR12-DIFF1 | PAIR | 2 | 6 | 5 | 10 | 5 | 14 | 6 | 15 | 12 | 12 | 12 | 12 | 15 |  |  |
| SCL_DR12 | I2C_DR12-DIFF1 | PAIR | 3 | 6 | 5 | 10 | 5 | 14 | 6 | 15 | 12 | 12 | 12 | 12 | 15 |  |  |
| SCL_DR12 | I2C_DR12-DIFF1 | PAIR | 4 | 6 | 5 | 10 | 5 | 14 | 6 | 15 | 12 | 12 | 12 | 12 | 15 |  |  |
| SCL_DR12 | I2C_DR12-DIFF1 | PAIR | 5 | 6 | 5 | 10 | 5 | 14 | 6 | 15 | 12 | 12 | 12 | 12 | 15 |  |  |
| SCL_DR12 | I2C_DR12-DIFF1 | PAIR | 6 | 6 | 5 | 10 | 5 | 14 | 6 | 15 | 12 | 12 | 12 | 12 | 15 |  |  |
| SCL_DR12 | I2C_DR12-DIFF1 | PAIR | 7 | 6 | 5 | 10 | 5 | 14 | 6 | 15 | 12 | 12 | 12 | 12 | 15 |  |  |
| SCL_DR12 | I2C_DR12-DIFF1 | PAIR | 8 | 6.75 | 5 | 10 | 5 | 14 | 6 | 15 | 12 | 12 | 12 | 12 | 15 |  |  |
| SDA_DR12 | I2C_DR12-DIFF1 | PAIR | 1 | 6.75 | 5 | 10 | 5 | 14 | 6 | 15 | 12 | 12 | 12 | 12 | 15 |  |  |
| SDA_DR12 | I2C_DR12-DIFF1 | PAIR | 2 | 6 | 5 | 10 | 5 | 14 | 6 | 15 | 12 | 12 | 12 | 12 | 15 |  |  |
| SDA_DR12 | I2C_DR12-DIFF1 | PAIR | 3 | 6 | 5 | 10 | 5 | 14 | 6 | 15 | 12 | 12 | 12 | 12 | 15 |  |  |
| SDA_DR12 | I2C_DR12-DIFF1 | PAIR | 4 | 6 | 5 | 10 | 5 | 14 | 6 | 15 | 12 | 12 | 12 | 12 | 15 |  |  |
| SDA_DR12 | I2C_DR12-DIFF1 | PAIR | 5 | 6 | 5 | 10 | 5 | 14 | 6 | 15 | 12 | 12 | 12 | 12 | 15 |  |  |
| SDA_DR12 | I2C_DR12-DIFF1 | PAIR | 6 | 6 | 5 | 10 | 5 | 14 | 6 | 15 | 12 | 12 | 12 | 12 | 15 |  |  |
| SDA_DR12 | I2C_DR12-DIFF1 | PAIR | 7 | 6 | 5 | 10 | 5 | 14 | 6 | 15 | 12 | 12 | 12 | 12 | 15 |  |  |
| SDA_DR12 | I2C_DR12-DIFF1 | PAIR | 8 | 6.75 | 5 | 10 | 5 | 14 | 6 | 15 | 12 | 12 | 12 | 12 | 15 |  |  |
| SCL_DR13_R | I2C_DR13_R-DIFF1 | PAIR | 1 | 6.75 | 5 | 10 | 5 | 14 | 6 | 15 | 12 | 12 | 12 | 12 | 15 |  |  |
| SCL_DR13_R | I2C_DR13_R-DIFF1 | PAIR | 2 | 6 | 5 | 10 | 5 | 14 | 6 | 15 | 12 | 12 | 12 | 12 | 15 |  |  |
| SCL_DR13_R | I2C_DR13_R-DIFF1 | PAIR | 3 | 6 | 5 | 10 | 5 | 14 | 6 | 15 | 12 | 12 | 12 | 12 | 15 |  |  |
| SCL_DR13_R | I2C_DR13_R-DIFF1 | PAIR | 4 | 6 | 5 | 10 | 5 | 14 | 6 | 15 | 12 | 12 | 12 | 12 | 15 |  |  |
| SCL_DR13_R | I2C_DR13_R-DIFF1 | PAIR | 5 | 6 | 5 | 10 | 5 | 14 | 6 | 15 | 12 | 12 | 12 | 12 | 15 |  |  |
| SCL_DR13_R | I2C_DR13_R-DIFF1 | PAIR | 6 | 6 | 5 | 10 | 5 | 14 | 6 | 15 | 12 | 12 | 12 | 12 | 15 |  |  |
| SCL_DR13_R | I2C_DR13_R-DIFF1 | PAIR | 7 | 6 | 5 | 10 | 5 | 14 | 6 | 15 | 12 | 12 | 12 | 12 | 15 |  |  |
| SCL_DR13_R | I2C_DR13_R-DIFF1 | PAIR | 8 | 6.75 | 5 | 10 | 5 | 14 | 6 | 15 | 12 | 12 | 12 | 12 | 15 |  |  |
| SDA_DR13_R | I2C_DR13_R-DIFF1 | PAIR | 1 | 6.75 | 5 | 10 | 5 | 14 | 6 | 15 | 12 | 12 | 12 | 12 | 15 |  |  |
| SDA_DR13_R | I2C_DR13_R-DIFF1 | PAIR | 2 | 6 | 5 | 10 | 5 | 14 | 6 | 15 | 12 | 12 | 12 | 12 | 15 |  |  |
| SDA_DR13_R | I2C_DR13_R-DIFF1 | PAIR | 3 | 6 | 5 | 10 | 5 | 14 | 6 | 15 | 12 | 12 | 12 | 12 | 15 |  |  |
| SDA_DR13_R | I2C_DR13_R-DIFF1 | PAIR | 4 | 6 | 5 | 10 | 5 | 14 | 6 | 15 | 12 | 12 | 12 | 12 | 15 |  |  |
| SDA_DR13_R | I2C_DR13_R-DIFF1 | PAIR | 5 | 6 | 5 | 10 | 5 | 14 | 6 | 15 | 12 | 12 | 12 | 12 | 15 |  |  |
| SDA_DR13_R | I2C_DR13_R-DIFF1 | PAIR | 6 | 6 | 5 | 10 | 5 | 14 | 6 | 15 | 12 | 12 | 12 | 12 | 15 |  |  |
| SDA_DR13_R | I2C_DR13_R-DIFF1 | PAIR | 7 | 6 | 5 | 10 | 5 | 14 | 6 | 15 | 12 | 12 | 12 | 12 | 15 |  |  |
| SDA_DR13_R | I2C_DR13_R-DIFF1 | PAIR | 8 | 6.75 | 5 | 10 | 5 | 14 | 6 | 15 | 12 | 12 | 12 | 12 | 15 |  |  |
| SCL_DR13 | I2C_DR13-DIFF1 | PAIR | 1 | 6.75 | 5 | 10 | 5 | 14 | 6 | 15 | 12 | 12 | 12 | 12 | 15 |  |  |
| SCL_DR13 | I2C_DR13-DIFF1 | PAIR | 2 | 6 | 5 | 10 | 5 | 14 | 6 | 15 | 12 | 12 | 12 | 12 | 15 |  |  |
| SCL_DR13 | I2C_DR13-DIFF1 | PAIR | 3 | 6 | 5 | 10 | 5 | 14 | 6 | 15 | 12 | 12 | 12 | 12 | 15 |  |  |
| SCL_DR13 | I2C_DR13-DIFF1 | PAIR | 4 | 6 | 5 | 10 | 5 | 14 | 6 | 15 | 12 | 12 | 12 | 12 | 15 |  |  |
| SCL_DR13 | I2C_DR13-DIFF1 | PAIR | 5 | 6 | 5 | 10 | 5 | 14 | 6 | 15 | 12 | 12 | 12 | 12 | 15 |  |  |
| SCL_DR13 | I2C_DR13-DIFF1 | PAIR | 6 | 6 | 5 | 10 | 5 | 14 | 6 | 15 | 12 | 12 | 12 | 12 | 15 |  |  |
| SCL_DR13 | I2C_DR13-DIFF1 | PAIR | 7 | 6 | 5 | 10 | 5 | 14 | 6 | 15 | 12 | 12 | 12 | 12 | 15 |  |  |
| SCL_DR13 | I2C_DR13-DIFF1 | PAIR | 8 | 6.75 | 5 | 10 | 5 | 14 | 6 | 15 | 12 | 12 | 12 | 12 | 15 |  |  |
| SDA_DR13 | I2C_DR13-DIFF1 | PAIR | 1 | 6.75 | 5 | 10 | 5 | 14 | 6 | 15 | 12 | 12 | 12 | 12 | 15 |  |  |
| SDA_DR13 | I2C_DR13-DIFF1 | PAIR | 2 | 6 | 5 | 10 | 5 | 14 | 6 | 15 | 12 | 12 | 12 | 12 | 15 |  |  |
| SDA_DR13 | I2C_DR13-DIFF1 | PAIR | 3 | 6 | 5 | 10 | 5 | 14 | 6 | 15 | 12 | 12 | 12 | 12 | 15 |  |  |
| SDA_DR13 | I2C_DR13-DIFF1 | PAIR | 4 | 6 | 5 | 10 | 5 | 14 | 6 | 15 | 12 | 12 | 12 | 12 | 15 |  |  |
| SDA_DR13 | I2C_DR13-DIFF1 | PAIR | 5 | 6 | 5 | 10 | 5 | 14 | 6 | 15 | 12 | 12 | 12 | 12 | 15 |  |  |
| SDA_DR13 | I2C_DR13-DIFF1 | PAIR | 6 | 6 | 5 | 10 | 5 | 14 | 6 | 15 | 12 | 12 | 12 | 12 | 15 |  |  |
| SDA_DR13 | I2C_DR13-DIFF1 | PAIR | 7 | 6 | 5 | 10 | 5 | 14 | 6 | 15 | 12 | 12 | 12 | 12 | 15 |  |  |
| SDA_DR13 | I2C_DR13-DIFF1 | PAIR | 8 | 6.75 | 5 | 10 | 5 | 14 | 6 | 15 | 12 | 12 | 12 | 12 | 15 |  |  |
| SCL_DR14_R | I2C_DR14_R-DIFF1 | PAIR | 1 | 6.75 | 5 | 10 | 5 | 14 | 6 | 15 | 12 | 12 | 12 | 12 | 15 |  |  |
| SCL_DR14_R | I2C_DR14_R-DIFF1 | PAIR | 2 | 6 | 5 | 10 | 5 | 14 | 6 | 15 | 12 | 12 | 12 | 12 | 15 |  |  |
| SCL_DR14_R | I2C_DR14_R-DIFF1 | PAIR | 3 | 6 | 5 | 10 | 5 | 14 | 6 | 15 | 12 | 12 | 12 | 12 | 15 |  |  |
| SCL_DR14_R | I2C_DR14_R-DIFF1 | PAIR | 4 | 6 | 5 | 10 | 5 | 14 | 6 | 15 | 12 | 12 | 12 | 12 | 15 |  |  |
| SCL_DR14_R | I2C_DR14_R-DIFF1 | PAIR | 5 | 6 | 5 | 10 | 5 | 14 | 6 | 15 | 12 | 12 | 12 | 12 | 15 |  |  |
| SCL_DR14_R | I2C_DR14_R-DIFF1 | PAIR | 6 | 6 | 5 | 10 | 5 | 14 | 6 | 15 | 12 | 12 | 12 | 12 | 15 |  |  |
| SCL_DR14_R | I2C_DR14_R-DIFF1 | PAIR | 7 | 6 | 5 | 10 | 5 | 14 | 6 | 15 | 12 | 12 | 12 | 12 | 15 |  |  |
| SCL_DR14_R | I2C_DR14_R-DIFF1 | PAIR | 8 | 6.75 | 5 | 10 | 5 | 14 | 6 | 15 | 12 | 12 | 12 | 12 | 15 |  |  |
| SDA_DR14_R | I2C_DR14_R-DIFF1 | PAIR | 1 | 6.75 | 5 | 10 | 5 | 14 | 6 | 15 | 12 | 12 | 12 | 12 | 15 |  |  |
| SDA_DR14_R | I2C_DR14_R-DIFF1 | PAIR | 2 | 6 | 5 | 10 | 5 | 14 | 6 | 15 | 12 | 12 | 12 | 12 | 15 |  |  |
| SDA_DR14_R | I2C_DR14_R-DIFF1 | PAIR | 3 | 6 | 5 | 10 | 5 | 14 | 6 | 15 | 12 | 12 | 12 | 12 | 15 |  |  |
| SDA_DR14_R | I2C_DR14_R-DIFF1 | PAIR | 4 | 6 | 5 | 10 | 5 | 14 | 6 | 15 | 12 | 12 | 12 | 12 | 15 |  |  |
| SDA_DR14_R | I2C_DR14_R-DIFF1 | PAIR | 5 | 6 | 5 | 10 | 5 | 14 | 6 | 15 | 12 | 12 | 12 | 12 | 15 |  |  |
| SDA_DR14_R | I2C_DR14_R-DIFF1 | PAIR | 6 | 6 | 5 | 10 | 5 | 14 | 6 | 15 | 12 | 12 | 12 | 12 | 15 |  |  |
| SDA_DR14_R | I2C_DR14_R-DIFF1 | PAIR | 7 | 6 | 5 | 10 | 5 | 14 | 6 | 15 | 12 | 12 | 12 | 12 | 15 |  |  |
| SDA_DR14_R | I2C_DR14_R-DIFF1 | PAIR | 8 | 6.75 | 5 | 10 | 5 | 14 | 6 | 15 | 12 | 12 | 12 | 12 | 15 |  |  |
| SCL_DR14 | I2C_DR14-DIFF1 | PAIR | 1 | 6.75 | 5 | 10 | 5 | 14 | 6 | 15 | 12 | 12 | 12 | 12 | 15 |  |  |
| SCL_DR14 | I2C_DR14-DIFF1 | PAIR | 2 | 6 | 5 | 10 | 5 | 14 | 6 | 15 | 12 | 12 | 12 | 12 | 15 |  |  |
| SCL_DR14 | I2C_DR14-DIFF1 | PAIR | 3 | 6 | 5 | 10 | 5 | 14 | 6 | 15 | 12 | 12 | 12 | 12 | 15 |  |  |
| SCL_DR14 | I2C_DR14-DIFF1 | PAIR | 4 | 6 | 5 | 10 | 5 | 14 | 6 | 15 | 12 | 12 | 12 | 12 | 15 |  |  |
| SCL_DR14 | I2C_DR14-DIFF1 | PAIR | 5 | 6 | 5 | 10 | 5 | 14 | 6 | 15 | 12 | 12 | 12 | 12 | 15 |  |  |
| SCL_DR14 | I2C_DR14-DIFF1 | PAIR | 6 | 6 | 5 | 10 | 5 | 14 | 6 | 15 | 12 | 12 | 12 | 12 | 15 |  |  |
| SCL_DR14 | I2C_DR14-DIFF1 | PAIR | 7 | 6 | 5 | 10 | 5 | 14 | 6 | 15 | 12 | 12 | 12 | 12 | 15 |  |  |
| SCL_DR14 | I2C_DR14-DIFF1 | PAIR | 8 | 6.75 | 5 | 10 | 5 | 14 | 6 | 15 | 12 | 12 | 12 | 12 | 15 |  |  |
| SDA_DR14 | I2C_DR14-DIFF1 | PAIR | 1 | 6.75 | 5 | 10 | 5 | 14 | 6 | 15 | 12 | 12 | 12 | 12 | 15 |  |  |
| SDA_DR14 | I2C_DR14-DIFF1 | PAIR | 2 | 6 | 5 | 10 | 5 | 14 | 6 | 15 | 12 | 12 | 12 | 12 | 15 |  |  |
| SDA_DR14 | I2C_DR14-DIFF1 | PAIR | 3 | 6 | 5 | 10 | 5 | 14 | 6 | 15 | 12 | 12 | 12 | 12 | 15 |  |  |
| SDA_DR14 | I2C_DR14-DIFF1 | PAIR | 4 | 6 | 5 | 10 | 5 | 14 | 6 | 15 | 12 | 12 | 12 | 12 | 15 |  |  |
| SDA_DR14 | I2C_DR14-DIFF1 | PAIR | 5 | 6 | 5 | 10 | 5 | 14 | 6 | 15 | 12 | 12 | 12 | 12 | 15 |  |  |
| SDA_DR14 | I2C_DR14-DIFF1 | PAIR | 6 | 6 | 5 | 10 | 5 | 14 | 6 | 15 | 12 | 12 | 12 | 12 | 15 |  |  |
| SDA_DR14 | I2C_DR14-DIFF1 | PAIR | 7 | 6 | 5 | 10 | 5 | 14 | 6 | 15 | 12 | 12 | 12 | 12 | 15 |  |  |
| SDA_DR14 | I2C_DR14-DIFF1 | PAIR | 8 | 6.75 | 5 | 10 | 5 | 14 | 6 | 15 | 12 | 12 | 12 | 12 | 15 |  |  |
| SCL_DR1 | I2C_DR1-DIFF1 | PAIR | 1 | 6.75 | 5 | 10 | 5 | 14 | 6 | 15 | 12 | 12 | 12 | 12 | 15 |  |  |
| SCL_DR1 | I2C_DR1-DIFF1 | PAIR | 2 | 6 | 5 | 10 | 5 | 14 | 6 | 15 | 12 | 12 | 12 | 12 | 15 |  |  |
| SCL_DR1 | I2C_DR1-DIFF1 | PAIR | 3 | 6 | 5 | 10 | 5 | 14 | 6 | 15 | 12 | 12 | 12 | 12 | 15 |  |  |
| SCL_DR1 | I2C_DR1-DIFF1 | PAIR | 4 | 6 | 5 | 10 | 5 | 14 | 6 | 15 | 12 | 12 | 12 | 12 | 15 |  |  |
| SCL_DR1 | I2C_DR1-DIFF1 | PAIR | 5 | 6 | 5 | 10 | 5 | 14 | 6 | 15 | 12 | 12 | 12 | 12 | 15 |  |  |
| SCL_DR1 | I2C_DR1-DIFF1 | PAIR | 6 | 6 | 5 | 10 | 5 | 14 | 6 | 15 | 12 | 12 | 12 | 12 | 15 |  |  |
| SCL_DR1 | I2C_DR1-DIFF1 | PAIR | 7 | 6 | 5 | 10 | 5 | 14 | 6 | 15 | 12 | 12 | 12 | 12 | 15 |  |  |
| SCL_DR1 | I2C_DR1-DIFF1 | PAIR | 8 | 6.75 | 5 | 10 | 5 | 14 | 6 | 15 | 12 | 12 | 12 | 12 | 15 |  |  |
| SDA_DR1 | I2C_DR1-DIFF1 | PAIR | 1 | 6.75 | 5 | 10 | 5 | 14 | 6 | 15 | 12 | 12 | 12 | 12 | 15 |  |  |
| SDA_DR1 | I2C_DR1-DIFF1 | PAIR | 2 | 6 | 5 | 10 | 5 | 14 | 6 | 15 | 12 | 12 | 12 | 12 | 15 |  |  |
| SDA_DR1 | I2C_DR1-DIFF1 | PAIR | 3 | 6 | 5 | 10 | 5 | 14 | 6 | 15 | 12 | 12 | 12 | 12 | 15 |  |  |
| SDA_DR1 | I2C_DR1-DIFF1 | PAIR | 4 | 6 | 5 | 10 | 5 | 14 | 6 | 15 | 12 | 12 | 12 | 12 | 15 |  |  |
| SDA_DR1 | I2C_DR1-DIFF1 | PAIR | 5 | 6 | 5 | 10 | 5 | 14 | 6 | 15 | 12 | 12 | 12 | 12 | 15 |  |  |
| SDA_DR1 | I2C_DR1-DIFF1 | PAIR | 6 | 6 | 5 | 10 | 5 | 14 | 6 | 15 | 12 | 12 | 12 | 12 | 15 |  |  |
| SDA_DR1 | I2C_DR1-DIFF1 | PAIR | 7 | 6 | 5 | 10 | 5 | 14 | 6 | 15 | 12 | 12 | 12 | 12 | 15 |  |  |
| SDA_DR1 | I2C_DR1-DIFF1 | PAIR | 8 | 6.75 | 5 | 10 | 5 | 14 | 6 | 15 | 12 | 12 | 12 | 12 | 15 |  |  |
| SCL_DR2_R | I2C_DR2_R-DIFF1 | PAIR | 1 | 6.75 | 5 | 10 | 5 | 14 | 6 | 15 | 12 | 12 | 12 | 12 | 15 |  |  |
| SCL_DR2_R | I2C_DR2_R-DIFF1 | PAIR | 2 | 6 | 5 | 10 | 5 | 14 | 6 | 15 | 12 | 12 | 12 | 12 | 15 |  |  |
| SCL_DR2_R | I2C_DR2_R-DIFF1 | PAIR | 3 | 6 | 5 | 10 | 5 | 14 | 6 | 15 | 12 | 12 | 12 | 12 | 15 |  |  |
| SCL_DR2_R | I2C_DR2_R-DIFF1 | PAIR | 4 | 6 | 5 | 10 | 5 | 14 | 6 | 15 | 12 | 12 | 12 | 12 | 15 |  |  |
| SCL_DR2_R | I2C_DR2_R-DIFF1 | PAIR | 5 | 6 | 5 | 10 | 5 | 14 | 6 | 15 | 12 | 12 | 12 | 12 | 15 |  |  |
| SCL_DR2_R | I2C_DR2_R-DIFF1 | PAIR | 6 | 6 | 5 | 10 | 5 | 14 | 6 | 15 | 12 | 12 | 12 | 12 | 15 |  |  |
| SCL_DR2_R | I2C_DR2_R-DIFF1 | PAIR | 7 | 6 | 5 | 10 | 5 | 14 | 6 | 15 | 12 | 12 | 12 | 12 | 15 |  |  |
| SCL_DR2_R | I2C_DR2_R-DIFF1 | PAIR | 8 | 6.75 | 5 | 10 | 5 | 14 | 6 | 15 | 12 | 12 | 12 | 12 | 15 |  |  |
| SDA_DR2_R | I2C_DR2_R-DIFF1 | PAIR | 1 | 6.75 | 5 | 10 | 5 | 14 | 6 | 15 | 12 | 12 | 12 | 12 | 15 |  |  |
| SDA_DR2_R | I2C_DR2_R-DIFF1 | PAIR | 2 | 6 | 5 | 10 | 5 | 14 | 6 | 15 | 12 | 12 | 12 | 12 | 15 |  |  |
| SDA_DR2_R | I2C_DR2_R-DIFF1 | PAIR | 3 | 6 | 5 | 10 | 5 | 14 | 6 | 15 | 12 | 12 | 12 | 12 | 15 |  |  |
| SDA_DR2_R | I2C_DR2_R-DIFF1 | PAIR | 4 | 6 | 5 | 10 | 5 | 14 | 6 | 15 | 12 | 12 | 12 | 12 | 15 |  |  |
| SDA_DR2_R | I2C_DR2_R-DIFF1 | PAIR | 5 | 6 | 5 | 10 | 5 | 14 | 6 | 15 | 12 | 12 | 12 | 12 | 15 |  |  |
| SDA_DR2_R | I2C_DR2_R-DIFF1 | PAIR | 6 | 6 | 5 | 10 | 5 | 14 | 6 | 15 | 12 | 12 | 12 | 12 | 15 |  |  |
| SDA_DR2_R | I2C_DR2_R-DIFF1 | PAIR | 7 | 6 | 5 | 10 | 5 | 14 | 6 | 15 | 12 | 12 | 12 | 12 | 15 |  |  |
| SDA_DR2_R | I2C_DR2_R-DIFF1 | PAIR | 8 | 6.75 | 5 | 10 | 5 | 14 | 6 | 15 | 12 | 12 | 12 | 12 | 15 |  |  |
| SCL_DR2 | I2C_DR2-DIFF1 | PAIR | 1 | 6.75 | 5 | 10 | 5 | 14 | 6 | 15 | 12 | 12 | 12 | 12 | 15 |  |  |
| SCL_DR2 | I2C_DR2-DIFF1 | PAIR | 2 | 6 | 5 | 10 | 5 | 14 | 6 | 15 | 12 | 12 | 12 | 12 | 15 |  |  |
| SCL_DR2 | I2C_DR2-DIFF1 | PAIR | 3 | 6 | 5 | 10 | 5 | 14 | 6 | 15 | 12 | 12 | 12 | 12 | 15 |  |  |
| SCL_DR2 | I2C_DR2-DIFF1 | PAIR | 4 | 6 | 5 | 10 | 5 | 14 | 6 | 15 | 12 | 12 | 12 | 12 | 15 |  |  |
| SCL_DR2 | I2C_DR2-DIFF1 | PAIR | 5 | 6 | 5 | 10 | 5 | 14 | 6 | 15 | 12 | 12 | 12 | 12 | 15 |  |  |
| SCL_DR2 | I2C_DR2-DIFF1 | PAIR | 6 | 6 | 5 | 10 | 5 | 14 | 6 | 15 | 12 | 12 | 12 | 12 | 15 |  |  |
| SCL_DR2 | I2C_DR2-DIFF1 | PAIR | 7 | 6 | 5 | 10 | 5 | 14 | 6 | 15 | 12 | 12 | 12 | 12 | 15 |  |  |
| SCL_DR2 | I2C_DR2-DIFF1 | PAIR | 8 | 6.75 | 5 | 10 | 5 | 14 | 6 | 15 | 12 | 12 | 12 | 12 | 15 |  |  |
| SDA_DR2 | I2C_DR2-DIFF1 | PAIR | 1 | 6.75 | 5 | 10 | 5 | 14 | 6 | 15 | 12 | 12 | 12 | 12 | 15 |  |  |
| SDA_DR2 | I2C_DR2-DIFF1 | PAIR | 2 | 6 | 5 | 10 | 5 | 14 | 6 | 15 | 12 | 12 | 12 | 12 | 15 |  |  |
| SDA_DR2 | I2C_DR2-DIFF1 | PAIR | 3 | 6 | 5 | 10 | 5 | 14 | 6 | 15 | 12 | 12 | 12 | 12 | 15 |  |  |
| SDA_DR2 | I2C_DR2-DIFF1 | PAIR | 4 | 6 | 5 | 10 | 5 | 14 | 6 | 15 | 12 | 12 | 12 | 12 | 15 |  |  |
| SDA_DR2 | I2C_DR2-DIFF1 | PAIR | 5 | 6 | 5 | 10 | 5 | 14 | 6 | 15 | 12 | 12 | 12 | 12 | 15 |  |  |
| SDA_DR2 | I2C_DR2-DIFF1 | PAIR | 6 | 6 | 5 | 10 | 5 | 14 | 6 | 15 | 12 | 12 | 12 | 12 | 15 |  |  |
| SDA_DR2 | I2C_DR2-DIFF1 | PAIR | 7 | 6 | 5 | 10 | 5 | 14 | 6 | 15 | 12 | 12 | 12 | 12 | 15 |  |  |
| SDA_DR2 | I2C_DR2-DIFF1 | PAIR | 8 | 6.75 | 5 | 10 | 5 | 14 | 6 | 15 | 12 | 12 | 12 | 12 | 15 |  |  |
| SCL_DR3_R | I2C_DR3_R-DIFF1 | PAIR | 1 | 6.75 | 5 | 10 | 5 | 14 | 6 | 15 | 12 | 12 | 12 | 12 | 15 |  |  |
| SCL_DR3_R | I2C_DR3_R-DIFF1 | PAIR | 2 | 6 | 5 | 10 | 5 | 14 | 6 | 15 | 12 | 12 | 12 | 12 | 15 |  |  |
| SCL_DR3_R | I2C_DR3_R-DIFF1 | PAIR | 3 | 6 | 5 | 10 | 5 | 14 | 6 | 15 | 12 | 12 | 12 | 12 | 15 |  |  |
| SCL_DR3_R | I2C_DR3_R-DIFF1 | PAIR | 4 | 6 | 5 | 10 | 5 | 14 | 6 | 15 | 12 | 12 | 12 | 12 | 15 |  |  |
| SCL_DR3_R | I2C_DR3_R-DIFF1 | PAIR | 5 | 6 | 5 | 10 | 5 | 14 | 6 | 15 | 12 | 12 | 12 | 12 | 15 |  |  |
| SCL_DR3_R | I2C_DR3_R-DIFF1 | PAIR | 6 | 6 | 5 | 10 | 5 | 14 | 6 | 15 | 12 | 12 | 12 | 12 | 15 |  |  |
| SCL_DR3_R | I2C_DR3_R-DIFF1 | PAIR | 7 | 6 | 5 | 10 | 5 | 14 | 6 | 15 | 12 | 12 | 12 | 12 | 15 |  |  |
| SCL_DR3_R | I2C_DR3_R-DIFF1 | PAIR | 8 | 6.75 | 5 | 10 | 5 | 14 | 6 | 15 | 12 | 12 | 12 | 12 | 15 |  |  |
| SDA_DR3_R | I2C_DR3_R-DIFF1 | PAIR | 1 | 6.75 | 5 | 10 | 5 | 14 | 6 | 15 | 12 | 12 | 12 | 12 | 15 |  |  |
| SDA_DR3_R | I2C_DR3_R-DIFF1 | PAIR | 2 | 6 | 5 | 10 | 5 | 14 | 6 | 15 | 12 | 12 | 12 | 12 | 15 |  |  |
| SDA_DR3_R | I2C_DR3_R-DIFF1 | PAIR | 3 | 6 | 5 | 10 | 5 | 14 | 6 | 15 | 12 | 12 | 12 | 12 | 15 |  |  |
| SDA_DR3_R | I2C_DR3_R-DIFF1 | PAIR | 4 | 6 | 5 | 10 | 5 | 14 | 6 | 15 | 12 | 12 | 12 | 12 | 15 |  |  |
| SDA_DR3_R | I2C_DR3_R-DIFF1 | PAIR | 5 | 6 | 5 | 10 | 5 | 14 | 6 | 15 | 12 | 12 | 12 | 12 | 15 |  |  |
| SDA_DR3_R | I2C_DR3_R-DIFF1 | PAIR | 6 | 6 | 5 | 10 | 5 | 14 | 6 | 15 | 12 | 12 | 12 | 12 | 15 |  |  |
| SDA_DR3_R | I2C_DR3_R-DIFF1 | PAIR | 7 | 6 | 5 | 10 | 5 | 14 | 6 | 15 | 12 | 12 | 12 | 12 | 15 |  |  |
| SDA_DR3_R | I2C_DR3_R-DIFF1 | PAIR | 8 | 6.75 | 5 | 10 | 5 | 14 | 6 | 15 | 12 | 12 | 12 | 12 | 15 |  |  |
| SCL_DR3 | I2C_DR3-DIFF1 | PAIR | 1 | 6.75 | 5 | 10 | 5 | 14 | 6 | 15 | 12 | 12 | 12 | 12 | 15 |  |  |
| SCL_DR3 | I2C_DR3-DIFF1 | PAIR | 2 | 6 | 5 | 10 | 5 | 14 | 6 | 15 | 12 | 12 | 12 | 12 | 15 |  |  |
| SCL_DR3 | I2C_DR3-DIFF1 | PAIR | 3 | 6 | 5 | 10 | 5 | 14 | 6 | 15 | 12 | 12 | 12 | 12 | 15 |  |  |
| SCL_DR3 | I2C_DR3-DIFF1 | PAIR | 4 | 6 | 5 | 10 | 5 | 14 | 6 | 15 | 12 | 12 | 12 | 12 | 15 |  |  |
| SCL_DR3 | I2C_DR3-DIFF1 | PAIR | 5 | 6 | 5 | 10 | 5 | 14 | 6 | 15 | 12 | 12 | 12 | 12 | 15 |  |  |
| SCL_DR3 | I2C_DR3-DIFF1 | PAIR | 6 | 6 | 5 | 10 | 5 | 14 | 6 | 15 | 12 | 12 | 12 | 12 | 15 |  |  |
| SCL_DR3 | I2C_DR3-DIFF1 | PAIR | 7 | 6 | 5 | 10 | 5 | 14 | 6 | 15 | 12 | 12 | 12 | 12 | 15 |  |  |
| SCL_DR3 | I2C_DR3-DIFF1 | PAIR | 8 | 6.75 | 5 | 10 | 5 | 14 | 6 | 15 | 12 | 12 | 12 | 12 | 15 |  |  |
| SDA_DR3 | I2C_DR3-DIFF1 | PAIR | 1 | 6.75 | 5 | 10 | 5 | 14 | 6 | 15 | 12 | 12 | 12 | 12 | 15 |  |  |
| SDA_DR3 | I2C_DR3-DIFF1 | PAIR | 2 | 6 | 5 | 10 | 5 | 14 | 6 | 15 | 12 | 12 | 12 | 12 | 15 |  |  |
| SDA_DR3 | I2C_DR3-DIFF1 | PAIR | 3 | 6 | 5 | 10 | 5 | 14 | 6 | 15 | 12 | 12 | 12 | 12 | 15 |  |  |
| SDA_DR3 | I2C_DR3-DIFF1 | PAIR | 4 | 6 | 5 | 10 | 5 | 14 | 6 | 15 | 12 | 12 | 12 | 12 | 15 |  |  |
| SDA_DR3 | I2C_DR3-DIFF1 | PAIR | 5 | 6 | 5 | 10 | 5 | 14 | 6 | 15 | 12 | 12 | 12 | 12 | 15 |  |  |
| SDA_DR3 | I2C_DR3-DIFF1 | PAIR | 6 | 6 | 5 | 10 | 5 | 14 | 6 | 15 | 12 | 12 | 12 | 12 | 15 |  |  |
| SDA_DR3 | I2C_DR3-DIFF1 | PAIR | 7 | 6 | 5 | 10 | 5 | 14 | 6 | 15 | 12 | 12 | 12 | 12 | 15 |  |  |
| SDA_DR3 | I2C_DR3-DIFF1 | PAIR | 8 | 6.75 | 5 | 10 | 5 | 14 | 6 | 15 | 12 | 12 | 12 | 12 | 15 |  |  |
| SCL_DR4_R | I2C_DR4_R-DIFF1 | PAIR | 1 | 6.75 | 5 | 10 | 5 | 14 | 6 | 15 | 12 | 12 | 12 | 12 | 15 |  |  |
| SCL_DR4_R | I2C_DR4_R-DIFF1 | PAIR | 2 | 6 | 5 | 10 | 5 | 14 | 6 | 15 | 12 | 12 | 12 | 12 | 15 |  |  |
| SCL_DR4_R | I2C_DR4_R-DIFF1 | PAIR | 3 | 6 | 5 | 10 | 5 | 14 | 6 | 15 | 12 | 12 | 12 | 12 | 15 |  |  |
| SCL_DR4_R | I2C_DR4_R-DIFF1 | PAIR | 4 | 6 | 5 | 10 | 5 | 14 | 6 | 15 | 12 | 12 | 12 | 12 | 15 |  |  |
| SCL_DR4_R | I2C_DR4_R-DIFF1 | PAIR | 5 | 6 | 5 | 10 | 5 | 14 | 6 | 15 | 12 | 12 | 12 | 12 | 15 |  |  |
| SCL_DR4_R | I2C_DR4_R-DIFF1 | PAIR | 6 | 6 | 5 | 10 | 5 | 14 | 6 | 15 | 12 | 12 | 12 | 12 | 15 |  |  |
| SCL_DR4_R | I2C_DR4_R-DIFF1 | PAIR | 7 | 6 | 5 | 10 | 5 | 14 | 6 | 15 | 12 | 12 | 12 | 12 | 15 |  |  |
| SCL_DR4_R | I2C_DR4_R-DIFF1 | PAIR | 8 | 6.75 | 5 | 10 | 5 | 14 | 6 | 15 | 12 | 12 | 12 | 12 | 15 |  |  |
| SDA_DR4_R | I2C_DR4_R-DIFF1 | PAIR | 1 | 6.75 | 5 | 10 | 5 | 14 | 6 | 15 | 12 | 12 | 12 | 12 | 15 |  |  |
| SDA_DR4_R | I2C_DR4_R-DIFF1 | PAIR | 2 | 6 | 5 | 10 | 5 | 14 | 6 | 15 | 12 | 12 | 12 | 12 | 15 |  |  |
| SDA_DR4_R | I2C_DR4_R-DIFF1 | PAIR | 3 | 6 | 5 | 10 | 5 | 14 | 6 | 15 | 12 | 12 | 12 | 12 | 15 |  |  |
| SDA_DR4_R | I2C_DR4_R-DIFF1 | PAIR | 4 | 6 | 5 | 10 | 5 | 14 | 6 | 15 | 12 | 12 | 12 | 12 | 15 |  |  |
| SDA_DR4_R | I2C_DR4_R-DIFF1 | PAIR | 5 | 6 | 5 | 10 | 5 | 14 | 6 | 15 | 12 | 12 | 12 | 12 | 15 |  |  |
| SDA_DR4_R | I2C_DR4_R-DIFF1 | PAIR | 6 | 6 | 5 | 10 | 5 | 14 | 6 | 15 | 12 | 12 | 12 | 12 | 15 |  |  |
| SDA_DR4_R | I2C_DR4_R-DIFF1 | PAIR | 7 | 6 | 5 | 10 | 5 | 14 | 6 | 15 | 12 | 12 | 12 | 12 | 15 |  |  |
| SDA_DR4_R | I2C_DR4_R-DIFF1 | PAIR | 8 | 6.75 | 5 | 10 | 5 | 14 | 6 | 15 | 12 | 12 | 12 | 12 | 15 |  |  |
| SCL_DR4 | I2C_DR4-DIFF1 | PAIR | 1 | 6.75 | 5 | 10 | 5 | 14 | 6 | 15 | 12 | 12 | 12 | 12 | 15 |  |  |
| SCL_DR4 | I2C_DR4-DIFF1 | PAIR | 2 | 6 | 5 | 10 | 5 | 14 | 6 | 15 | 12 | 12 | 12 | 12 | 15 |  |  |
| SCL_DR4 | I2C_DR4-DIFF1 | PAIR | 3 | 6 | 5 | 10 | 5 | 14 | 6 | 15 | 12 | 12 | 12 | 12 | 15 |  |  |
| SCL_DR4 | I2C_DR4-DIFF1 | PAIR | 4 | 6 | 5 | 10 | 5 | 14 | 6 | 15 | 12 | 12 | 12 | 12 | 15 |  |  |
| SCL_DR4 | I2C_DR4-DIFF1 | PAIR | 5 | 6 | 5 | 10 | 5 | 14 | 6 | 15 | 12 | 12 | 12 | 12 | 15 |  |  |
| SCL_DR4 | I2C_DR4-DIFF1 | PAIR | 6 | 6 | 5 | 10 | 5 | 14 | 6 | 15 | 12 | 12 | 12 | 12 | 15 |  |  |
| SCL_DR4 | I2C_DR4-DIFF1 | PAIR | 7 | 6 | 5 | 10 | 5 | 14 | 6 | 15 | 12 | 12 | 12 | 12 | 15 |  |  |
| SCL_DR4 | I2C_DR4-DIFF1 | PAIR | 8 | 6.75 | 5 | 10 | 5 | 14 | 6 | 15 | 12 | 12 | 12 | 12 | 15 |  |  |
| SDA_DR4 | I2C_DR4-DIFF1 | PAIR | 1 | 6.75 | 5 | 10 | 5 | 14 | 6 | 15 | 12 | 12 | 12 | 12 | 15 |  |  |
| SDA_DR4 | I2C_DR4-DIFF1 | PAIR | 2 | 6 | 5 | 10 | 5 | 14 | 6 | 15 | 12 | 12 | 12 | 12 | 15 |  |  |
| SDA_DR4 | I2C_DR4-DIFF1 | PAIR | 3 | 6 | 5 | 10 | 5 | 14 | 6 | 15 | 12 | 12 | 12 | 12 | 15 |  |  |
| SDA_DR4 | I2C_DR4-DIFF1 | PAIR | 4 | 6 | 5 | 10 | 5 | 14 | 6 | 15 | 12 | 12 | 12 | 12 | 15 |  |  |
| SDA_DR4 | I2C_DR4-DIFF1 | PAIR | 5 | 6 | 5 | 10 | 5 | 14 | 6 | 15 | 12 | 12 | 12 | 12 | 15 |  |  |
| SDA_DR4 | I2C_DR4-DIFF1 | PAIR | 6 | 6 | 5 | 10 | 5 | 14 | 6 | 15 | 12 | 12 | 12 | 12 | 15 |  |  |
| SDA_DR4 | I2C_DR4-DIFF1 | PAIR | 7 | 6 | 5 | 10 | 5 | 14 | 6 | 15 | 12 | 12 | 12 | 12 | 15 |  |  |
| SDA_DR4 | I2C_DR4-DIFF1 | PAIR | 8 | 6.75 | 5 | 10 | 5 | 14 | 6 | 15 | 12 | 12 | 12 | 12 | 15 |  |  |
| SCL_DR5_R | I2C_DR5_R-DIFF1 | PAIR | 1 | 6.75 | 5 | 10 | 5 | 14 | 6 | 15 | 12 | 12 | 12 | 12 | 15 |  |  |
| SCL_DR5_R | I2C_DR5_R-DIFF1 | PAIR | 2 | 6 | 5 | 10 | 5 | 14 | 6 | 15 | 12 | 12 | 12 | 12 | 15 |  |  |
| SCL_DR5_R | I2C_DR5_R-DIFF1 | PAIR | 3 | 6 | 5 | 10 | 5 | 14 | 6 | 15 | 12 | 12 | 12 | 12 | 15 |  |  |
| SCL_DR5_R | I2C_DR5_R-DIFF1 | PAIR | 4 | 6 | 5 | 10 | 5 | 14 | 6 | 15 | 12 | 12 | 12 | 12 | 15 |  |  |
| SCL_DR5_R | I2C_DR5_R-DIFF1 | PAIR | 5 | 6 | 5 | 10 | 5 | 14 | 6 | 15 | 12 | 12 | 12 | 12 | 15 |  |  |
| SCL_DR5_R | I2C_DR5_R-DIFF1 | PAIR | 6 | 6 | 5 | 10 | 5 | 14 | 6 | 15 | 12 | 12 | 12 | 12 | 15 |  |  |
| SCL_DR5_R | I2C_DR5_R-DIFF1 | PAIR | 7 | 6 | 5 | 10 | 5 | 14 | 6 | 15 | 12 | 12 | 12 | 12 | 15 |  |  |
| SCL_DR5_R | I2C_DR5_R-DIFF1 | PAIR | 8 | 6.75 | 5 | 10 | 5 | 14 | 6 | 15 | 12 | 12 | 12 | 12 | 15 |  |  |
| SDA_DR5_R | I2C_DR5_R-DIFF1 | PAIR | 1 | 6.75 | 5 | 10 | 5 | 14 | 6 | 15 | 12 | 12 | 12 | 12 | 15 |  |  |
| SDA_DR5_R | I2C_DR5_R-DIFF1 | PAIR | 2 | 6 | 5 | 10 | 5 | 14 | 6 | 15 | 12 | 12 | 12 | 12 | 15 |  |  |
| SDA_DR5_R | I2C_DR5_R-DIFF1 | PAIR | 3 | 6 | 5 | 10 | 5 | 14 | 6 | 15 | 12 | 12 | 12 | 12 | 15 |  |  |
| SDA_DR5_R | I2C_DR5_R-DIFF1 | PAIR | 4 | 6 | 5 | 10 | 5 | 14 | 6 | 15 | 12 | 12 | 12 | 12 | 15 |  |  |
| SDA_DR5_R | I2C_DR5_R-DIFF1 | PAIR | 5 | 6 | 5 | 10 | 5 | 14 | 6 | 15 | 12 | 12 | 12 | 12 | 15 |  |  |
| SDA_DR5_R | I2C_DR5_R-DIFF1 | PAIR | 6 | 6 | 5 | 10 | 5 | 14 | 6 | 15 | 12 | 12 | 12 | 12 | 15 |  |  |
| SDA_DR5_R | I2C_DR5_R-DIFF1 | PAIR | 7 | 6 | 5 | 10 | 5 | 14 | 6 | 15 | 12 | 12 | 12 | 12 | 15 |  |  |
| SDA_DR5_R | I2C_DR5_R-DIFF1 | PAIR | 8 | 6.75 | 5 | 10 | 5 | 14 | 6 | 15 | 12 | 12 | 12 | 12 | 15 |  |  |
| SCL_DR5 | I2C_DR5-DIFF1 | PAIR | 1 | 6.75 | 5 | 10 | 5 | 14 | 6 | 15 | 12 | 12 | 12 | 12 | 15 |  |  |
| SCL_DR5 | I2C_DR5-DIFF1 | PAIR | 2 | 6 | 5 | 10 | 5 | 14 | 6 | 15 | 12 | 12 | 12 | 12 | 15 |  |  |
| SCL_DR5 | I2C_DR5-DIFF1 | PAIR | 3 | 6 | 5 | 10 | 5 | 14 | 6 | 15 | 12 | 12 | 12 | 12 | 15 |  |  |
| SCL_DR5 | I2C_DR5-DIFF1 | PAIR | 4 | 6 | 5 | 10 | 5 | 14 | 6 | 15 | 12 | 12 | 12 | 12 | 15 |  |  |
| SCL_DR5 | I2C_DR5-DIFF1 | PAIR | 5 | 6 | 5 | 10 | 5 | 14 | 6 | 15 | 12 | 12 | 12 | 12 | 15 |  |  |
| SCL_DR5 | I2C_DR5-DIFF1 | PAIR | 6 | 6 | 5 | 10 | 5 | 14 | 6 | 15 | 12 | 12 | 12 | 12 | 15 |  |  |
| SCL_DR5 | I2C_DR5-DIFF1 | PAIR | 7 | 6 | 5 | 10 | 5 | 14 | 6 | 15 | 12 | 12 | 12 | 12 | 15 |  |  |
| SCL_DR5 | I2C_DR5-DIFF1 | PAIR | 8 | 6.75 | 5 | 10 | 5 | 14 | 6 | 15 | 12 | 12 | 12 | 12 | 15 |  |  |
| SDA_DR5 | I2C_DR5-DIFF1 | PAIR | 1 | 6.75 | 5 | 10 | 5 | 14 | 6 | 15 | 12 | 12 | 12 | 12 | 15 |  |  |
| SDA_DR5 | I2C_DR5-DIFF1 | PAIR | 2 | 6 | 5 | 10 | 5 | 14 | 6 | 15 | 12 | 12 | 12 | 12 | 15 |  |  |
| SDA_DR5 | I2C_DR5-DIFF1 | PAIR | 3 | 6 | 5 | 10 | 5 | 14 | 6 | 15 | 12 | 12 | 12 | 12 | 15 |  |  |
| SDA_DR5 | I2C_DR5-DIFF1 | PAIR | 4 | 6 | 5 | 10 | 5 | 14 | 6 | 15 | 12 | 12 | 12 | 12 | 15 |  |  |
| SDA_DR5 | I2C_DR5-DIFF1 | PAIR | 5 | 6 | 5 | 10 | 5 | 14 | 6 | 15 | 12 | 12 | 12 | 12 | 15 |  |  |
| SDA_DR5 | I2C_DR5-DIFF1 | PAIR | 6 | 6 | 5 | 10 | 5 | 14 | 6 | 15 | 12 | 12 | 12 | 12 | 15 |  |  |
| SDA_DR5 | I2C_DR5-DIFF1 | PAIR | 7 | 6 | 5 | 10 | 5 | 14 | 6 | 15 | 12 | 12 | 12 | 12 | 15 |  |  |
| SDA_DR5 | I2C_DR5-DIFF1 | PAIR | 8 | 6.75 | 5 | 10 | 5 | 14 | 6 | 15 | 12 | 12 | 12 | 12 | 15 |  |  |
| SCL_DR6_R | I2C_DR6_R-DIFF1 | PAIR | 1 | 6.75 | 5 | 10 | 5 | 14 | 6 | 15 | 12 | 12 | 12 | 12 | 15 |  |  |
| SCL_DR6_R | I2C_DR6_R-DIFF1 | PAIR | 2 | 6 | 5 | 10 | 5 | 14 | 6 | 15 | 12 | 12 | 12 | 12 | 15 |  |  |
| SCL_DR6_R | I2C_DR6_R-DIFF1 | PAIR | 3 | 6 | 5 | 10 | 5 | 14 | 6 | 15 | 12 | 12 | 12 | 12 | 15 |  |  |
| SCL_DR6_R | I2C_DR6_R-DIFF1 | PAIR | 4 | 6 | 5 | 10 | 5 | 14 | 6 | 15 | 12 | 12 | 12 | 12 | 15 |  |  |
| SCL_DR6_R | I2C_DR6_R-DIFF1 | PAIR | 5 | 6 | 5 | 10 | 5 | 14 | 6 | 15 | 12 | 12 | 12 | 12 | 15 |  |  |
| SCL_DR6_R | I2C_DR6_R-DIFF1 | PAIR | 6 | 6 | 5 | 10 | 5 | 14 | 6 | 15 | 12 | 12 | 12 | 12 | 15 |  |  |
| SCL_DR6_R | I2C_DR6_R-DIFF1 | PAIR | 7 | 6 | 5 | 10 | 5 | 14 | 6 | 15 | 12 | 12 | 12 | 12 | 15 |  |  |
| SCL_DR6_R | I2C_DR6_R-DIFF1 | PAIR | 8 | 6.75 | 5 | 10 | 5 | 14 | 6 | 15 | 12 | 12 | 12 | 12 | 15 |  |  |
| SDA_DR6_R | I2C_DR6_R-DIFF1 | PAIR | 1 | 6.75 | 5 | 10 | 5 | 14 | 6 | 15 | 12 | 12 | 12 | 12 | 15 |  |  |
| SDA_DR6_R | I2C_DR6_R-DIFF1 | PAIR | 2 | 6 | 5 | 10 | 5 | 14 | 6 | 15 | 12 | 12 | 12 | 12 | 15 |  |  |
| SDA_DR6_R | I2C_DR6_R-DIFF1 | PAIR | 3 | 6 | 5 | 10 | 5 | 14 | 6 | 15 | 12 | 12 | 12 | 12 | 15 |  |  |
| SDA_DR6_R | I2C_DR6_R-DIFF1 | PAIR | 4 | 6 | 5 | 10 | 5 | 14 | 6 | 15 | 12 | 12 | 12 | 12 | 15 |  |  |
| SDA_DR6_R | I2C_DR6_R-DIFF1 | PAIR | 5 | 6 | 5 | 10 | 5 | 14 | 6 | 15 | 12 | 12 | 12 | 12 | 15 |  |  |
| SDA_DR6_R | I2C_DR6_R-DIFF1 | PAIR | 6 | 6 | 5 | 10 | 5 | 14 | 6 | 15 | 12 | 12 | 12 | 12 | 15 |  |  |
| SDA_DR6_R | I2C_DR6_R-DIFF1 | PAIR | 7 | 6 | 5 | 10 | 5 | 14 | 6 | 15 | 12 | 12 | 12 | 12 | 15 |  |  |
| SDA_DR6_R | I2C_DR6_R-DIFF1 | PAIR | 8 | 6.75 | 5 | 10 | 5 | 14 | 6 | 15 | 12 | 12 | 12 | 12 | 15 |  |  |
| SCL_DR6 | I2C_DR6-DIFF1 | PAIR | 1 | 6.75 | 5 | 10 | 5 | 14 | 6 | 15 | 12 | 12 | 12 | 12 | 15 |  |  |
| SCL_DR6 | I2C_DR6-DIFF1 | PAIR | 2 | 6 | 5 | 10 | 5 | 14 | 6 | 15 | 12 | 12 | 12 | 12 | 15 |  |  |
| SCL_DR6 | I2C_DR6-DIFF1 | PAIR | 3 | 6 | 5 | 10 | 5 | 14 | 6 | 15 | 12 | 12 | 12 | 12 | 15 |  |  |
| SCL_DR6 | I2C_DR6-DIFF1 | PAIR | 4 | 6 | 5 | 10 | 5 | 14 | 6 | 15 | 12 | 12 | 12 | 12 | 15 |  |  |
| SCL_DR6 | I2C_DR6-DIFF1 | PAIR | 5 | 6 | 5 | 10 | 5 | 14 | 6 | 15 | 12 | 12 | 12 | 12 | 15 |  |  |
| SCL_DR6 | I2C_DR6-DIFF1 | PAIR | 6 | 6 | 5 | 10 | 5 | 14 | 6 | 15 | 12 | 12 | 12 | 12 | 15 |  |  |
| SCL_DR6 | I2C_DR6-DIFF1 | PAIR | 7 | 6 | 5 | 10 | 5 | 14 | 6 | 15 | 12 | 12 | 12 | 12 | 15 |  |  |
| SCL_DR6 | I2C_DR6-DIFF1 | PAIR | 8 | 6.75 | 5 | 10 | 5 | 14 | 6 | 15 | 12 | 12 | 12 | 12 | 15 |  |  |
| SDA_DR6 | I2C_DR6-DIFF1 | PAIR | 1 | 6.75 | 5 | 10 | 5 | 14 | 6 | 15 | 12 | 12 | 12 | 12 | 15 |  |  |
| SDA_DR6 | I2C_DR6-DIFF1 | PAIR | 2 | 6 | 5 | 10 | 5 | 14 | 6 | 15 | 12 | 12 | 12 | 12 | 15 |  |  |
| SDA_DR6 | I2C_DR6-DIFF1 | PAIR | 3 | 6 | 5 | 10 | 5 | 14 | 6 | 15 | 12 | 12 | 12 | 12 | 15 |  |  |
| SDA_DR6 | I2C_DR6-DIFF1 | PAIR | 4 | 6 | 5 | 10 | 5 | 14 | 6 | 15 | 12 | 12 | 12 | 12 | 15 |  |  |
| SDA_DR6 | I2C_DR6-DIFF1 | PAIR | 5 | 6 | 5 | 10 | 5 | 14 | 6 | 15 | 12 | 12 | 12 | 12 | 15 |  |  |
| SDA_DR6 | I2C_DR6-DIFF1 | PAIR | 6 | 6 | 5 | 10 | 5 | 14 | 6 | 15 | 12 | 12 | 12 | 12 | 15 |  |  |
| SDA_DR6 | I2C_DR6-DIFF1 | PAIR | 7 | 6 | 5 | 10 | 5 | 14 | 6 | 15 | 12 | 12 | 12 | 12 | 15 |  |  |
| SDA_DR6 | I2C_DR6-DIFF1 | PAIR | 8 | 6.75 | 5 | 10 | 5 | 14 | 6 | 15 | 12 | 12 | 12 | 12 | 15 |  |  |
| SCL_DR7_R | I2C_DR7_R-DIFF1 | PAIR | 1 | 6.75 | 5 | 10 | 5 | 14 | 6 | 15 | 12 | 12 | 12 | 12 | 15 |  |  |
| SCL_DR7_R | I2C_DR7_R-DIFF1 | PAIR | 2 | 6 | 5 | 10 | 5 | 14 | 6 | 15 | 12 | 12 | 12 | 12 | 15 |  |  |
| SCL_DR7_R | I2C_DR7_R-DIFF1 | PAIR | 3 | 6 | 5 | 10 | 5 | 14 | 6 | 15 | 12 | 12 | 12 | 12 | 15 |  |  |
| SCL_DR7_R | I2C_DR7_R-DIFF1 | PAIR | 4 | 6 | 5 | 10 | 5 | 14 | 6 | 15 | 12 | 12 | 12 | 12 | 15 |  |  |
| SCL_DR7_R | I2C_DR7_R-DIFF1 | PAIR | 5 | 6 | 5 | 10 | 5 | 14 | 6 | 15 | 12 | 12 | 12 | 12 | 15 |  |  |
| SCL_DR7_R | I2C_DR7_R-DIFF1 | PAIR | 6 | 6 | 5 | 10 | 5 | 14 | 6 | 15 | 12 | 12 | 12 | 12 | 15 |  |  |
| SCL_DR7_R | I2C_DR7_R-DIFF1 | PAIR | 7 | 6 | 5 | 10 | 5 | 14 | 6 | 15 | 12 | 12 | 12 | 12 | 15 |  |  |
| SCL_DR7_R | I2C_DR7_R-DIFF1 | PAIR | 8 | 6.75 | 5 | 10 | 5 | 14 | 6 | 15 | 12 | 12 | 12 | 12 | 15 |  |  |
| SDA_DR7_R | I2C_DR7_R-DIFF1 | PAIR | 1 | 6.75 | 5 | 10 | 5 | 14 | 6 | 15 | 12 | 12 | 12 | 12 | 15 |  |  |
| SDA_DR7_R | I2C_DR7_R-DIFF1 | PAIR | 2 | 6 | 5 | 10 | 5 | 14 | 6 | 15 | 12 | 12 | 12 | 12 | 15 |  |  |
| SDA_DR7_R | I2C_DR7_R-DIFF1 | PAIR | 3 | 6 | 5 | 10 | 5 | 14 | 6 | 15 | 12 | 12 | 12 | 12 | 15 |  |  |
| SDA_DR7_R | I2C_DR7_R-DIFF1 | PAIR | 4 | 6 | 5 | 10 | 5 | 14 | 6 | 15 | 12 | 12 | 12 | 12 | 15 |  |  |
| SDA_DR7_R | I2C_DR7_R-DIFF1 | PAIR | 5 | 6 | 5 | 10 | 5 | 14 | 6 | 15 | 12 | 12 | 12 | 12 | 15 |  |  |
| SDA_DR7_R | I2C_DR7_R-DIFF1 | PAIR | 6 | 6 | 5 | 10 | 5 | 14 | 6 | 15 | 12 | 12 | 12 | 12 | 15 |  |  |
| SDA_DR7_R | I2C_DR7_R-DIFF1 | PAIR | 7 | 6 | 5 | 10 | 5 | 14 | 6 | 15 | 12 | 12 | 12 | 12 | 15 |  |  |
| SDA_DR7_R | I2C_DR7_R-DIFF1 | PAIR | 8 | 6.75 | 5 | 10 | 5 | 14 | 6 | 15 | 12 | 12 | 12 | 12 | 15 |  |  |
| SCL_DR7 | I2C_DR7-DIFF1 | PAIR | 1 | 6.75 | 5 | 10 | 5 | 14 | 6 | 15 | 12 | 12 | 12 | 12 | 15 |  |  |
| SCL_DR7 | I2C_DR7-DIFF1 | PAIR | 2 | 6 | 5 | 10 | 5 | 14 | 6 | 15 | 12 | 12 | 12 | 12 | 15 |  |  |
| SCL_DR7 | I2C_DR7-DIFF1 | PAIR | 3 | 6 | 5 | 10 | 5 | 14 | 6 | 15 | 12 | 12 | 12 | 12 | 15 |  |  |
| SCL_DR7 | I2C_DR7-DIFF1 | PAIR | 4 | 6 | 5 | 10 | 5 | 14 | 6 | 15 | 12 | 12 | 12 | 12 | 15 |  |  |
| SCL_DR7 | I2C_DR7-DIFF1 | PAIR | 5 | 6 | 5 | 10 | 5 | 14 | 6 | 15 | 12 | 12 | 12 | 12 | 15 |  |  |
| SCL_DR7 | I2C_DR7-DIFF1 | PAIR | 6 | 6 | 5 | 10 | 5 | 14 | 6 | 15 | 12 | 12 | 12 | 12 | 15 |  |  |
| SCL_DR7 | I2C_DR7-DIFF1 | PAIR | 7 | 6 | 5 | 10 | 5 | 14 | 6 | 15 | 12 | 12 | 12 | 12 | 15 |  |  |
| SCL_DR7 | I2C_DR7-DIFF1 | PAIR | 8 | 6.75 | 5 | 10 | 5 | 14 | 6 | 15 | 12 | 12 | 12 | 12 | 15 |  |  |
| SDA_DR7 | I2C_DR7-DIFF1 | PAIR | 1 | 6.75 | 5 | 10 | 5 | 14 | 6 | 15 | 12 | 12 | 12 | 12 | 15 |  |  |
| SDA_DR7 | I2C_DR7-DIFF1 | PAIR | 2 | 6 | 5 | 10 | 5 | 14 | 6 | 15 | 12 | 12 | 12 | 12 | 15 |  |  |
| SDA_DR7 | I2C_DR7-DIFF1 | PAIR | 3 | 6 | 5 | 10 | 5 | 14 | 6 | 15 | 12 | 12 | 12 | 12 | 15 |  |  |
| SDA_DR7 | I2C_DR7-DIFF1 | PAIR | 4 | 6 | 5 | 10 | 5 | 14 | 6 | 15 | 12 | 12 | 12 | 12 | 15 |  |  |
| SDA_DR7 | I2C_DR7-DIFF1 | PAIR | 5 | 6 | 5 | 10 | 5 | 14 | 6 | 15 | 12 | 12 | 12 | 12 | 15 |  |  |
| SDA_DR7 | I2C_DR7-DIFF1 | PAIR | 6 | 6 | 5 | 10 | 5 | 14 | 6 | 15 | 12 | 12 | 12 | 12 | 15 |  |  |
| SDA_DR7 | I2C_DR7-DIFF1 | PAIR | 7 | 6 | 5 | 10 | 5 | 14 | 6 | 15 | 12 | 12 | 12 | 12 | 15 |  |  |
| SDA_DR7 | I2C_DR7-DIFF1 | PAIR | 8 | 6.75 | 5 | 10 | 5 | 14 | 6 | 15 | 12 | 12 | 12 | 12 | 15 |  |  |
| SCL_DR8_R | I2C_DR8_R-DIFF1 | PAIR | 1 | 6.75 | 5 | 10 | 5 | 14 | 6 | 15 | 12 | 12 | 12 | 12 | 15 |  |  |
| SCL_DR8_R | I2C_DR8_R-DIFF1 | PAIR | 2 | 6 | 5 | 10 | 5 | 14 | 6 | 15 | 12 | 12 | 12 | 12 | 15 |  |  |
| SCL_DR8_R | I2C_DR8_R-DIFF1 | PAIR | 3 | 6 | 5 | 10 | 5 | 14 | 6 | 15 | 12 | 12 | 12 | 12 | 15 |  |  |
| SCL_DR8_R | I2C_DR8_R-DIFF1 | PAIR | 4 | 6 | 5 | 10 | 5 | 14 | 6 | 15 | 12 | 12 | 12 | 12 | 15 |  |  |
| SCL_DR8_R | I2C_DR8_R-DIFF1 | PAIR | 5 | 6 | 5 | 10 | 5 | 14 | 6 | 15 | 12 | 12 | 12 | 12 | 15 |  |  |
| SCL_DR8_R | I2C_DR8_R-DIFF1 | PAIR | 6 | 6 | 5 | 10 | 5 | 14 | 6 | 15 | 12 | 12 | 12 | 12 | 15 |  |  |
| SCL_DR8_R | I2C_DR8_R-DIFF1 | PAIR | 7 | 6 | 5 | 10 | 5 | 14 | 6 | 15 | 12 | 12 | 12 | 12 | 15 |  |  |
| SCL_DR8_R | I2C_DR8_R-DIFF1 | PAIR | 8 | 6.75 | 5 | 10 | 5 | 14 | 6 | 15 | 12 | 12 | 12 | 12 | 15 |  |  |
| SDA_DR8_R | I2C_DR8_R-DIFF1 | PAIR | 1 | 6.75 | 5 | 10 | 5 | 14 | 6 | 15 | 12 | 12 | 12 | 12 | 15 |  |  |
| SDA_DR8_R | I2C_DR8_R-DIFF1 | PAIR | 2 | 6 | 5 | 10 | 5 | 14 | 6 | 15 | 12 | 12 | 12 | 12 | 15 |  |  |
| SDA_DR8_R | I2C_DR8_R-DIFF1 | PAIR | 3 | 6 | 5 | 10 | 5 | 14 | 6 | 15 | 12 | 12 | 12 | 12 | 15 |  |  |
| SDA_DR8_R | I2C_DR8_R-DIFF1 | PAIR | 4 | 6 | 5 | 10 | 5 | 14 | 6 | 15 | 12 | 12 | 12 | 12 | 15 |  |  |
| SDA_DR8_R | I2C_DR8_R-DIFF1 | PAIR | 5 | 6 | 5 | 10 | 5 | 14 | 6 | 15 | 12 | 12 | 12 | 12 | 15 |  |  |
| SDA_DR8_R | I2C_DR8_R-DIFF1 | PAIR | 6 | 6 | 5 | 10 | 5 | 14 | 6 | 15 | 12 | 12 | 12 | 12 | 15 |  |  |
| SDA_DR8_R | I2C_DR8_R-DIFF1 | PAIR | 7 | 6 | 5 | 10 | 5 | 14 | 6 | 15 | 12 | 12 | 12 | 12 | 15 |  |  |
| SDA_DR8_R | I2C_DR8_R-DIFF1 | PAIR | 8 | 6.75 | 5 | 10 | 5 | 14 | 6 | 15 | 12 | 12 | 12 | 12 | 15 |  |  |
| SCL_DR8 | I2C_DR8-DIFF1 | PAIR | 1 | 6.75 | 5 | 10 | 5 | 14 | 6 | 15 | 12 | 12 | 12 | 12 | 15 |  |  |
| SCL_DR8 | I2C_DR8-DIFF1 | PAIR | 2 | 6 | 5 | 10 | 5 | 14 | 6 | 15 | 12 | 12 | 12 | 12 | 15 |  |  |
| SCL_DR8 | I2C_DR8-DIFF1 | PAIR | 3 | 6 | 5 | 10 | 5 | 14 | 6 | 15 | 12 | 12 | 12 | 12 | 15 |  |  |
| SCL_DR8 | I2C_DR8-DIFF1 | PAIR | 4 | 6 | 5 | 10 | 5 | 14 | 6 | 15 | 12 | 12 | 12 | 12 | 15 |  |  |
| SCL_DR8 | I2C_DR8-DIFF1 | PAIR | 5 | 6 | 5 | 10 | 5 | 14 | 6 | 15 | 12 | 12 | 12 | 12 | 15 |  |  |
| SCL_DR8 | I2C_DR8-DIFF1 | PAIR | 6 | 6 | 5 | 10 | 5 | 14 | 6 | 15 | 12 | 12 | 12 | 12 | 15 |  |  |
| SCL_DR8 | I2C_DR8-DIFF1 | PAIR | 7 | 6 | 5 | 10 | 5 | 14 | 6 | 15 | 12 | 12 | 12 | 12 | 15 |  |  |
| SCL_DR8 | I2C_DR8-DIFF1 | PAIR | 8 | 6.75 | 5 | 10 | 5 | 14 | 6 | 15 | 12 | 12 | 12 | 12 | 15 |  |  |
| SDA_DR8 | I2C_DR8-DIFF1 | PAIR | 1 | 6.75 | 5 | 10 | 5 | 14 | 6 | 15 | 12 | 12 | 12 | 12 | 15 |  |  |
| SDA_DR8 | I2C_DR8-DIFF1 | PAIR | 2 | 6 | 5 | 10 | 5 | 14 | 6 | 15 | 12 | 12 | 12 | 12 | 15 |  |  |
| SDA_DR8 | I2C_DR8-DIFF1 | PAIR | 3 | 6 | 5 | 10 | 5 | 14 | 6 | 15 | 12 | 12 | 12 | 12 | 15 |  |  |
| SDA_DR8 | I2C_DR8-DIFF1 | PAIR | 4 | 6 | 5 | 10 | 5 | 14 | 6 | 15 | 12 | 12 | 12 | 12 | 15 |  |  |
| SDA_DR8 | I2C_DR8-DIFF1 | PAIR | 5 | 6 | 5 | 10 | 5 | 14 | 6 | 15 | 12 | 12 | 12 | 12 | 15 |  |  |
| SDA_DR8 | I2C_DR8-DIFF1 | PAIR | 6 | 6 | 5 | 10 | 5 | 14 | 6 | 15 | 12 | 12 | 12 | 12 | 15 |  |  |
| SDA_DR8 | I2C_DR8-DIFF1 | PAIR | 7 | 6 | 5 | 10 | 5 | 14 | 6 | 15 | 12 | 12 | 12 | 12 | 15 |  |  |
| SDA_DR8 | I2C_DR8-DIFF1 | PAIR | 8 | 6.75 | 5 | 10 | 5 | 14 | 6 | 15 | 12 | 12 | 12 | 12 | 15 |  |  |
| SCL_DR9_R | I2C_DR9_R-DIFF1 | PAIR | 1 | 6.75 | 5 | 10 | 5 | 14 | 6 | 15 | 12 | 12 | 12 | 12 | 15 |  |  |
| SCL_DR9_R | I2C_DR9_R-DIFF1 | PAIR | 2 | 6 | 5 | 10 | 5 | 14 | 6 | 15 | 12 | 12 | 12 | 12 | 15 |  |  |
| SCL_DR9_R | I2C_DR9_R-DIFF1 | PAIR | 3 | 6 | 5 | 10 | 5 | 14 | 6 | 15 | 12 | 12 | 12 | 12 | 15 |  |  |
| SCL_DR9_R | I2C_DR9_R-DIFF1 | PAIR | 4 | 6 | 5 | 10 | 5 | 14 | 6 | 15 | 12 | 12 | 12 | 12 | 15 |  |  |
| SCL_DR9_R | I2C_DR9_R-DIFF1 | PAIR | 5 | 6 | 5 | 10 | 5 | 14 | 6 | 15 | 12 | 12 | 12 | 12 | 15 |  |  |
| SCL_DR9_R | I2C_DR9_R-DIFF1 | PAIR | 6 | 6 | 5 | 10 | 5 | 14 | 6 | 15 | 12 | 12 | 12 | 12 | 15 |  |  |
| SCL_DR9_R | I2C_DR9_R-DIFF1 | PAIR | 7 | 6 | 5 | 10 | 5 | 14 | 6 | 15 | 12 | 12 | 12 | 12 | 15 |  |  |
| SCL_DR9_R | I2C_DR9_R-DIFF1 | PAIR | 8 | 6.75 | 5 | 10 | 5 | 14 | 6 | 15 | 12 | 12 | 12 | 12 | 15 |  |  |
| SDA_DR9_R | I2C_DR9_R-DIFF1 | PAIR | 1 | 6.75 | 5 | 10 | 5 | 14 | 6 | 15 | 12 | 12 | 12 | 12 | 15 |  |  |
| SDA_DR9_R | I2C_DR9_R-DIFF1 | PAIR | 2 | 6 | 5 | 10 | 5 | 14 | 6 | 15 | 12 | 12 | 12 | 12 | 15 |  |  |
| SDA_DR9_R | I2C_DR9_R-DIFF1 | PAIR | 3 | 6 | 5 | 10 | 5 | 14 | 6 | 15 | 12 | 12 | 12 | 12 | 15 |  |  |
| SDA_DR9_R | I2C_DR9_R-DIFF1 | PAIR | 4 | 6 | 5 | 10 | 5 | 14 | 6 | 15 | 12 | 12 | 12 | 12 | 15 |  |  |
| SDA_DR9_R | I2C_DR9_R-DIFF1 | PAIR | 5 | 6 | 5 | 10 | 5 | 14 | 6 | 15 | 12 | 12 | 12 | 12 | 15 |  |  |
| SDA_DR9_R | I2C_DR9_R-DIFF1 | PAIR | 6 | 6 | 5 | 10 | 5 | 14 | 6 | 15 | 12 | 12 | 12 | 12 | 15 |  |  |
| SDA_DR9_R | I2C_DR9_R-DIFF1 | PAIR | 7 | 6 | 5 | 10 | 5 | 14 | 6 | 15 | 12 | 12 | 12 | 12 | 15 |  |  |
| SDA_DR9_R | I2C_DR9_R-DIFF1 | PAIR | 8 | 6.75 | 5 | 10 | 5 | 14 | 6 | 15 | 12 | 12 | 12 | 12 | 15 |  |  |
| SCL_DR9 | I2C_DR9-DIFF1 | PAIR | 1 | 6.75 | 5 | 10 | 5 | 14 | 6 | 15 | 12 | 12 | 12 | 12 | 15 |  |  |
| SCL_DR9 | I2C_DR9-DIFF1 | PAIR | 2 | 6 | 5 | 10 | 5 | 14 | 6 | 15 | 12 | 12 | 12 | 12 | 15 |  |  |
| SCL_DR9 | I2C_DR9-DIFF1 | PAIR | 3 | 6 | 5 | 10 | 5 | 14 | 6 | 15 | 12 | 12 | 12 | 12 | 15 |  |  |
| SCL_DR9 | I2C_DR9-DIFF1 | PAIR | 4 | 6 | 5 | 10 | 5 | 14 | 6 | 15 | 12 | 12 | 12 | 12 | 15 |  |  |
| SCL_DR9 | I2C_DR9-DIFF1 | PAIR | 5 | 6 | 5 | 10 | 5 | 14 | 6 | 15 | 12 | 12 | 12 | 12 | 15 |  |  |
| SCL_DR9 | I2C_DR9-DIFF1 | PAIR | 6 | 6 | 5 | 10 | 5 | 14 | 6 | 15 | 12 | 12 | 12 | 12 | 15 |  |  |
| SCL_DR9 | I2C_DR9-DIFF1 | PAIR | 7 | 6 | 5 | 10 | 5 | 14 | 6 | 15 | 12 | 12 | 12 | 12 | 15 |  |  |
| SCL_DR9 | I2C_DR9-DIFF1 | PAIR | 8 | 6.75 | 5 | 10 | 5 | 14 | 6 | 15 | 12 | 12 | 12 | 12 | 15 |  |  |
| SDA_DR9 | I2C_DR9-DIFF1 | PAIR | 1 | 6.75 | 5 | 10 | 5 | 14 | 6 | 15 | 12 | 12 | 12 | 12 | 15 |  |  |
| SDA_DR9 | I2C_DR9-DIFF1 | PAIR | 2 | 6 | 5 | 10 | 5 | 14 | 6 | 15 | 12 | 12 | 12 | 12 | 15 |  |  |
| SDA_DR9 | I2C_DR9-DIFF1 | PAIR | 3 | 6 | 5 | 10 | 5 | 14 | 6 | 15 | 12 | 12 | 12 | 12 | 15 |  |  |
| SDA_DR9 | I2C_DR9-DIFF1 | PAIR | 4 | 6 | 5 | 10 | 5 | 14 | 6 | 15 | 12 | 12 | 12 | 12 | 15 |  |  |
| SDA_DR9 | I2C_DR9-DIFF1 | PAIR | 5 | 6 | 5 | 10 | 5 | 14 | 6 | 15 | 12 | 12 | 12 | 12 | 15 |  |  |
| SDA_DR9 | I2C_DR9-DIFF1 | PAIR | 6 | 6 | 5 | 10 | 5 | 14 | 6 | 15 | 12 | 12 | 12 | 12 | 15 |  |  |
| SDA_DR9 | I2C_DR9-DIFF1 | PAIR | 7 | 6 | 5 | 10 | 5 | 14 | 6 | 15 | 12 | 12 | 12 | 12 | 15 |  |  |
| SDA_DR9 | I2C_DR9-DIFF1 | PAIR | 8 | 6.75 | 5 | 10 | 5 | 14 | 6 | 15 | 12 | 12 | 12 | 12 | 15 |  |  |
| TMP1_SCL | I2C_TMP1-DIFF1 | PAIR | 1 | 6.75 | 5 | 10 | 5 | 14 | 6 | 15 | 12 | 12 | 12 | 12 | 15 |  |  |
| TMP1_SCL | I2C_TMP1-DIFF1 | PAIR | 2 | 6 | 5 | 10 | 5 | 14 | 6 | 15 | 12 | 12 | 12 | 12 | 15 |  |  |
| TMP1_SCL | I2C_TMP1-DIFF1 | PAIR | 3 | 6 | 5 | 10 | 5 | 14 | 6 | 15 | 12 | 12 | 12 | 12 | 15 |  |  |
| TMP1_SCL | I2C_TMP1-DIFF1 | PAIR | 4 | 6 | 5 | 10 | 5 | 14 | 6 | 15 | 12 | 12 | 12 | 12 | 15 |  |  |
| TMP1_SCL | I2C_TMP1-DIFF1 | PAIR | 5 | 6 | 5 | 10 | 5 | 14 | 6 | 15 | 12 | 12 | 12 | 12 | 15 |  |  |
| TMP1_SCL | I2C_TMP1-DIFF1 | PAIR | 6 | 6 | 5 | 10 | 5 | 14 | 6 | 15 | 12 | 12 | 12 | 12 | 15 |  |  |
| TMP1_SCL | I2C_TMP1-DIFF1 | PAIR | 7 | 6 | 5 | 10 | 5 | 14 | 6 | 15 | 12 | 12 | 12 | 12 | 15 |  |  |
| TMP1_SCL | I2C_TMP1-DIFF1 | PAIR | 8 | 6.75 | 5 | 10 | 5 | 14 | 6 | 15 | 12 | 12 | 12 | 12 | 15 |  |  |
| TMP1_SDA | I2C_TMP1-DIFF1 | PAIR | 1 | 6.75 | 5 | 10 | 5 | 14 | 6 | 15 | 12 | 12 | 12 | 12 | 15 |  |  |
| TMP1_SDA | I2C_TMP1-DIFF1 | PAIR | 2 | 6 | 5 | 10 | 5 | 14 | 6 | 15 | 12 | 12 | 12 | 12 | 15 |  |  |
| TMP1_SDA | I2C_TMP1-DIFF1 | PAIR | 3 | 6 | 5 | 10 | 5 | 14 | 6 | 15 | 12 | 12 | 12 | 12 | 15 |  |  |
| TMP1_SDA | I2C_TMP1-DIFF1 | PAIR | 4 | 6 | 5 | 10 | 5 | 14 | 6 | 15 | 12 | 12 | 12 | 12 | 15 |  |  |
| TMP1_SDA | I2C_TMP1-DIFF1 | PAIR | 5 | 6 | 5 | 10 | 5 | 14 | 6 | 15 | 12 | 12 | 12 | 12 | 15 |  |  |
| TMP1_SDA | I2C_TMP1-DIFF1 | PAIR | 6 | 6 | 5 | 10 | 5 | 14 | 6 | 15 | 12 | 12 | 12 | 12 | 15 |  |  |
| TMP1_SDA | I2C_TMP1-DIFF1 | PAIR | 7 | 6 | 5 | 10 | 5 | 14 | 6 | 15 | 12 | 12 | 12 | 12 | 15 |  |  |
| TMP1_SDA | I2C_TMP1-DIFF1 | PAIR | 8 | 6.75 | 5 | 10 | 5 | 14 | 6 | 15 | 12 | 12 | 12 | 12 | 15 |  |  |
| TMP2_SCL | I2C_TMP2-DIFF1 | PAIR | 1 | 6.75 | 5 | 10 | 5 | 14 | 6 | 15 | 12 | 12 | 12 | 12 | 15 |  |  |
| TMP2_SCL | I2C_TMP2-DIFF1 | PAIR | 2 | 6 | 5 | 10 | 5 | 14 | 6 | 15 | 12 | 12 | 12 | 12 | 15 |  |  |
| TMP2_SCL | I2C_TMP2-DIFF1 | PAIR | 3 | 6 | 5 | 10 | 5 | 14 | 6 | 15 | 12 | 12 | 12 | 12 | 15 |  |  |
| TMP2_SCL | I2C_TMP2-DIFF1 | PAIR | 4 | 6 | 5 | 10 | 5 | 14 | 6 | 15 | 12 | 12 | 12 | 12 | 15 |  |  |
| TMP2_SCL | I2C_TMP2-DIFF1 | PAIR | 5 | 6 | 5 | 10 | 5 | 14 | 6 | 15 | 12 | 12 | 12 | 12 | 15 |  |  |
| TMP2_SCL | I2C_TMP2-DIFF1 | PAIR | 6 | 6 | 5 | 10 | 5 | 14 | 6 | 15 | 12 | 12 | 12 | 12 | 15 |  |  |
| TMP2_SCL | I2C_TMP2-DIFF1 | PAIR | 7 | 6 | 5 | 10 | 5 | 14 | 6 | 15 | 12 | 12 | 12 | 12 | 15 |  |  |
| TMP2_SCL | I2C_TMP2-DIFF1 | PAIR | 8 | 6.75 | 5 | 10 | 5 | 14 | 6 | 15 | 12 | 12 | 12 | 12 | 15 |  |  |
| TMP2_SDA | I2C_TMP2-DIFF1 | PAIR | 1 | 6.75 | 5 | 10 | 5 | 14 | 6 | 15 | 12 | 12 | 12 | 12 | 15 |  |  |
| TMP2_SDA | I2C_TMP2-DIFF1 | PAIR | 2 | 6 | 5 | 10 | 5 | 14 | 6 | 15 | 12 | 12 | 12 | 12 | 15 |  |  |
| TMP2_SDA | I2C_TMP2-DIFF1 | PAIR | 3 | 6 | 5 | 10 | 5 | 14 | 6 | 15 | 12 | 12 | 12 | 12 | 15 |  |  |
| TMP2_SDA | I2C_TMP2-DIFF1 | PAIR | 4 | 6 | 5 | 10 | 5 | 14 | 6 | 15 | 12 | 12 | 12 | 12 | 15 |  |  |
| TMP2_SDA | I2C_TMP2-DIFF1 | PAIR | 5 | 6 | 5 | 10 | 5 | 14 | 6 | 15 | 12 | 12 | 12 | 12 | 15 |  |  |
| TMP2_SDA | I2C_TMP2-DIFF1 | PAIR | 6 | 6 | 5 | 10 | 5 | 14 | 6 | 15 | 12 | 12 | 12 | 12 | 15 |  |  |
| TMP2_SDA | I2C_TMP2-DIFF1 | PAIR | 7 | 6 | 5 | 10 | 5 | 14 | 6 | 15 | 12 | 12 | 12 | 12 | 15 |  |  |
| TMP2_SDA | I2C_TMP2-DIFF1 | PAIR | 8 | 6.75 | 5 | 10 | 5 | 14 | 6 | 15 | 12 | 12 | 12 | 12 | 15 |  |  |
| TMP3_SCL | I2C_TMP3-DIFF1 | PAIR | 1 | 6.75 | 5 | 10 | 5 | 14 | 6 | 15 | 12 | 12 | 12 | 12 | 15 |  |  |
| TMP3_SCL | I2C_TMP3-DIFF1 | PAIR | 2 | 6 | 5 | 10 | 5 | 14 | 6 | 15 | 12 | 12 | 12 | 12 | 15 |  |  |
| TMP3_SCL | I2C_TMP3-DIFF1 | PAIR | 3 | 6 | 5 | 10 | 5 | 14 | 6 | 15 | 12 | 12 | 12 | 12 | 15 |  |  |
| TMP3_SCL | I2C_TMP3-DIFF1 | PAIR | 4 | 6 | 5 | 10 | 5 | 14 | 6 | 15 | 12 | 12 | 12 | 12 | 15 |  |  |
| TMP3_SCL | I2C_TMP3-DIFF1 | PAIR | 5 | 6 | 5 | 10 | 5 | 14 | 6 | 15 | 12 | 12 | 12 | 12 | 15 |  |  |
| TMP3_SCL | I2C_TMP3-DIFF1 | PAIR | 6 | 6 | 5 | 10 | 5 | 14 | 6 | 15 | 12 | 12 | 12 | 12 | 15 |  |  |
| TMP3_SCL | I2C_TMP3-DIFF1 | PAIR | 7 | 6 | 5 | 10 | 5 | 14 | 6 | 15 | 12 | 12 | 12 | 12 | 15 |  |  |
| TMP3_SCL | I2C_TMP3-DIFF1 | PAIR | 8 | 6.75 | 5 | 10 | 5 | 14 | 6 | 15 | 12 | 12 | 12 | 12 | 15 |  |  |
| TMP3_SDA | I2C_TMP3-DIFF1 | PAIR | 1 | 6.75 | 5 | 10 | 5 | 14 | 6 | 15 | 12 | 12 | 12 | 12 | 15 |  |  |
| TMP3_SDA | I2C_TMP3-DIFF1 | PAIR | 2 | 6 | 5 | 10 | 5 | 14 | 6 | 15 | 12 | 12 | 12 | 12 | 15 |  |  |
| TMP3_SDA | I2C_TMP3-DIFF1 | PAIR | 3 | 6 | 5 | 10 | 5 | 14 | 6 | 15 | 12 | 12 | 12 | 12 | 15 |  |  |
| TMP3_SDA | I2C_TMP3-DIFF1 | PAIR | 4 | 6 | 5 | 10 | 5 | 14 | 6 | 15 | 12 | 12 | 12 | 12 | 15 |  |  |
| TMP3_SDA | I2C_TMP3-DIFF1 | PAIR | 5 | 6 | 5 | 10 | 5 | 14 | 6 | 15 | 12 | 12 | 12 | 12 | 15 |  |  |
| TMP3_SDA | I2C_TMP3-DIFF1 | PAIR | 6 | 6 | 5 | 10 | 5 | 14 | 6 | 15 | 12 | 12 | 12 | 12 | 15 |  |  |
| TMP3_SDA | I2C_TMP3-DIFF1 | PAIR | 7 | 6 | 5 | 10 | 5 | 14 | 6 | 15 | 12 | 12 | 12 | 12 | 15 |  |  |
| TMP3_SDA | I2C_TMP3-DIFF1 | PAIR | 8 | 6.75 | 5 | 10 | 5 | 14 | 6 | 15 | 12 | 12 | 12 | 12 | 15 |  |  |
| TMP4_SCL | I2C_TMP4-DIFF1 | PAIR | 1 | 6.75 | 5 | 10 | 5 | 14 | 6 | 15 | 12 | 12 | 12 | 12 | 15 |  |  |
| TMP4_SCL | I2C_TMP4-DIFF1 | PAIR | 2 | 6 | 5 | 10 | 5 | 14 | 6 | 15 | 12 | 12 | 12 | 12 | 15 |  |  |
| TMP4_SCL | I2C_TMP4-DIFF1 | PAIR | 3 | 6 | 5 | 10 | 5 | 14 | 6 | 15 | 12 | 12 | 12 | 12 | 15 |  |  |
| TMP4_SCL | I2C_TMP4-DIFF1 | PAIR | 4 | 6 | 5 | 10 | 5 | 14 | 6 | 15 | 12 | 12 | 12 | 12 | 15 |  |  |
| TMP4_SCL | I2C_TMP4-DIFF1 | PAIR | 5 | 6 | 5 | 10 | 5 | 14 | 6 | 15 | 12 | 12 | 12 | 12 | 15 |  |  |
| TMP4_SCL | I2C_TMP4-DIFF1 | PAIR | 6 | 6 | 5 | 10 | 5 | 14 | 6 | 15 | 12 | 12 | 12 | 12 | 15 |  |  |
| TMP4_SCL | I2C_TMP4-DIFF1 | PAIR | 7 | 6 | 5 | 10 | 5 | 14 | 6 | 15 | 12 | 12 | 12 | 12 | 15 |  |  |
| TMP4_SCL | I2C_TMP4-DIFF1 | PAIR | 8 | 6.75 | 5 | 10 | 5 | 14 | 6 | 15 | 12 | 12 | 12 | 12 | 15 |  |  |
| TMP4_SDA | I2C_TMP4-DIFF1 | PAIR | 1 | 6.75 | 5 | 10 | 5 | 14 | 6 | 15 | 12 | 12 | 12 | 12 | 15 |  |  |
| TMP4_SDA | I2C_TMP4-DIFF1 | PAIR | 2 | 6 | 5 | 10 | 5 | 14 | 6 | 15 | 12 | 12 | 12 | 12 | 15 |  |  |
| TMP4_SDA | I2C_TMP4-DIFF1 | PAIR | 3 | 6 | 5 | 10 | 5 | 14 | 6 | 15 | 12 | 12 | 12 | 12 | 15 |  |  |
| TMP4_SDA | I2C_TMP4-DIFF1 | PAIR | 4 | 6 | 5 | 10 | 5 | 14 | 6 | 15 | 12 | 12 | 12 | 12 | 15 |  |  |
| TMP4_SDA | I2C_TMP4-DIFF1 | PAIR | 5 | 6 | 5 | 10 | 5 | 14 | 6 | 15 | 12 | 12 | 12 | 12 | 15 |  |  |
| TMP4_SDA | I2C_TMP4-DIFF1 | PAIR | 6 | 6 | 5 | 10 | 5 | 14 | 6 | 15 | 12 | 12 | 12 | 12 | 15 |  |  |
| TMP4_SDA | I2C_TMP4-DIFF1 | PAIR | 7 | 6 | 5 | 10 | 5 | 14 | 6 | 15 | 12 | 12 | 12 | 12 | 15 |  |  |
| TMP4_SDA | I2C_TMP4-DIFF1 | PAIR | 8 | 6.75 | 5 | 10 | 5 | 14 | 6 | 15 | 12 | 12 | 12 | 12 | 15 |  |  |
| PE_100M_CLK1_C_N | PE_100M_CLK1_C-DIFF1 | PAIR | 1 | 6.88 | 5 | 10 | 5 | 12 | 20 | 36 | 12 | 12 | 20 | 12 | 5.13 | 85 Ohms | TOP=L2:L3=L2/L4:L6=L5/L7:BOTTOM=L7 |
| PE_100M_CLK1_C_N | PE_100M_CLK1_C-DIFF1 | PAIR | 2 | 6.5 | 5 | 10 | 5 | 12 | 20 | 25 | 12 | 12 | 20 | 12 | 7.5 | 85 Ohms | TOP=L2:L3=L2/L4:L6=L5/L7:BOTTOM=L7 |
| PE_100M_CLK1_C_N | PE_100M_CLK1_C-DIFF1 | PAIR | 3 | 6.5 | 5 | 10 | 5 | 12 | 20 | 25 | 12 | 12 | 20 | 12 | 7.5 | 85 Ohms | TOP=L2:L3=L2/L4:L6=L5/L7:BOTTOM=L7 |
| PE_100M_CLK1_C_N | PE_100M_CLK1_C-DIFF1 | PAIR | 4 | 6.5 | 5 | 10 | 5 | 12 | 20 | 25 | 12 | 12 | 20 | 12 | 7.5 | 85 Ohms | TOP=L2:L3=L2/L4:L6=L5/L7:BOTTOM=L7 |
| PE_100M_CLK1_C_N | PE_100M_CLK1_C-DIFF1 | PAIR | 5 | 6.5 | 5 | 10 | 5 | 12 | 20 | 25 | 12 | 12 | 20 | 12 | 7.5 | 85 Ohms | TOP=L2:L3=L2/L4:L6=L5/L7:BOTTOM=L7 |
| PE_100M_CLK1_C_N | PE_100M_CLK1_C-DIFF1 | PAIR | 6 | 6.5 | 5 | 10 | 5 | 12 | 20 | 25 | 12 | 12 | 20 | 12 | 7.5 | 85 Ohms | TOP=L2:L3=L2/L4:L6=L5/L7:BOTTOM=L7 |
| PE_100M_CLK1_C_N | PE_100M_CLK1_C-DIFF1 | PAIR | 7 | 6.5 | 5 | 10 | 5 | 12 | 20 | 25 | 12 | 12 | 20 | 12 | 7.5 | 85 Ohms | TOP=L2:L3=L2/L4:L6=L5/L7:BOTTOM=L7 |
| PE_100M_CLK1_C_N | PE_100M_CLK1_C-DIFF1 | PAIR | 8 | 6.88 | 5 | 10 | 5 | 12 | 20 | 36 | 12 | 12 | 20 | 12 | 5.13 | 85 Ohms | TOP=L2:L3=L2/L4:L6=L5/L7:BOTTOM=L7 |
| PE_100M_CLK1_C_P | PE_100M_CLK1_C-DIFF1 | PAIR | 1 | 6.88 | 5 | 10 | 5 | 12 | 20 | 36 | 12 | 12 | 20 | 12 | 5.13 | 85 Ohms | TOP=L2:L3=L2/L4:L6=L5/L7:BOTTOM=L7 |
| PE_100M_CLK1_C_P | PE_100M_CLK1_C-DIFF1 | PAIR | 2 | 6.5 | 5 | 10 | 5 | 12 | 20 | 25 | 12 | 12 | 20 | 12 | 7.5 | 85 Ohms | TOP=L2:L3=L2/L4:L6=L5/L7:BOTTOM=L7 |
| PE_100M_CLK1_C_P | PE_100M_CLK1_C-DIFF1 | PAIR | 3 | 6.5 | 5 | 10 | 5 | 12 | 20 | 25 | 12 | 12 | 20 | 12 | 7.5 | 85 Ohms | TOP=L2:L3=L2/L4:L6=L5/L7:BOTTOM=L7 |
| PE_100M_CLK1_C_P | PE_100M_CLK1_C-DIFF1 | PAIR | 4 | 6.5 | 5 | 10 | 5 | 12 | 20 | 25 | 12 | 12 | 20 | 12 | 7.5 | 85 Ohms | TOP=L2:L3=L2/L4:L6=L5/L7:BOTTOM=L7 |
| PE_100M_CLK1_C_P | PE_100M_CLK1_C-DIFF1 | PAIR | 5 | 6.5 | 5 | 10 | 5 | 12 | 20 | 25 | 12 | 12 | 20 | 12 | 7.5 | 85 Ohms | TOP=L2:L3=L2/L4:L6=L5/L7:BOTTOM=L7 |
| PE_100M_CLK1_C_P | PE_100M_CLK1_C-DIFF1 | PAIR | 6 | 6.5 | 5 | 10 | 5 | 12 | 20 | 25 | 12 | 12 | 20 | 12 | 7.5 | 85 Ohms | TOP=L2:L3=L2/L4:L6=L5/L7:BOTTOM=L7 |
| PE_100M_CLK1_C_P | PE_100M_CLK1_C-DIFF1 | PAIR | 7 | 6.5 | 5 | 10 | 5 | 12 | 20 | 25 | 12 | 12 | 20 | 12 | 7.5 | 85 Ohms | TOP=L2:L3=L2/L4:L6=L5/L7:BOTTOM=L7 |
| PE_100M_CLK1_C_P | PE_100M_CLK1_C-DIFF1 | PAIR | 8 | 6.88 | 5 | 10 | 5 | 12 | 20 | 36 | 12 | 12 | 20 | 12 | 5.13 | 85 Ohms | TOP=L2:L3=L2/L4:L6=L5/L7:BOTTOM=L7 |
| PE_100M_CLK1_N | PE_100M_CLK1-DIFF1 | PAIR | 1 | 6.88 | 5 | 10 | 5 | 12 | 20 | 36 | 12 | 12 | 20 | 12 | 5.13 | 85 Ohms | TOP=L2:L3=L2/L4:L6=L5/L7:BOTTOM=L7 |
| PE_100M_CLK1_N | PE_100M_CLK1-DIFF1 | PAIR | 2 | 6.5 | 5 | 10 | 5 | 12 | 20 | 25 | 12 | 12 | 20 | 12 | 7.5 | 85 Ohms | TOP=L2:L3=L2/L4:L6=L5/L7:BOTTOM=L7 |
| PE_100M_CLK1_N | PE_100M_CLK1-DIFF1 | PAIR | 3 | 6.5 | 5 | 10 | 5 | 12 | 20 | 25 | 12 | 12 | 20 | 12 | 7.5 | 85 Ohms | TOP=L2:L3=L2/L4:L6=L5/L7:BOTTOM=L7 |
| PE_100M_CLK1_N | PE_100M_CLK1-DIFF1 | PAIR | 4 | 6.5 | 5 | 10 | 5 | 12 | 20 | 25 | 12 | 12 | 20 | 12 | 7.5 | 85 Ohms | TOP=L2:L3=L2/L4:L6=L5/L7:BOTTOM=L7 |
| PE_100M_CLK1_N | PE_100M_CLK1-DIFF1 | PAIR | 5 | 6.5 | 5 | 10 | 5 | 12 | 20 | 25 | 12 | 12 | 20 | 12 | 7.5 | 85 Ohms | TOP=L2:L3=L2/L4:L6=L5/L7:BOTTOM=L7 |
| PE_100M_CLK1_N | PE_100M_CLK1-DIFF1 | PAIR | 6 | 6.5 | 5 | 10 | 5 | 12 | 20 | 25 | 12 | 12 | 20 | 12 | 7.5 | 85 Ohms | TOP=L2:L3=L2/L4:L6=L5/L7:BOTTOM=L7 |
| PE_100M_CLK1_N | PE_100M_CLK1-DIFF1 | PAIR | 7 | 6.5 | 5 | 10 | 5 | 12 | 20 | 25 | 12 | 12 | 20 | 12 | 7.5 | 85 Ohms | TOP=L2:L3=L2/L4:L6=L5/L7:BOTTOM=L7 |
| PE_100M_CLK1_N | PE_100M_CLK1-DIFF1 | PAIR | 8 | 6.88 | 5 | 10 | 5 | 12 | 20 | 36 | 12 | 12 | 20 | 12 | 5.13 | 85 Ohms | TOP=L2:L3=L2/L4:L6=L5/L7:BOTTOM=L7 |
| PE_100M_CLK1_P | PE_100M_CLK1-DIFF1 | PAIR | 1 | 6.88 | 5 | 10 | 5 | 12 | 20 | 36 | 12 | 12 | 20 | 12 | 5.13 | 85 Ohms | TOP=L2:L3=L2/L4:L6=L5/L7:BOTTOM=L7 |
| PE_100M_CLK1_P | PE_100M_CLK1-DIFF1 | PAIR | 2 | 6.5 | 5 | 10 | 5 | 12 | 20 | 25 | 12 | 12 | 20 | 12 | 7.5 | 85 Ohms | TOP=L2:L3=L2/L4:L6=L5/L7:BOTTOM=L7 |
| PE_100M_CLK1_P | PE_100M_CLK1-DIFF1 | PAIR | 3 | 6.5 | 5 | 10 | 5 | 12 | 20 | 25 | 12 | 12 | 20 | 12 | 7.5 | 85 Ohms | TOP=L2:L3=L2/L4:L6=L5/L7:BOTTOM=L7 |
| PE_100M_CLK1_P | PE_100M_CLK1-DIFF1 | PAIR | 4 | 6.5 | 5 | 10 | 5 | 12 | 20 | 25 | 12 | 12 | 20 | 12 | 7.5 | 85 Ohms | TOP=L2:L3=L2/L4:L6=L5/L7:BOTTOM=L7 |
| PE_100M_CLK1_P | PE_100M_CLK1-DIFF1 | PAIR | 5 | 6.5 | 5 | 10 | 5 | 12 | 20 | 25 | 12 | 12 | 20 | 12 | 7.5 | 85 Ohms | TOP=L2:L3=L2/L4:L6=L5/L7:BOTTOM=L7 |
| PE_100M_CLK1_P | PE_100M_CLK1-DIFF1 | PAIR | 6 | 6.5 | 5 | 10 | 5 | 12 | 20 | 25 | 12 | 12 | 20 | 12 | 7.5 | 85 Ohms | TOP=L2:L3=L2/L4:L6=L5/L7:BOTTOM=L7 |
| PE_100M_CLK1_P | PE_100M_CLK1-DIFF1 | PAIR | 7 | 6.5 | 5 | 10 | 5 | 12 | 20 | 25 | 12 | 12 | 20 | 12 | 7.5 | 85 Ohms | TOP=L2:L3=L2/L4:L6=L5/L7:BOTTOM=L7 |
| PE_100M_CLK1_P | PE_100M_CLK1-DIFF1 | PAIR | 8 | 6.88 | 5 | 10 | 5 | 12 | 20 | 36 | 12 | 12 | 20 | 12 | 5.13 | 85 Ohms | TOP=L2:L3=L2/L4:L6=L5/L7:BOTTOM=L7 |
| PE_100M_CLK2_C_N | PE_100M_CLK2_C-DIFF1 | PAIR | 1 | 6.88 | 5 | 10 | 5 | 12 | 20 | 36 | 12 | 12 | 20 | 12 | 5.13 | 85 Ohms | TOP=L2:L3=L2/L4:L6=L5/L7:BOTTOM=L7 |
| PE_100M_CLK2_C_N | PE_100M_CLK2_C-DIFF1 | PAIR | 2 | 6.5 | 5 | 10 | 5 | 12 | 20 | 25 | 12 | 12 | 20 | 12 | 7.5 | 85 Ohms | TOP=L2:L3=L2/L4:L6=L5/L7:BOTTOM=L7 |
| PE_100M_CLK2_C_N | PE_100M_CLK2_C-DIFF1 | PAIR | 3 | 6.5 | 5 | 10 | 5 | 12 | 20 | 25 | 12 | 12 | 20 | 12 | 7.5 | 85 Ohms | TOP=L2:L3=L2/L4:L6=L5/L7:BOTTOM=L7 |
| PE_100M_CLK2_C_N | PE_100M_CLK2_C-DIFF1 | PAIR | 4 | 6.5 | 5 | 10 | 5 | 12 | 20 | 25 | 12 | 12 | 20 | 12 | 7.5 | 85 Ohms | TOP=L2:L3=L2/L4:L6=L5/L7:BOTTOM=L7 |
| PE_100M_CLK2_C_N | PE_100M_CLK2_C-DIFF1 | PAIR | 5 | 6.5 | 5 | 10 | 5 | 12 | 20 | 25 | 12 | 12 | 20 | 12 | 7.5 | 85 Ohms | TOP=L2:L3=L2/L4:L6=L5/L7:BOTTOM=L7 |
| PE_100M_CLK2_C_N | PE_100M_CLK2_C-DIFF1 | PAIR | 6 | 6.5 | 5 | 10 | 5 | 12 | 20 | 25 | 12 | 12 | 20 | 12 | 7.5 | 85 Ohms | TOP=L2:L3=L2/L4:L6=L5/L7:BOTTOM=L7 |
| PE_100M_CLK2_C_N | PE_100M_CLK2_C-DIFF1 | PAIR | 7 | 6.5 | 5 | 10 | 5 | 12 | 20 | 25 | 12 | 12 | 20 | 12 | 7.5 | 85 Ohms | TOP=L2:L3=L2/L4:L6=L5/L7:BOTTOM=L7 |
| PE_100M_CLK2_C_N | PE_100M_CLK2_C-DIFF1 | PAIR | 8 | 6.88 | 5 | 10 | 5 | 12 | 20 | 36 | 12 | 12 | 20 | 12 | 5.13 | 85 Ohms | TOP=L2:L3=L2/L4:L6=L5/L7:BOTTOM=L7 |
| PE_100M_CLK2_C_P | PE_100M_CLK2_C-DIFF1 | PAIR | 1 | 6.88 | 5 | 10 | 5 | 12 | 20 | 36 | 12 | 12 | 20 | 12 | 5.13 | 85 Ohms | TOP=L2:L3=L2/L4:L6=L5/L7:BOTTOM=L7 |
| PE_100M_CLK2_C_P | PE_100M_CLK2_C-DIFF1 | PAIR | 2 | 6.5 | 5 | 10 | 5 | 12 | 20 | 25 | 12 | 12 | 20 | 12 | 7.5 | 85 Ohms | TOP=L2:L3=L2/L4:L6=L5/L7:BOTTOM=L7 |
| PE_100M_CLK2_C_P | PE_100M_CLK2_C-DIFF1 | PAIR | 3 | 6.5 | 5 | 10 | 5 | 12 | 20 | 25 | 12 | 12 | 20 | 12 | 7.5 | 85 Ohms | TOP=L2:L3=L2/L4:L6=L5/L7:BOTTOM=L7 |
| PE_100M_CLK2_C_P | PE_100M_CLK2_C-DIFF1 | PAIR | 4 | 6.5 | 5 | 10 | 5 | 12 | 20 | 25 | 12 | 12 | 20 | 12 | 7.5 | 85 Ohms | TOP=L2:L3=L2/L4:L6=L5/L7:BOTTOM=L7 |
| PE_100M_CLK2_C_P | PE_100M_CLK2_C-DIFF1 | PAIR | 5 | 6.5 | 5 | 10 | 5 | 12 | 20 | 25 | 12 | 12 | 20 | 12 | 7.5 | 85 Ohms | TOP=L2:L3=L2/L4:L6=L5/L7:BOTTOM=L7 |
| PE_100M_CLK2_C_P | PE_100M_CLK2_C-DIFF1 | PAIR | 6 | 6.5 | 5 | 10 | 5 | 12 | 20 | 25 | 12 | 12 | 20 | 12 | 7.5 | 85 Ohms | TOP=L2:L3=L2/L4:L6=L5/L7:BOTTOM=L7 |
| PE_100M_CLK2_C_P | PE_100M_CLK2_C-DIFF1 | PAIR | 7 | 6.5 | 5 | 10 | 5 | 12 | 20 | 25 | 12 | 12 | 20 | 12 | 7.5 | 85 Ohms | TOP=L2:L3=L2/L4:L6=L5/L7:BOTTOM=L7 |
| PE_100M_CLK2_C_P | PE_100M_CLK2_C-DIFF1 | PAIR | 8 | 6.88 | 5 | 10 | 5 | 12 | 20 | 36 | 12 | 12 | 20 | 12 | 5.13 | 85 Ohms | TOP=L2:L3=L2/L4:L6=L5/L7:BOTTOM=L7 |
| PE_100M_CLK2_N | PE_100M_CLK2-DIFF1 | PAIR | 1 | 6.88 | 5 | 10 | 5 | 12 | 20 | 36 | 12 | 12 | 20 | 12 | 5.13 | 85 Ohms | TOP=L2:L3=L2/L4:L6=L5/L7:BOTTOM=L7 |
| PE_100M_CLK2_N | PE_100M_CLK2-DIFF1 | PAIR | 2 | 6.5 | 5 | 10 | 5 | 12 | 20 | 25 | 12 | 12 | 20 | 12 | 7.5 | 85 Ohms | TOP=L2:L3=L2/L4:L6=L5/L7:BOTTOM=L7 |
| PE_100M_CLK2_N | PE_100M_CLK2-DIFF1 | PAIR | 3 | 6.5 | 5 | 10 | 5 | 12 | 20 | 25 | 12 | 12 | 20 | 12 | 7.5 | 85 Ohms | TOP=L2:L3=L2/L4:L6=L5/L7:BOTTOM=L7 |
| PE_100M_CLK2_N | PE_100M_CLK2-DIFF1 | PAIR | 4 | 6.5 | 5 | 10 | 5 | 12 | 20 | 25 | 12 | 12 | 20 | 12 | 7.5 | 85 Ohms | TOP=L2:L3=L2/L4:L6=L5/L7:BOTTOM=L7 |
| PE_100M_CLK2_N | PE_100M_CLK2-DIFF1 | PAIR | 5 | 6.5 | 5 | 10 | 5 | 12 | 20 | 25 | 12 | 12 | 20 | 12 | 7.5 | 85 Ohms | TOP=L2:L3=L2/L4:L6=L5/L7:BOTTOM=L7 |
| PE_100M_CLK2_N | PE_100M_CLK2-DIFF1 | PAIR | 6 | 6.5 | 5 | 10 | 5 | 12 | 20 | 25 | 12 | 12 | 20 | 12 | 7.5 | 85 Ohms | TOP=L2:L3=L2/L4:L6=L5/L7:BOTTOM=L7 |
| PE_100M_CLK2_N | PE_100M_CLK2-DIFF1 | PAIR | 7 | 6.5 | 5 | 10 | 5 | 12 | 20 | 25 | 12 | 12 | 20 | 12 | 7.5 | 85 Ohms | TOP=L2:L3=L2/L4:L6=L5/L7:BOTTOM=L7 |
| PE_100M_CLK2_N | PE_100M_CLK2-DIFF1 | PAIR | 8 | 6.88 | 5 | 10 | 5 | 12 | 20 | 36 | 12 | 12 | 20 | 12 | 5.13 | 85 Ohms | TOP=L2:L3=L2/L4:L6=L5/L7:BOTTOM=L7 |
| PE_100M_CLK2_P | PE_100M_CLK2-DIFF1 | PAIR | 1 | 6.88 | 5 | 10 | 5 | 12 | 20 | 36 | 12 | 12 | 20 | 12 | 5.13 | 85 Ohms | TOP=L2:L3=L2/L4:L6=L5/L7:BOTTOM=L7 |
| PE_100M_CLK2_P | PE_100M_CLK2-DIFF1 | PAIR | 2 | 6.5 | 5 | 10 | 5 | 12 | 20 | 25 | 12 | 12 | 20 | 12 | 7.5 | 85 Ohms | TOP=L2:L3=L2/L4:L6=L5/L7:BOTTOM=L7 |
| PE_100M_CLK2_P | PE_100M_CLK2-DIFF1 | PAIR | 3 | 6.5 | 5 | 10 | 5 | 12 | 20 | 25 | 12 | 12 | 20 | 12 | 7.5 | 85 Ohms | TOP=L2:L3=L2/L4:L6=L5/L7:BOTTOM=L7 |
| PE_100M_CLK2_P | PE_100M_CLK2-DIFF1 | PAIR | 4 | 6.5 | 5 | 10 | 5 | 12 | 20 | 25 | 12 | 12 | 20 | 12 | 7.5 | 85 Ohms | TOP=L2:L3=L2/L4:L6=L5/L7:BOTTOM=L7 |
| PE_100M_CLK2_P | PE_100M_CLK2-DIFF1 | PAIR | 5 | 6.5 | 5 | 10 | 5 | 12 | 20 | 25 | 12 | 12 | 20 | 12 | 7.5 | 85 Ohms | TOP=L2:L3=L2/L4:L6=L5/L7:BOTTOM=L7 |
| PE_100M_CLK2_P | PE_100M_CLK2-DIFF1 | PAIR | 6 | 6.5 | 5 | 10 | 5 | 12 | 20 | 25 | 12 | 12 | 20 | 12 | 7.5 | 85 Ohms | TOP=L2:L3=L2/L4:L6=L5/L7:BOTTOM=L7 |
| PE_100M_CLK2_P | PE_100M_CLK2-DIFF1 | PAIR | 7 | 6.5 | 5 | 10 | 5 | 12 | 20 | 25 | 12 | 12 | 20 | 12 | 7.5 | 85 Ohms | TOP=L2:L3=L2/L4:L6=L5/L7:BOTTOM=L7 |
| PE_100M_CLK2_P | PE_100M_CLK2-DIFF1 | PAIR | 8 | 6.88 | 5 | 10 | 5 | 12 | 20 | 36 | 12 | 12 | 20 | 12 | 5.13 | 85 Ohms | TOP=L2:L3=L2/L4:L6=L5/L7:BOTTOM=L7 |
| PE_100M_CLK3_C_N | PE_100M_CLK3_C-DIFF1 | PAIR | 1 | 6.88 | 5 | 10 | 5 | 12 | 20 | 36 | 12 | 12 | 20 | 12 | 5.13 | 85 Ohms | TOP=L2:L3=L2/L4:L6=L5/L7:BOTTOM=L7 |
| PE_100M_CLK3_C_N | PE_100M_CLK3_C-DIFF1 | PAIR | 2 | 6.5 | 5 | 10 | 5 | 12 | 20 | 25 | 12 | 12 | 20 | 12 | 7.5 | 85 Ohms | TOP=L2:L3=L2/L4:L6=L5/L7:BOTTOM=L7 |
| PE_100M_CLK3_C_N | PE_100M_CLK3_C-DIFF1 | PAIR | 3 | 6.5 | 5 | 10 | 5 | 12 | 20 | 25 | 12 | 12 | 20 | 12 | 7.5 | 85 Ohms | TOP=L2:L3=L2/L4:L6=L5/L7:BOTTOM=L7 |
| PE_100M_CLK3_C_N | PE_100M_CLK3_C-DIFF1 | PAIR | 4 | 6.5 | 5 | 10 | 5 | 12 | 20 | 25 | 12 | 12 | 20 | 12 | 7.5 | 85 Ohms | TOP=L2:L3=L2/L4:L6=L5/L7:BOTTOM=L7 |
| PE_100M_CLK3_C_N | PE_100M_CLK3_C-DIFF1 | PAIR | 5 | 6.5 | 5 | 10 | 5 | 12 | 20 | 25 | 12 | 12 | 20 | 12 | 7.5 | 85 Ohms | TOP=L2:L3=L2/L4:L6=L5/L7:BOTTOM=L7 |
| PE_100M_CLK3_C_N | PE_100M_CLK3_C-DIFF1 | PAIR | 6 | 6.5 | 5 | 10 | 5 | 12 | 20 | 25 | 12 | 12 | 20 | 12 | 7.5 | 85 Ohms | TOP=L2:L3=L2/L4:L6=L5/L7:BOTTOM=L7 |
| PE_100M_CLK3_C_N | PE_100M_CLK3_C-DIFF1 | PAIR | 7 | 6.5 | 5 | 10 | 5 | 12 | 20 | 25 | 12 | 12 | 20 | 12 | 7.5 | 85 Ohms | TOP=L2:L3=L2/L4:L6=L5/L7:BOTTOM=L7 |
| PE_100M_CLK3_C_N | PE_100M_CLK3_C-DIFF1 | PAIR | 8 | 6.88 | 5 | 10 | 5 | 12 | 20 | 36 | 12 | 12 | 20 | 12 | 5.13 | 85 Ohms | TOP=L2:L3=L2/L4:L6=L5/L7:BOTTOM=L7 |
| PE_100M_CLK3_C_P | PE_100M_CLK3_C-DIFF1 | PAIR | 1 | 6.88 | 5 | 10 | 5 | 12 | 20 | 36 | 12 | 12 | 20 | 12 | 5.13 | 85 Ohms | TOP=L2:L3=L2/L4:L6=L5/L7:BOTTOM=L7 |
| PE_100M_CLK3_C_P | PE_100M_CLK3_C-DIFF1 | PAIR | 2 | 6.5 | 5 | 10 | 5 | 12 | 20 | 25 | 12 | 12 | 20 | 12 | 7.5 | 85 Ohms | TOP=L2:L3=L2/L4:L6=L5/L7:BOTTOM=L7 |
| PE_100M_CLK3_C_P | PE_100M_CLK3_C-DIFF1 | PAIR | 3 | 6.5 | 5 | 10 | 5 | 12 | 20 | 25 | 12 | 12 | 20 | 12 | 7.5 | 85 Ohms | TOP=L2:L3=L2/L4:L6=L5/L7:BOTTOM=L7 |
| PE_100M_CLK3_C_P | PE_100M_CLK3_C-DIFF1 | PAIR | 4 | 6.5 | 5 | 10 | 5 | 12 | 20 | 25 | 12 | 12 | 20 | 12 | 7.5 | 85 Ohms | TOP=L2:L3=L2/L4:L6=L5/L7:BOTTOM=L7 |
| PE_100M_CLK3_C_P | PE_100M_CLK3_C-DIFF1 | PAIR | 5 | 6.5 | 5 | 10 | 5 | 12 | 20 | 25 | 12 | 12 | 20 | 12 | 7.5 | 85 Ohms | TOP=L2:L3=L2/L4:L6=L5/L7:BOTTOM=L7 |
| PE_100M_CLK3_C_P | PE_100M_CLK3_C-DIFF1 | PAIR | 6 | 6.5 | 5 | 10 | 5 | 12 | 20 | 25 | 12 | 12 | 20 | 12 | 7.5 | 85 Ohms | TOP=L2:L3=L2/L4:L6=L5/L7:BOTTOM=L7 |
| PE_100M_CLK3_C_P | PE_100M_CLK3_C-DIFF1 | PAIR | 7 | 6.5 | 5 | 10 | 5 | 12 | 20 | 25 | 12 | 12 | 20 | 12 | 7.5 | 85 Ohms | TOP=L2:L3=L2/L4:L6=L5/L7:BOTTOM=L7 |
| PE_100M_CLK3_C_P | PE_100M_CLK3_C-DIFF1 | PAIR | 8 | 6.88 | 5 | 10 | 5 | 12 | 20 | 36 | 12 | 12 | 20 | 12 | 5.13 | 85 Ohms | TOP=L2:L3=L2/L4:L6=L5/L7:BOTTOM=L7 |
| PE_100M_CLK3_N | PE_100M_CLK3-DIFF1 | PAIR | 1 | 6.88 | 5 | 10 | 5 | 12 | 20 | 36 | 12 | 12 | 20 | 12 | 5.13 | 85 Ohms | TOP=L2:L3=L2/L4:L6=L5/L7:BOTTOM=L7 |
| PE_100M_CLK3_N | PE_100M_CLK3-DIFF1 | PAIR | 2 | 6.5 | 5 | 10 | 5 | 12 | 20 | 25 | 12 | 12 | 20 | 12 | 7.5 | 85 Ohms | TOP=L2:L3=L2/L4:L6=L5/L7:BOTTOM=L7 |
| PE_100M_CLK3_N | PE_100M_CLK3-DIFF1 | PAIR | 3 | 6.5 | 5 | 10 | 5 | 12 | 20 | 25 | 12 | 12 | 20 | 12 | 7.5 | 85 Ohms | TOP=L2:L3=L2/L4:L6=L5/L7:BOTTOM=L7 |
| PE_100M_CLK3_N | PE_100M_CLK3-DIFF1 | PAIR | 4 | 6.5 | 5 | 10 | 5 | 12 | 20 | 25 | 12 | 12 | 20 | 12 | 7.5 | 85 Ohms | TOP=L2:L3=L2/L4:L6=L5/L7:BOTTOM=L7 |
| PE_100M_CLK3_N | PE_100M_CLK3-DIFF1 | PAIR | 5 | 6.5 | 5 | 10 | 5 | 12 | 20 | 25 | 12 | 12 | 20 | 12 | 7.5 | 85 Ohms | TOP=L2:L3=L2/L4:L6=L5/L7:BOTTOM=L7 |
| PE_100M_CLK3_N | PE_100M_CLK3-DIFF1 | PAIR | 6 | 6.5 | 5 | 10 | 5 | 12 | 20 | 25 | 12 | 12 | 20 | 12 | 7.5 | 85 Ohms | TOP=L2:L3=L2/L4:L6=L5/L7:BOTTOM=L7 |
| PE_100M_CLK3_N | PE_100M_CLK3-DIFF1 | PAIR | 7 | 6.5 | 5 | 10 | 5 | 12 | 20 | 25 | 12 | 12 | 20 | 12 | 7.5 | 85 Ohms | TOP=L2:L3=L2/L4:L6=L5/L7:BOTTOM=L7 |
| PE_100M_CLK3_N | PE_100M_CLK3-DIFF1 | PAIR | 8 | 6.88 | 5 | 10 | 5 | 12 | 20 | 36 | 12 | 12 | 20 | 12 | 5.13 | 85 Ohms | TOP=L2:L3=L2/L4:L6=L5/L7:BOTTOM=L7 |
| PE_100M_CLK3_P | PE_100M_CLK3-DIFF1 | PAIR | 1 | 6.88 | 5 | 10 | 5 | 12 | 20 | 36 | 12 | 12 | 20 | 12 | 5.13 | 85 Ohms | TOP=L2:L3=L2/L4:L6=L5/L7:BOTTOM=L7 |
| PE_100M_CLK3_P | PE_100M_CLK3-DIFF1 | PAIR | 2 | 6.5 | 5 | 10 | 5 | 12 | 20 | 25 | 12 | 12 | 20 | 12 | 7.5 | 85 Ohms | TOP=L2:L3=L2/L4:L6=L5/L7:BOTTOM=L7 |
| PE_100M_CLK3_P | PE_100M_CLK3-DIFF1 | PAIR | 3 | 6.5 | 5 | 10 | 5 | 12 | 20 | 25 | 12 | 12 | 20 | 12 | 7.5 | 85 Ohms | TOP=L2:L3=L2/L4:L6=L5/L7:BOTTOM=L7 |
| PE_100M_CLK3_P | PE_100M_CLK3-DIFF1 | PAIR | 4 | 6.5 | 5 | 10 | 5 | 12 | 20 | 25 | 12 | 12 | 20 | 12 | 7.5 | 85 Ohms | TOP=L2:L3=L2/L4:L6=L5/L7:BOTTOM=L7 |
| PE_100M_CLK3_P | PE_100M_CLK3-DIFF1 | PAIR | 5 | 6.5 | 5 | 10 | 5 | 12 | 20 | 25 | 12 | 12 | 20 | 12 | 7.5 | 85 Ohms | TOP=L2:L3=L2/L4:L6=L5/L7:BOTTOM=L7 |
| PE_100M_CLK3_P | PE_100M_CLK3-DIFF1 | PAIR | 6 | 6.5 | 5 | 10 | 5 | 12 | 20 | 25 | 12 | 12 | 20 | 12 | 7.5 | 85 Ohms | TOP=L2:L3=L2/L4:L6=L5/L7:BOTTOM=L7 |
| PE_100M_CLK3_P | PE_100M_CLK3-DIFF1 | PAIR | 7 | 6.5 | 5 | 10 | 5 | 12 | 20 | 25 | 12 | 12 | 20 | 12 | 7.5 | 85 Ohms | TOP=L2:L3=L2/L4:L6=L5/L7:BOTTOM=L7 |
| PE_100M_CLK3_P | PE_100M_CLK3-DIFF1 | PAIR | 8 | 6.88 | 5 | 10 | 5 | 12 | 20 | 36 | 12 | 12 | 20 | 12 | 5.13 | 85 Ohms | TOP=L2:L3=L2/L4:L6=L5/L7:BOTTOM=L7 |
| PE_100M_CLK4_C_N | PE_100M_CLK4_C-DIFF1 | PAIR | 1 | 6.88 | 5 | 10 | 5 | 12 | 20 | 36 | 12 | 12 | 20 | 12 | 5.13 | 85 Ohms | TOP=L2:L3=L2/L4:L6=L5/L7:BOTTOM=L7 |
| PE_100M_CLK4_C_N | PE_100M_CLK4_C-DIFF1 | PAIR | 2 | 6.5 | 5 | 10 | 5 | 12 | 20 | 25 | 12 | 12 | 20 | 12 | 7.5 | 85 Ohms | TOP=L2:L3=L2/L4:L6=L5/L7:BOTTOM=L7 |
| PE_100M_CLK4_C_N | PE_100M_CLK4_C-DIFF1 | PAIR | 3 | 6.5 | 5 | 10 | 5 | 12 | 20 | 25 | 12 | 12 | 20 | 12 | 7.5 | 85 Ohms | TOP=L2:L3=L2/L4:L6=L5/L7:BOTTOM=L7 |
| PE_100M_CLK4_C_N | PE_100M_CLK4_C-DIFF1 | PAIR | 4 | 6.5 | 5 | 10 | 5 | 12 | 20 | 25 | 12 | 12 | 20 | 12 | 7.5 | 85 Ohms | TOP=L2:L3=L2/L4:L6=L5/L7:BOTTOM=L7 |
| PE_100M_CLK4_C_N | PE_100M_CLK4_C-DIFF1 | PAIR | 5 | 6.5 | 5 | 10 | 5 | 12 | 20 | 25 | 12 | 12 | 20 | 12 | 7.5 | 85 Ohms | TOP=L2:L3=L2/L4:L6=L5/L7:BOTTOM=L7 |
| PE_100M_CLK4_C_N | PE_100M_CLK4_C-DIFF1 | PAIR | 6 | 6.5 | 5 | 10 | 5 | 12 | 20 | 25 | 12 | 12 | 20 | 12 | 7.5 | 85 Ohms | TOP=L2:L3=L2/L4:L6=L5/L7:BOTTOM=L7 |
| PE_100M_CLK4_C_N | PE_100M_CLK4_C-DIFF1 | PAIR | 7 | 6.5 | 5 | 10 | 5 | 12 | 20 | 25 | 12 | 12 | 20 | 12 | 7.5 | 85 Ohms | TOP=L2:L3=L2/L4:L6=L5/L7:BOTTOM=L7 |
| PE_100M_CLK4_C_N | PE_100M_CLK4_C-DIFF1 | PAIR | 8 | 6.88 | 5 | 10 | 5 | 12 | 20 | 36 | 12 | 12 | 20 | 12 | 5.13 | 85 Ohms | TOP=L2:L3=L2/L4:L6=L5/L7:BOTTOM=L7 |
| PE_100M_CLK4_C_P | PE_100M_CLK4_C-DIFF1 | PAIR | 1 | 6.88 | 5 | 10 | 5 | 12 | 20 | 36 | 12 | 12 | 20 | 12 | 5.13 | 85 Ohms | TOP=L2:L3=L2/L4:L6=L5/L7:BOTTOM=L7 |
| PE_100M_CLK4_C_P | PE_100M_CLK4_C-DIFF1 | PAIR | 2 | 6.5 | 5 | 10 | 5 | 12 | 20 | 25 | 12 | 12 | 20 | 12 | 7.5 | 85 Ohms | TOP=L2:L3=L2/L4:L6=L5/L7:BOTTOM=L7 |
| PE_100M_CLK4_C_P | PE_100M_CLK4_C-DIFF1 | PAIR | 3 | 6.5 | 5 | 10 | 5 | 12 | 20 | 25 | 12 | 12 | 20 | 12 | 7.5 | 85 Ohms | TOP=L2:L3=L2/L4:L6=L5/L7:BOTTOM=L7 |
| PE_100M_CLK4_C_P | PE_100M_CLK4_C-DIFF1 | PAIR | 4 | 6.5 | 5 | 10 | 5 | 12 | 20 | 25 | 12 | 12 | 20 | 12 | 7.5 | 85 Ohms | TOP=L2:L3=L2/L4:L6=L5/L7:BOTTOM=L7 |
| PE_100M_CLK4_C_P | PE_100M_CLK4_C-DIFF1 | PAIR | 5 | 6.5 | 5 | 10 | 5 | 12 | 20 | 25 | 12 | 12 | 20 | 12 | 7.5 | 85 Ohms | TOP=L2:L3=L2/L4:L6=L5/L7:BOTTOM=L7 |
| PE_100M_CLK4_C_P | PE_100M_CLK4_C-DIFF1 | PAIR | 6 | 6.5 | 5 | 10 | 5 | 12 | 20 | 25 | 12 | 12 | 20 | 12 | 7.5 | 85 Ohms | TOP=L2:L3=L2/L4:L6=L5/L7:BOTTOM=L7 |
| PE_100M_CLK4_C_P | PE_100M_CLK4_C-DIFF1 | PAIR | 7 | 6.5 | 5 | 10 | 5 | 12 | 20 | 25 | 12 | 12 | 20 | 12 | 7.5 | 85 Ohms | TOP=L2:L3=L2/L4:L6=L5/L7:BOTTOM=L7 |
| PE_100M_CLK4_C_P | PE_100M_CLK4_C-DIFF1 | PAIR | 8 | 6.88 | 5 | 10 | 5 | 12 | 20 | 36 | 12 | 12 | 20 | 12 | 5.13 | 85 Ohms | TOP=L2:L3=L2/L4:L6=L5/L7:BOTTOM=L7 |
| PE_100M_CLK4_N | PE_100M_CLK4-DIFF1 | PAIR | 1 | 6.88 | 5 | 10 | 5 | 12 | 20 | 36 | 12 | 12 | 20 | 12 | 5.13 | 85 Ohms | TOP=L2:L3=L2/L4:L6=L5/L7:BOTTOM=L7 |
| PE_100M_CLK4_N | PE_100M_CLK4-DIFF1 | PAIR | 2 | 6.5 | 5 | 10 | 5 | 12 | 20 | 25 | 12 | 12 | 20 | 12 | 7.5 | 85 Ohms | TOP=L2:L3=L2/L4:L6=L5/L7:BOTTOM=L7 |
| PE_100M_CLK4_N | PE_100M_CLK4-DIFF1 | PAIR | 3 | 6.5 | 5 | 10 | 5 | 12 | 20 | 25 | 12 | 12 | 20 | 12 | 7.5 | 85 Ohms | TOP=L2:L3=L2/L4:L6=L5/L7:BOTTOM=L7 |
| PE_100M_CLK4_N | PE_100M_CLK4-DIFF1 | PAIR | 4 | 6.5 | 5 | 10 | 5 | 12 | 20 | 25 | 12 | 12 | 20 | 12 | 7.5 | 85 Ohms | TOP=L2:L3=L2/L4:L6=L5/L7:BOTTOM=L7 |
| PE_100M_CLK4_N | PE_100M_CLK4-DIFF1 | PAIR | 5 | 6.5 | 5 | 10 | 5 | 12 | 20 | 25 | 12 | 12 | 20 | 12 | 7.5 | 85 Ohms | TOP=L2:L3=L2/L4:L6=L5/L7:BOTTOM=L7 |
| PE_100M_CLK4_N | PE_100M_CLK4-DIFF1 | PAIR | 6 | 6.5 | 5 | 10 | 5 | 12 | 20 | 25 | 12 | 12 | 20 | 12 | 7.5 | 85 Ohms | TOP=L2:L3=L2/L4:L6=L5/L7:BOTTOM=L7 |
| PE_100M_CLK4_N | PE_100M_CLK4-DIFF1 | PAIR | 7 | 6.5 | 5 | 10 | 5 | 12 | 20 | 25 | 12 | 12 | 20 | 12 | 7.5 | 85 Ohms | TOP=L2:L3=L2/L4:L6=L5/L7:BOTTOM=L7 |
| PE_100M_CLK4_N | PE_100M_CLK4-DIFF1 | PAIR | 8 | 6.88 | 5 | 10 | 5 | 12 | 20 | 36 | 12 | 12 | 20 | 12 | 5.13 | 85 Ohms | TOP=L2:L3=L2/L4:L6=L5/L7:BOTTOM=L7 |
| PE_100M_CLK4_P | PE_100M_CLK4-DIFF1 | PAIR | 1 | 6.88 | 5 | 10 | 5 | 12 | 20 | 36 | 12 | 12 | 20 | 12 | 5.13 | 85 Ohms | TOP=L2:L3=L2/L4:L6=L5/L7:BOTTOM=L7 |
| PE_100M_CLK4_P | PE_100M_CLK4-DIFF1 | PAIR | 2 | 6.5 | 5 | 10 | 5 | 12 | 20 | 25 | 12 | 12 | 20 | 12 | 7.5 | 85 Ohms | TOP=L2:L3=L2/L4:L6=L5/L7:BOTTOM=L7 |
| PE_100M_CLK4_P | PE_100M_CLK4-DIFF1 | PAIR | 3 | 6.5 | 5 | 10 | 5 | 12 | 20 | 25 | 12 | 12 | 20 | 12 | 7.5 | 85 Ohms | TOP=L2:L3=L2/L4:L6=L5/L7:BOTTOM=L7 |
| PE_100M_CLK4_P | PE_100M_CLK4-DIFF1 | PAIR | 4 | 6.5 | 5 | 10 | 5 | 12 | 20 | 25 | 12 | 12 | 20 | 12 | 7.5 | 85 Ohms | TOP=L2:L3=L2/L4:L6=L5/L7:BOTTOM=L7 |
| PE_100M_CLK4_P | PE_100M_CLK4-DIFF1 | PAIR | 5 | 6.5 | 5 | 10 | 5 | 12 | 20 | 25 | 12 | 12 | 20 | 12 | 7.5 | 85 Ohms | TOP=L2:L3=L2/L4:L6=L5/L7:BOTTOM=L7 |
| PE_100M_CLK4_P | PE_100M_CLK4-DIFF1 | PAIR | 6 | 6.5 | 5 | 10 | 5 | 12 | 20 | 25 | 12 | 12 | 20 | 12 | 7.5 | 85 Ohms | TOP=L2:L3=L2/L4:L6=L5/L7:BOTTOM=L7 |
| PE_100M_CLK4_P | PE_100M_CLK4-DIFF1 | PAIR | 7 | 6.5 | 5 | 10 | 5 | 12 | 20 | 25 | 12 | 12 | 20 | 12 | 7.5 | 85 Ohms | TOP=L2:L3=L2/L4:L6=L5/L7:BOTTOM=L7 |
| PE_100M_CLK4_P | PE_100M_CLK4-DIFF1 | PAIR | 8 | 6.88 | 5 | 10 | 5 | 12 | 20 | 36 | 12 | 12 | 20 | 12 | 5.13 | 85 Ohms | TOP=L2:L3=L2/L4:L6=L5/L7:BOTTOM=L7 |
| PE_CLK_100M_DR0_1_R_N | PE_CLK_100M_DR0_1_R-DIFF1 | PAIR | 1 | 6.88 | 5 | 10 | 5 | 12 | 20 | 36 | 12 | 12 | 20 | 12 | 5.13 | 85 Ohms | TOP=L2:L3=L2/L4:L6=L5/L7:BOTTOM=L7 |
| PE_CLK_100M_DR0_1_R_N | PE_CLK_100M_DR0_1_R-DIFF1 | PAIR | 2 | 6.5 | 5 | 10 | 5 | 12 | 20 | 25 | 12 | 12 | 20 | 12 | 7.5 | 85 Ohms | TOP=L2:L3=L2/L4:L6=L5/L7:BOTTOM=L7 |
| PE_CLK_100M_DR0_1_R_N | PE_CLK_100M_DR0_1_R-DIFF1 | PAIR | 3 | 6.5 | 5 | 10 | 5 | 12 | 20 | 25 | 12 | 12 | 20 | 12 | 7.5 | 85 Ohms | TOP=L2:L3=L2/L4:L6=L5/L7:BOTTOM=L7 |
| PE_CLK_100M_DR0_1_R_N | PE_CLK_100M_DR0_1_R-DIFF1 | PAIR | 4 | 6.5 | 5 | 10 | 5 | 12 | 20 | 25 | 12 | 12 | 20 | 12 | 7.5 | 85 Ohms | TOP=L2:L3=L2/L4:L6=L5/L7:BOTTOM=L7 |
| PE_CLK_100M_DR0_1_R_N | PE_CLK_100M_DR0_1_R-DIFF1 | PAIR | 5 | 6.5 | 5 | 10 | 5 | 12 | 20 | 25 | 12 | 12 | 20 | 12 | 7.5 | 85 Ohms | TOP=L2:L3=L2/L4:L6=L5/L7:BOTTOM=L7 |
| PE_CLK_100M_DR0_1_R_N | PE_CLK_100M_DR0_1_R-DIFF1 | PAIR | 6 | 6.5 | 5 | 10 | 5 | 12 | 20 | 25 | 12 | 12 | 20 | 12 | 7.5 | 85 Ohms | TOP=L2:L3=L2/L4:L6=L5/L7:BOTTOM=L7 |
| PE_CLK_100M_DR0_1_R_N | PE_CLK_100M_DR0_1_R-DIFF1 | PAIR | 7 | 6.5 | 5 | 10 | 5 | 12 | 20 | 25 | 12 | 12 | 20 | 12 | 7.5 | 85 Ohms | TOP=L2:L3=L2/L4:L6=L5/L7:BOTTOM=L7 |
| PE_CLK_100M_DR0_1_R_N | PE_CLK_100M_DR0_1_R-DIFF1 | PAIR | 8 | 6.88 | 5 | 10 | 5 | 12 | 20 | 36 | 12 | 12 | 20 | 12 | 5.13 | 85 Ohms | TOP=L2:L3=L2/L4:L6=L5/L7:BOTTOM=L7 |
| PE_CLK_100M_DR0_1_R_P | PE_CLK_100M_DR0_1_R-DIFF1 | PAIR | 1 | 6.88 | 5 | 10 | 5 | 12 | 20 | 36 | 12 | 12 | 20 | 12 | 5.13 | 85 Ohms | TOP=L2:L3=L2/L4:L6=L5/L7:BOTTOM=L7 |
| PE_CLK_100M_DR0_1_R_P | PE_CLK_100M_DR0_1_R-DIFF1 | PAIR | 2 | 6.5 | 5 | 10 | 5 | 12 | 20 | 25 | 12 | 12 | 20 | 12 | 7.5 | 85 Ohms | TOP=L2:L3=L2/L4:L6=L5/L7:BOTTOM=L7 |
| PE_CLK_100M_DR0_1_R_P | PE_CLK_100M_DR0_1_R-DIFF1 | PAIR | 3 | 6.5 | 5 | 10 | 5 | 12 | 20 | 25 | 12 | 12 | 20 | 12 | 7.5 | 85 Ohms | TOP=L2:L3=L2/L4:L6=L5/L7:BOTTOM=L7 |
| PE_CLK_100M_DR0_1_R_P | PE_CLK_100M_DR0_1_R-DIFF1 | PAIR | 4 | 6.5 | 5 | 10 | 5 | 12 | 20 | 25 | 12 | 12 | 20 | 12 | 7.5 | 85 Ohms | TOP=L2:L3=L2/L4:L6=L5/L7:BOTTOM=L7 |
| PE_CLK_100M_DR0_1_R_P | PE_CLK_100M_DR0_1_R-DIFF1 | PAIR | 5 | 6.5 | 5 | 10 | 5 | 12 | 20 | 25 | 12 | 12 | 20 | 12 | 7.5 | 85 Ohms | TOP=L2:L3=L2/L4:L6=L5/L7:BOTTOM=L7 |
| PE_CLK_100M_DR0_1_R_P | PE_CLK_100M_DR0_1_R-DIFF1 | PAIR | 6 | 6.5 | 5 | 10 | 5 | 12 | 20 | 25 | 12 | 12 | 20 | 12 | 7.5 | 85 Ohms | TOP=L2:L3=L2/L4:L6=L5/L7:BOTTOM=L7 |
| PE_CLK_100M_DR0_1_R_P | PE_CLK_100M_DR0_1_R-DIFF1 | PAIR | 7 | 6.5 | 5 | 10 | 5 | 12 | 20 | 25 | 12 | 12 | 20 | 12 | 7.5 | 85 Ohms | TOP=L2:L3=L2/L4:L6=L5/L7:BOTTOM=L7 |
| PE_CLK_100M_DR0_1_R_P | PE_CLK_100M_DR0_1_R-DIFF1 | PAIR | 8 | 6.88 | 5 | 10 | 5 | 12 | 20 | 36 | 12 | 12 | 20 | 12 | 5.13 | 85 Ohms | TOP=L2:L3=L2/L4:L6=L5/L7:BOTTOM=L7 |
| PE_CLK_100M_DR0_2_R_N | PE_CLK_100M_DR0_2_R-DIFF1 | PAIR | 1 | 6.88 | 5 | 10 | 5 | 12 | 20 | 36 | 12 | 12 | 20 | 12 | 5.13 | 85 Ohms | TOP=L2:L3=L2/L4:L6=L5/L7:BOTTOM=L7 |
| PE_CLK_100M_DR0_2_R_N | PE_CLK_100M_DR0_2_R-DIFF1 | PAIR | 2 | 6.5 | 5 | 10 | 5 | 12 | 20 | 25 | 12 | 12 | 20 | 12 | 7.5 | 85 Ohms | TOP=L2:L3=L2/L4:L6=L5/L7:BOTTOM=L7 |
| PE_CLK_100M_DR0_2_R_N | PE_CLK_100M_DR0_2_R-DIFF1 | PAIR | 3 | 6.5 | 5 | 10 | 5 | 12 | 20 | 25 | 12 | 12 | 20 | 12 | 7.5 | 85 Ohms | TOP=L2:L3=L2/L4:L6=L5/L7:BOTTOM=L7 |
| PE_CLK_100M_DR0_2_R_N | PE_CLK_100M_DR0_2_R-DIFF1 | PAIR | 4 | 6.5 | 5 | 10 | 5 | 12 | 20 | 25 | 12 | 12 | 20 | 12 | 7.5 | 85 Ohms | TOP=L2:L3=L2/L4:L6=L5/L7:BOTTOM=L7 |
| PE_CLK_100M_DR0_2_R_N | PE_CLK_100M_DR0_2_R-DIFF1 | PAIR | 5 | 6.5 | 5 | 10 | 5 | 12 | 20 | 25 | 12 | 12 | 20 | 12 | 7.5 | 85 Ohms | TOP=L2:L3=L2/L4:L6=L5/L7:BOTTOM=L7 |
| PE_CLK_100M_DR0_2_R_N | PE_CLK_100M_DR0_2_R-DIFF1 | PAIR | 6 | 6.5 | 5 | 10 | 5 | 12 | 20 | 25 | 12 | 12 | 20 | 12 | 7.5 | 85 Ohms | TOP=L2:L3=L2/L4:L6=L5/L7:BOTTOM=L7 |
| PE_CLK_100M_DR0_2_R_N | PE_CLK_100M_DR0_2_R-DIFF1 | PAIR | 7 | 6.5 | 5 | 10 | 5 | 12 | 20 | 25 | 12 | 12 | 20 | 12 | 7.5 | 85 Ohms | TOP=L2:L3=L2/L4:L6=L5/L7:BOTTOM=L7 |
| PE_CLK_100M_DR0_2_R_N | PE_CLK_100M_DR0_2_R-DIFF1 | PAIR | 8 | 6.88 | 5 | 10 | 5 | 12 | 20 | 36 | 12 | 12 | 20 | 12 | 5.13 | 85 Ohms | TOP=L2:L3=L2/L4:L6=L5/L7:BOTTOM=L7 |
| PE_CLK_100M_DR0_2_R_P | PE_CLK_100M_DR0_2_R-DIFF1 | PAIR | 1 | 6.88 | 5 | 10 | 5 | 12 | 20 | 36 | 12 | 12 | 20 | 12 | 5.13 | 85 Ohms | TOP=L2:L3=L2/L4:L6=L5/L7:BOTTOM=L7 |
| PE_CLK_100M_DR0_2_R_P | PE_CLK_100M_DR0_2_R-DIFF1 | PAIR | 2 | 6.5 | 5 | 10 | 5 | 12 | 20 | 25 | 12 | 12 | 20 | 12 | 7.5 | 85 Ohms | TOP=L2:L3=L2/L4:L6=L5/L7:BOTTOM=L7 |
| PE_CLK_100M_DR0_2_R_P | PE_CLK_100M_DR0_2_R-DIFF1 | PAIR | 3 | 6.5 | 5 | 10 | 5 | 12 | 20 | 25 | 12 | 12 | 20 | 12 | 7.5 | 85 Ohms | TOP=L2:L3=L2/L4:L6=L5/L7:BOTTOM=L7 |
| PE_CLK_100M_DR0_2_R_P | PE_CLK_100M_DR0_2_R-DIFF1 | PAIR | 4 | 6.5 | 5 | 10 | 5 | 12 | 20 | 25 | 12 | 12 | 20 | 12 | 7.5 | 85 Ohms | TOP=L2:L3=L2/L4:L6=L5/L7:BOTTOM=L7 |
| PE_CLK_100M_DR0_2_R_P | PE_CLK_100M_DR0_2_R-DIFF1 | PAIR | 5 | 6.5 | 5 | 10 | 5 | 12 | 20 | 25 | 12 | 12 | 20 | 12 | 7.5 | 85 Ohms | TOP=L2:L3=L2/L4:L6=L5/L7:BOTTOM=L7 |
| PE_CLK_100M_DR0_2_R_P | PE_CLK_100M_DR0_2_R-DIFF1 | PAIR | 6 | 6.5 | 5 | 10 | 5 | 12 | 20 | 25 | 12 | 12 | 20 | 12 | 7.5 | 85 Ohms | TOP=L2:L3=L2/L4:L6=L5/L7:BOTTOM=L7 |
| PE_CLK_100M_DR0_2_R_P | PE_CLK_100M_DR0_2_R-DIFF1 | PAIR | 7 | 6.5 | 5 | 10 | 5 | 12 | 20 | 25 | 12 | 12 | 20 | 12 | 7.5 | 85 Ohms | TOP=L2:L3=L2/L4:L6=L5/L7:BOTTOM=L7 |
| PE_CLK_100M_DR0_2_R_P | PE_CLK_100M_DR0_2_R-DIFF1 | PAIR | 8 | 6.88 | 5 | 10 | 5 | 12 | 20 | 36 | 12 | 12 | 20 | 12 | 5.13 | 85 Ohms | TOP=L2:L3=L2/L4:L6=L5/L7:BOTTOM=L7 |
| PE_CLK_100M_DR1_1_R_N | PE_CLK_100M_DR1_1_R-DIFF1 | PAIR | 1 | 6.88 | 5 | 10 | 5 | 12 | 20 | 36 | 12 | 12 | 20 | 12 | 5.13 | 85 Ohms | TOP=L2:L3=L2/L4:L6=L5/L7:BOTTOM=L7 |
| PE_CLK_100M_DR1_1_R_N | PE_CLK_100M_DR1_1_R-DIFF1 | PAIR | 2 | 6.5 | 5 | 10 | 5 | 12 | 20 | 25 | 12 | 12 | 20 | 12 | 7.5 | 85 Ohms | TOP=L2:L3=L2/L4:L6=L5/L7:BOTTOM=L7 |
| PE_CLK_100M_DR1_1_R_N | PE_CLK_100M_DR1_1_R-DIFF1 | PAIR | 3 | 6.5 | 5 | 10 | 5 | 12 | 20 | 25 | 12 | 12 | 20 | 12 | 7.5 | 85 Ohms | TOP=L2:L3=L2/L4:L6=L5/L7:BOTTOM=L7 |
| PE_CLK_100M_DR1_1_R_N | PE_CLK_100M_DR1_1_R-DIFF1 | PAIR | 4 | 6.5 | 5 | 10 | 5 | 12 | 20 | 25 | 12 | 12 | 20 | 12 | 7.5 | 85 Ohms | TOP=L2:L3=L2/L4:L6=L5/L7:BOTTOM=L7 |
| PE_CLK_100M_DR1_1_R_N | PE_CLK_100M_DR1_1_R-DIFF1 | PAIR | 5 | 6.5 | 5 | 10 | 5 | 12 | 20 | 25 | 12 | 12 | 20 | 12 | 7.5 | 85 Ohms | TOP=L2:L3=L2/L4:L6=L5/L7:BOTTOM=L7 |
| PE_CLK_100M_DR1_1_R_N | PE_CLK_100M_DR1_1_R-DIFF1 | PAIR | 6 | 6.5 | 5 | 10 | 5 | 12 | 20 | 25 | 12 | 12 | 20 | 12 | 7.5 | 85 Ohms | TOP=L2:L3=L2/L4:L6=L5/L7:BOTTOM=L7 |
| PE_CLK_100M_DR1_1_R_N | PE_CLK_100M_DR1_1_R-DIFF1 | PAIR | 7 | 6.5 | 5 | 10 | 5 | 12 | 20 | 25 | 12 | 12 | 20 | 12 | 7.5 | 85 Ohms | TOP=L2:L3=L2/L4:L6=L5/L7:BOTTOM=L7 |
| PE_CLK_100M_DR1_1_R_N | PE_CLK_100M_DR1_1_R-DIFF1 | PAIR | 8 | 6.88 | 5 | 10 | 5 | 12 | 20 | 36 | 12 | 12 | 20 | 12 | 5.13 | 85 Ohms | TOP=L2:L3=L2/L4:L6=L5/L7:BOTTOM=L7 |
| PE_CLK_100M_DR1_1_R_P | PE_CLK_100M_DR1_1_R-DIFF1 | PAIR | 1 | 6.88 | 5 | 10 | 5 | 12 | 20 | 36 | 12 | 12 | 20 | 12 | 5.13 | 85 Ohms | TOP=L2:L3=L2/L4:L6=L5/L7:BOTTOM=L7 |
| PE_CLK_100M_DR1_1_R_P | PE_CLK_100M_DR1_1_R-DIFF1 | PAIR | 2 | 6.5 | 5 | 10 | 5 | 12 | 20 | 25 | 12 | 12 | 20 | 12 | 7.5 | 85 Ohms | TOP=L2:L3=L2/L4:L6=L5/L7:BOTTOM=L7 |
| PE_CLK_100M_DR1_1_R_P | PE_CLK_100M_DR1_1_R-DIFF1 | PAIR | 3 | 6.5 | 5 | 10 | 5 | 12 | 20 | 25 | 12 | 12 | 20 | 12 | 7.5 | 85 Ohms | TOP=L2:L3=L2/L4:L6=L5/L7:BOTTOM=L7 |
| PE_CLK_100M_DR1_1_R_P | PE_CLK_100M_DR1_1_R-DIFF1 | PAIR | 4 | 6.5 | 5 | 10 | 5 | 12 | 20 | 25 | 12 | 12 | 20 | 12 | 7.5 | 85 Ohms | TOP=L2:L3=L2/L4:L6=L5/L7:BOTTOM=L7 |
| PE_CLK_100M_DR1_1_R_P | PE_CLK_100M_DR1_1_R-DIFF1 | PAIR | 5 | 6.5 | 5 | 10 | 5 | 12 | 20 | 25 | 12 | 12 | 20 | 12 | 7.5 | 85 Ohms | TOP=L2:L3=L2/L4:L6=L5/L7:BOTTOM=L7 |
| PE_CLK_100M_DR1_1_R_P | PE_CLK_100M_DR1_1_R-DIFF1 | PAIR | 6 | 6.5 | 5 | 10 | 5 | 12 | 20 | 25 | 12 | 12 | 20 | 12 | 7.5 | 85 Ohms | TOP=L2:L3=L2/L4:L6=L5/L7:BOTTOM=L7 |
| PE_CLK_100M_DR1_1_R_P | PE_CLK_100M_DR1_1_R-DIFF1 | PAIR | 7 | 6.5 | 5 | 10 | 5 | 12 | 20 | 25 | 12 | 12 | 20 | 12 | 7.5 | 85 Ohms | TOP=L2:L3=L2/L4:L6=L5/L7:BOTTOM=L7 |
| PE_CLK_100M_DR1_1_R_P | PE_CLK_100M_DR1_1_R-DIFF1 | PAIR | 8 | 6.88 | 5 | 10 | 5 | 12 | 20 | 36 | 12 | 12 | 20 | 12 | 5.13 | 85 Ohms | TOP=L2:L3=L2/L4:L6=L5/L7:BOTTOM=L7 |
| PE_CLK_100M_DR1_2_R_N | PE_CLK_100M_DR1_2_R-DIFF1 | PAIR | 1 | 6.88 | 5 | 10 | 5 | 12 | 20 | 36 | 12 | 12 | 20 | 12 | 5.13 | 85 Ohms | TOP=L2:L3=L2/L4:L6=L5/L7:BOTTOM=L7 |
| PE_CLK_100M_DR1_2_R_N | PE_CLK_100M_DR1_2_R-DIFF1 | PAIR | 2 | 6.5 | 5 | 10 | 5 | 12 | 20 | 25 | 12 | 12 | 20 | 12 | 7.5 | 85 Ohms | TOP=L2:L3=L2/L4:L6=L5/L7:BOTTOM=L7 |
| PE_CLK_100M_DR1_2_R_N | PE_CLK_100M_DR1_2_R-DIFF1 | PAIR | 3 | 6.5 | 5 | 10 | 5 | 12 | 20 | 25 | 12 | 12 | 20 | 12 | 7.5 | 85 Ohms | TOP=L2:L3=L2/L4:L6=L5/L7:BOTTOM=L7 |
| PE_CLK_100M_DR1_2_R_N | PE_CLK_100M_DR1_2_R-DIFF1 | PAIR | 4 | 6.5 | 5 | 10 | 5 | 12 | 20 | 25 | 12 | 12 | 20 | 12 | 7.5 | 85 Ohms | TOP=L2:L3=L2/L4:L6=L5/L7:BOTTOM=L7 |
| PE_CLK_100M_DR1_2_R_N | PE_CLK_100M_DR1_2_R-DIFF1 | PAIR | 5 | 6.5 | 5 | 10 | 5 | 12 | 20 | 25 | 12 | 12 | 20 | 12 | 7.5 | 85 Ohms | TOP=L2:L3=L2/L4:L6=L5/L7:BOTTOM=L7 |
| PE_CLK_100M_DR1_2_R_N | PE_CLK_100M_DR1_2_R-DIFF1 | PAIR | 6 | 6.5 | 5 | 10 | 5 | 12 | 20 | 25 | 12 | 12 | 20 | 12 | 7.5 | 85 Ohms | TOP=L2:L3=L2/L4:L6=L5/L7:BOTTOM=L7 |
| PE_CLK_100M_DR1_2_R_N | PE_CLK_100M_DR1_2_R-DIFF1 | PAIR | 7 | 6.5 | 5 | 10 | 5 | 12 | 20 | 25 | 12 | 12 | 20 | 12 | 7.5 | 85 Ohms | TOP=L2:L3=L2/L4:L6=L5/L7:BOTTOM=L7 |
| PE_CLK_100M_DR1_2_R_N | PE_CLK_100M_DR1_2_R-DIFF1 | PAIR | 8 | 6.88 | 5 | 10 | 5 | 12 | 20 | 36 | 12 | 12 | 20 | 12 | 5.13 | 85 Ohms | TOP=L2:L3=L2/L4:L6=L5/L7:BOTTOM=L7 |
| PE_CLK_100M_DR1_2_R_P | PE_CLK_100M_DR1_2_R-DIFF1 | PAIR | 1 | 6.88 | 5 | 10 | 5 | 12 | 20 | 36 | 12 | 12 | 20 | 12 | 5.13 | 85 Ohms | TOP=L2:L3=L2/L4:L6=L5/L7:BOTTOM=L7 |
| PE_CLK_100M_DR1_2_R_P | PE_CLK_100M_DR1_2_R-DIFF1 | PAIR | 2 | 6.5 | 5 | 10 | 5 | 12 | 20 | 25 | 12 | 12 | 20 | 12 | 7.5 | 85 Ohms | TOP=L2:L3=L2/L4:L6=L5/L7:BOTTOM=L7 |
| PE_CLK_100M_DR1_2_R_P | PE_CLK_100M_DR1_2_R-DIFF1 | PAIR | 3 | 6.5 | 5 | 10 | 5 | 12 | 20 | 25 | 12 | 12 | 20 | 12 | 7.5 | 85 Ohms | TOP=L2:L3=L2/L4:L6=L5/L7:BOTTOM=L7 |
| PE_CLK_100M_DR1_2_R_P | PE_CLK_100M_DR1_2_R-DIFF1 | PAIR | 4 | 6.5 | 5 | 10 | 5 | 12 | 20 | 25 | 12 | 12 | 20 | 12 | 7.5 | 85 Ohms | TOP=L2:L3=L2/L4:L6=L5/L7:BOTTOM=L7 |
| PE_CLK_100M_DR1_2_R_P | PE_CLK_100M_DR1_2_R-DIFF1 | PAIR | 5 | 6.5 | 5 | 10 | 5 | 12 | 20 | 25 | 12 | 12 | 20 | 12 | 7.5 | 85 Ohms | TOP=L2:L3=L2/L4:L6=L5/L7:BOTTOM=L7 |
| PE_CLK_100M_DR1_2_R_P | PE_CLK_100M_DR1_2_R-DIFF1 | PAIR | 6 | 6.5 | 5 | 10 | 5 | 12 | 20 | 25 | 12 | 12 | 20 | 12 | 7.5 | 85 Ohms | TOP=L2:L3=L2/L4:L6=L5/L7:BOTTOM=L7 |
| PE_CLK_100M_DR1_2_R_P | PE_CLK_100M_DR1_2_R-DIFF1 | PAIR | 7 | 6.5 | 5 | 10 | 5 | 12 | 20 | 25 | 12 | 12 | 20 | 12 | 7.5 | 85 Ohms | TOP=L2:L3=L2/L4:L6=L5/L7:BOTTOM=L7 |
| PE_CLK_100M_DR1_2_R_P | PE_CLK_100M_DR1_2_R-DIFF1 | PAIR | 8 | 6.88 | 5 | 10 | 5 | 12 | 20 | 36 | 12 | 12 | 20 | 12 | 5.13 | 85 Ohms | TOP=L2:L3=L2/L4:L6=L5/L7:BOTTOM=L7 |
| PE_CLK_100M_DR10_1_R_N | PE_CLK_100M_DR10_1_R-DIFF1 | PAIR | 1 | 6.88 | 5 | 10 | 5 | 12 | 20 | 36 | 12 | 12 | 20 | 12 | 5.13 | 85 Ohms | TOP=L2:L3=L2/L4:L6=L5/L7:BOTTOM=L7 |
| PE_CLK_100M_DR10_1_R_N | PE_CLK_100M_DR10_1_R-DIFF1 | PAIR | 2 | 6.5 | 5 | 10 | 5 | 12 | 20 | 25 | 12 | 12 | 20 | 12 | 7.5 | 85 Ohms | TOP=L2:L3=L2/L4:L6=L5/L7:BOTTOM=L7 |
| PE_CLK_100M_DR10_1_R_N | PE_CLK_100M_DR10_1_R-DIFF1 | PAIR | 3 | 6.5 | 5 | 10 | 5 | 12 | 20 | 25 | 12 | 12 | 20 | 12 | 7.5 | 85 Ohms | TOP=L2:L3=L2/L4:L6=L5/L7:BOTTOM=L7 |
| PE_CLK_100M_DR10_1_R_N | PE_CLK_100M_DR10_1_R-DIFF1 | PAIR | 4 | 6.5 | 5 | 10 | 5 | 12 | 20 | 25 | 12 | 12 | 20 | 12 | 7.5 | 85 Ohms | TOP=L2:L3=L2/L4:L6=L5/L7:BOTTOM=L7 |
| PE_CLK_100M_DR10_1_R_N | PE_CLK_100M_DR10_1_R-DIFF1 | PAIR | 5 | 6.5 | 5 | 10 | 5 | 12 | 20 | 25 | 12 | 12 | 20 | 12 | 7.5 | 85 Ohms | TOP=L2:L3=L2/L4:L6=L5/L7:BOTTOM=L7 |
| PE_CLK_100M_DR10_1_R_N | PE_CLK_100M_DR10_1_R-DIFF1 | PAIR | 6 | 6.5 | 5 | 10 | 5 | 12 | 20 | 25 | 12 | 12 | 20 | 12 | 7.5 | 85 Ohms | TOP=L2:L3=L2/L4:L6=L5/L7:BOTTOM=L7 |
| PE_CLK_100M_DR10_1_R_N | PE_CLK_100M_DR10_1_R-DIFF1 | PAIR | 7 | 6.5 | 5 | 10 | 5 | 12 | 20 | 25 | 12 | 12 | 20 | 12 | 7.5 | 85 Ohms | TOP=L2:L3=L2/L4:L6=L5/L7:BOTTOM=L7 |
| PE_CLK_100M_DR10_1_R_N | PE_CLK_100M_DR10_1_R-DIFF1 | PAIR | 8 | 6.88 | 5 | 10 | 5 | 12 | 20 | 36 | 12 | 12 | 20 | 12 | 5.13 | 85 Ohms | TOP=L2:L3=L2/L4:L6=L5/L7:BOTTOM=L7 |
| PE_CLK_100M_DR10_1_R_P | PE_CLK_100M_DR10_1_R-DIFF1 | PAIR | 1 | 6.88 | 5 | 10 | 5 | 12 | 20 | 36 | 12 | 12 | 20 | 12 | 5.13 | 85 Ohms | TOP=L2:L3=L2/L4:L6=L5/L7:BOTTOM=L7 |
| PE_CLK_100M_DR10_1_R_P | PE_CLK_100M_DR10_1_R-DIFF1 | PAIR | 2 | 6.5 | 5 | 10 | 5 | 12 | 20 | 25 | 12 | 12 | 20 | 12 | 7.5 | 85 Ohms | TOP=L2:L3=L2/L4:L6=L5/L7:BOTTOM=L7 |
| PE_CLK_100M_DR10_1_R_P | PE_CLK_100M_DR10_1_R-DIFF1 | PAIR | 3 | 6.5 | 5 | 10 | 5 | 12 | 20 | 25 | 12 | 12 | 20 | 12 | 7.5 | 85 Ohms | TOP=L2:L3=L2/L4:L6=L5/L7:BOTTOM=L7 |
| PE_CLK_100M_DR10_1_R_P | PE_CLK_100M_DR10_1_R-DIFF1 | PAIR | 4 | 6.5 | 5 | 10 | 5 | 12 | 20 | 25 | 12 | 12 | 20 | 12 | 7.5 | 85 Ohms | TOP=L2:L3=L2/L4:L6=L5/L7:BOTTOM=L7 |
| PE_CLK_100M_DR10_1_R_P | PE_CLK_100M_DR10_1_R-DIFF1 | PAIR | 5 | 6.5 | 5 | 10 | 5 | 12 | 20 | 25 | 12 | 12 | 20 | 12 | 7.5 | 85 Ohms | TOP=L2:L3=L2/L4:L6=L5/L7:BOTTOM=L7 |
| PE_CLK_100M_DR10_1_R_P | PE_CLK_100M_DR10_1_R-DIFF1 | PAIR | 6 | 6.5 | 5 | 10 | 5 | 12 | 20 | 25 | 12 | 12 | 20 | 12 | 7.5 | 85 Ohms | TOP=L2:L3=L2/L4:L6=L5/L7:BOTTOM=L7 |
| PE_CLK_100M_DR10_1_R_P | PE_CLK_100M_DR10_1_R-DIFF1 | PAIR | 7 | 6.5 | 5 | 10 | 5 | 12 | 20 | 25 | 12 | 12 | 20 | 12 | 7.5 | 85 Ohms | TOP=L2:L3=L2/L4:L6=L5/L7:BOTTOM=L7 |
| PE_CLK_100M_DR10_1_R_P | PE_CLK_100M_DR10_1_R-DIFF1 | PAIR | 8 | 6.88 | 5 | 10 | 5 | 12 | 20 | 36 | 12 | 12 | 20 | 12 | 5.13 | 85 Ohms | TOP=L2:L3=L2/L4:L6=L5/L7:BOTTOM=L7 |
| PE_CLK_100M_DR10_2_R_N | PE_CLK_100M_DR10_2_R-DIFF1 | PAIR | 1 | 6.88 | 5 | 10 | 5 | 12 | 20 | 36 | 12 | 12 | 20 | 12 | 5.13 | 85 Ohms | TOP=L2:L3=L2/L4:L6=L5/L7:BOTTOM=L7 |
| PE_CLK_100M_DR10_2_R_N | PE_CLK_100M_DR10_2_R-DIFF1 | PAIR | 2 | 6.5 | 5 | 10 | 5 | 12 | 20 | 25 | 12 | 12 | 20 | 12 | 7.5 | 85 Ohms | TOP=L2:L3=L2/L4:L6=L5/L7:BOTTOM=L7 |
| PE_CLK_100M_DR10_2_R_N | PE_CLK_100M_DR10_2_R-DIFF1 | PAIR | 3 | 6.5 | 5 | 10 | 5 | 12 | 20 | 25 | 12 | 12 | 20 | 12 | 7.5 | 85 Ohms | TOP=L2:L3=L2/L4:L6=L5/L7:BOTTOM=L7 |
| PE_CLK_100M_DR10_2_R_N | PE_CLK_100M_DR10_2_R-DIFF1 | PAIR | 4 | 6.5 | 5 | 10 | 5 | 12 | 20 | 25 | 12 | 12 | 20 | 12 | 7.5 | 85 Ohms | TOP=L2:L3=L2/L4:L6=L5/L7:BOTTOM=L7 |
| PE_CLK_100M_DR10_2_R_N | PE_CLK_100M_DR10_2_R-DIFF1 | PAIR | 5 | 6.5 | 5 | 10 | 5 | 12 | 20 | 25 | 12 | 12 | 20 | 12 | 7.5 | 85 Ohms | TOP=L2:L3=L2/L4:L6=L5/L7:BOTTOM=L7 |
| PE_CLK_100M_DR10_2_R_N | PE_CLK_100M_DR10_2_R-DIFF1 | PAIR | 6 | 6.5 | 5 | 10 | 5 | 12 | 20 | 25 | 12 | 12 | 20 | 12 | 7.5 | 85 Ohms | TOP=L2:L3=L2/L4:L6=L5/L7:BOTTOM=L7 |
| PE_CLK_100M_DR10_2_R_N | PE_CLK_100M_DR10_2_R-DIFF1 | PAIR | 7 | 6.5 | 5 | 10 | 5 | 12 | 20 | 25 | 12 | 12 | 20 | 12 | 7.5 | 85 Ohms | TOP=L2:L3=L2/L4:L6=L5/L7:BOTTOM=L7 |
| PE_CLK_100M_DR10_2_R_N | PE_CLK_100M_DR10_2_R-DIFF1 | PAIR | 8 | 6.88 | 5 | 10 | 5 | 12 | 20 | 36 | 12 | 12 | 20 | 12 | 5.13 | 85 Ohms | TOP=L2:L3=L2/L4:L6=L5/L7:BOTTOM=L7 |
| PE_CLK_100M_DR10_2_R_P | PE_CLK_100M_DR10_2_R-DIFF1 | PAIR | 1 | 6.88 | 5 | 10 | 5 | 12 | 20 | 36 | 12 | 12 | 20 | 12 | 5.13 | 85 Ohms | TOP=L2:L3=L2/L4:L6=L5/L7:BOTTOM=L7 |
| PE_CLK_100M_DR10_2_R_P | PE_CLK_100M_DR10_2_R-DIFF1 | PAIR | 2 | 6.5 | 5 | 10 | 5 | 12 | 20 | 25 | 12 | 12 | 20 | 12 | 7.5 | 85 Ohms | TOP=L2:L3=L2/L4:L6=L5/L7:BOTTOM=L7 |
| PE_CLK_100M_DR10_2_R_P | PE_CLK_100M_DR10_2_R-DIFF1 | PAIR | 3 | 6.5 | 5 | 10 | 5 | 12 | 20 | 25 | 12 | 12 | 20 | 12 | 7.5 | 85 Ohms | TOP=L2:L3=L2/L4:L6=L5/L7:BOTTOM=L7 |
| PE_CLK_100M_DR10_2_R_P | PE_CLK_100M_DR10_2_R-DIFF1 | PAIR | 4 | 6.5 | 5 | 10 | 5 | 12 | 20 | 25 | 12 | 12 | 20 | 12 | 7.5 | 85 Ohms | TOP=L2:L3=L2/L4:L6=L5/L7:BOTTOM=L7 |
| PE_CLK_100M_DR10_2_R_P | PE_CLK_100M_DR10_2_R-DIFF1 | PAIR | 5 | 6.5 | 5 | 10 | 5 | 12 | 20 | 25 | 12 | 12 | 20 | 12 | 7.5 | 85 Ohms | TOP=L2:L3=L2/L4:L6=L5/L7:BOTTOM=L7 |
| PE_CLK_100M_DR10_2_R_P | PE_CLK_100M_DR10_2_R-DIFF1 | PAIR | 6 | 6.5 | 5 | 10 | 5 | 12 | 20 | 25 | 12 | 12 | 20 | 12 | 7.5 | 85 Ohms | TOP=L2:L3=L2/L4:L6=L5/L7:BOTTOM=L7 |
| PE_CLK_100M_DR10_2_R_P | PE_CLK_100M_DR10_2_R-DIFF1 | PAIR | 7 | 6.5 | 5 | 10 | 5 | 12 | 20 | 25 | 12 | 12 | 20 | 12 | 7.5 | 85 Ohms | TOP=L2:L3=L2/L4:L6=L5/L7:BOTTOM=L7 |
| PE_CLK_100M_DR10_2_R_P | PE_CLK_100M_DR10_2_R-DIFF1 | PAIR | 8 | 6.88 | 5 | 10 | 5 | 12 | 20 | 36 | 12 | 12 | 20 | 12 | 5.13 | 85 Ohms | TOP=L2:L3=L2/L4:L6=L5/L7:BOTTOM=L7 |
| PE_CLK_100M_DR11_1_R_N | PE_CLK_100M_DR11_1_R-DIFF1 | PAIR | 1 | 6.88 | 5 | 10 | 5 | 12 | 20 | 36 | 12 | 12 | 20 | 12 | 5.13 | 85 Ohms | TOP=L2:L3=L2/L4:L6=L5/L7:BOTTOM=L7 |
| PE_CLK_100M_DR11_1_R_N | PE_CLK_100M_DR11_1_R-DIFF1 | PAIR | 2 | 6.5 | 5 | 10 | 5 | 12 | 20 | 25 | 12 | 12 | 20 | 12 | 7.5 | 85 Ohms | TOP=L2:L3=L2/L4:L6=L5/L7:BOTTOM=L7 |
| PE_CLK_100M_DR11_1_R_N | PE_CLK_100M_DR11_1_R-DIFF1 | PAIR | 3 | 6.5 | 5 | 10 | 5 | 12 | 20 | 25 | 12 | 12 | 20 | 12 | 7.5 | 85 Ohms | TOP=L2:L3=L2/L4:L6=L5/L7:BOTTOM=L7 |
| PE_CLK_100M_DR11_1_R_N | PE_CLK_100M_DR11_1_R-DIFF1 | PAIR | 4 | 6.5 | 5 | 10 | 5 | 12 | 20 | 25 | 12 | 12 | 20 | 12 | 7.5 | 85 Ohms | TOP=L2:L3=L2/L4:L6=L5/L7:BOTTOM=L7 |
| PE_CLK_100M_DR11_1_R_N | PE_CLK_100M_DR11_1_R-DIFF1 | PAIR | 5 | 6.5 | 5 | 10 | 5 | 12 | 20 | 25 | 12 | 12 | 20 | 12 | 7.5 | 85 Ohms | TOP=L2:L3=L2/L4:L6=L5/L7:BOTTOM=L7 |
| PE_CLK_100M_DR11_1_R_N | PE_CLK_100M_DR11_1_R-DIFF1 | PAIR | 6 | 6.5 | 5 | 10 | 5 | 12 | 20 | 25 | 12 | 12 | 20 | 12 | 7.5 | 85 Ohms | TOP=L2:L3=L2/L4:L6=L5/L7:BOTTOM=L7 |
| PE_CLK_100M_DR11_1_R_N | PE_CLK_100M_DR11_1_R-DIFF1 | PAIR | 7 | 6.5 | 5 | 10 | 5 | 12 | 20 | 25 | 12 | 12 | 20 | 12 | 7.5 | 85 Ohms | TOP=L2:L3=L2/L4:L6=L5/L7:BOTTOM=L7 |
| PE_CLK_100M_DR11_1_R_N | PE_CLK_100M_DR11_1_R-DIFF1 | PAIR | 8 | 6.88 | 5 | 10 | 5 | 12 | 20 | 36 | 12 | 12 | 20 | 12 | 5.13 | 85 Ohms | TOP=L2:L3=L2/L4:L6=L5/L7:BOTTOM=L7 |
| PE_CLK_100M_DR11_1_R_P | PE_CLK_100M_DR11_1_R-DIFF1 | PAIR | 1 | 6.88 | 5 | 10 | 5 | 12 | 20 | 36 | 12 | 12 | 20 | 12 | 5.13 | 85 Ohms | TOP=L2:L3=L2/L4:L6=L5/L7:BOTTOM=L7 |
| PE_CLK_100M_DR11_1_R_P | PE_CLK_100M_DR11_1_R-DIFF1 | PAIR | 2 | 6.5 | 5 | 10 | 5 | 12 | 20 | 25 | 12 | 12 | 20 | 12 | 7.5 | 85 Ohms | TOP=L2:L3=L2/L4:L6=L5/L7:BOTTOM=L7 |
| PE_CLK_100M_DR11_1_R_P | PE_CLK_100M_DR11_1_R-DIFF1 | PAIR | 3 | 6.5 | 5 | 10 | 5 | 12 | 20 | 25 | 12 | 12 | 20 | 12 | 7.5 | 85 Ohms | TOP=L2:L3=L2/L4:L6=L5/L7:BOTTOM=L7 |
| PE_CLK_100M_DR11_1_R_P | PE_CLK_100M_DR11_1_R-DIFF1 | PAIR | 4 | 6.5 | 5 | 10 | 5 | 12 | 20 | 25 | 12 | 12 | 20 | 12 | 7.5 | 85 Ohms | TOP=L2:L3=L2/L4:L6=L5/L7:BOTTOM=L7 |
| PE_CLK_100M_DR11_1_R_P | PE_CLK_100M_DR11_1_R-DIFF1 | PAIR | 5 | 6.5 | 5 | 10 | 5 | 12 | 20 | 25 | 12 | 12 | 20 | 12 | 7.5 | 85 Ohms | TOP=L2:L3=L2/L4:L6=L5/L7:BOTTOM=L7 |
| PE_CLK_100M_DR11_1_R_P | PE_CLK_100M_DR11_1_R-DIFF1 | PAIR | 6 | 6.5 | 5 | 10 | 5 | 12 | 20 | 25 | 12 | 12 | 20 | 12 | 7.5 | 85 Ohms | TOP=L2:L3=L2/L4:L6=L5/L7:BOTTOM=L7 |
| PE_CLK_100M_DR11_1_R_P | PE_CLK_100M_DR11_1_R-DIFF1 | PAIR | 7 | 6.5 | 5 | 10 | 5 | 12 | 20 | 25 | 12 | 12 | 20 | 12 | 7.5 | 85 Ohms | TOP=L2:L3=L2/L4:L6=L5/L7:BOTTOM=L7 |
| PE_CLK_100M_DR11_1_R_P | PE_CLK_100M_DR11_1_R-DIFF1 | PAIR | 8 | 6.88 | 5 | 10 | 5 | 12 | 20 | 36 | 12 | 12 | 20 | 12 | 5.13 | 85 Ohms | TOP=L2:L3=L2/L4:L6=L5/L7:BOTTOM=L7 |
| PE_CLK_100M_DR11_2_R_N | PE_CLK_100M_DR11_2_R-DIFF1 | PAIR | 1 | 6.88 | 5 | 10 | 5 | 12 | 20 | 36 | 12 | 12 | 20 | 12 | 5.13 | 85 Ohms | TOP=L2:L3=L2/L4:L6=L5/L7:BOTTOM=L7 |
| PE_CLK_100M_DR11_2_R_N | PE_CLK_100M_DR11_2_R-DIFF1 | PAIR | 2 | 6.5 | 5 | 10 | 5 | 12 | 20 | 25 | 12 | 12 | 20 | 12 | 7.5 | 85 Ohms | TOP=L2:L3=L2/L4:L6=L5/L7:BOTTOM=L7 |
| PE_CLK_100M_DR11_2_R_N | PE_CLK_100M_DR11_2_R-DIFF1 | PAIR | 3 | 6.5 | 5 | 10 | 5 | 12 | 20 | 25 | 12 | 12 | 20 | 12 | 7.5 | 85 Ohms | TOP=L2:L3=L2/L4:L6=L5/L7:BOTTOM=L7 |
| PE_CLK_100M_DR11_2_R_N | PE_CLK_100M_DR11_2_R-DIFF1 | PAIR | 4 | 6.5 | 5 | 10 | 5 | 12 | 20 | 25 | 12 | 12 | 20 | 12 | 7.5 | 85 Ohms | TOP=L2:L3=L2/L4:L6=L5/L7:BOTTOM=L7 |
| PE_CLK_100M_DR11_2_R_N | PE_CLK_100M_DR11_2_R-DIFF1 | PAIR | 5 | 6.5 | 5 | 10 | 5 | 12 | 20 | 25 | 12 | 12 | 20 | 12 | 7.5 | 85 Ohms | TOP=L2:L3=L2/L4:L6=L5/L7:BOTTOM=L7 |
| PE_CLK_100M_DR11_2_R_N | PE_CLK_100M_DR11_2_R-DIFF1 | PAIR | 6 | 6.5 | 5 | 10 | 5 | 12 | 20 | 25 | 12 | 12 | 20 | 12 | 7.5 | 85 Ohms | TOP=L2:L3=L2/L4:L6=L5/L7:BOTTOM=L7 |
| PE_CLK_100M_DR11_2_R_N | PE_CLK_100M_DR11_2_R-DIFF1 | PAIR | 7 | 6.5 | 5 | 10 | 5 | 12 | 20 | 25 | 12 | 12 | 20 | 12 | 7.5 | 85 Ohms | TOP=L2:L3=L2/L4:L6=L5/L7:BOTTOM=L7 |
| PE_CLK_100M_DR11_2_R_N | PE_CLK_100M_DR11_2_R-DIFF1 | PAIR | 8 | 6.88 | 5 | 10 | 5 | 12 | 20 | 36 | 12 | 12 | 20 | 12 | 5.13 | 85 Ohms | TOP=L2:L3=L2/L4:L6=L5/L7:BOTTOM=L7 |
| PE_CLK_100M_DR11_2_R_P | PE_CLK_100M_DR11_2_R-DIFF1 | PAIR | 1 | 6.88 | 5 | 10 | 5 | 12 | 20 | 36 | 12 | 12 | 20 | 12 | 5.13 | 85 Ohms | TOP=L2:L3=L2/L4:L6=L5/L7:BOTTOM=L7 |
| PE_CLK_100M_DR11_2_R_P | PE_CLK_100M_DR11_2_R-DIFF1 | PAIR | 2 | 6.5 | 5 | 10 | 5 | 12 | 20 | 25 | 12 | 12 | 20 | 12 | 7.5 | 85 Ohms | TOP=L2:L3=L2/L4:L6=L5/L7:BOTTOM=L7 |
| PE_CLK_100M_DR11_2_R_P | PE_CLK_100M_DR11_2_R-DIFF1 | PAIR | 3 | 6.5 | 5 | 10 | 5 | 12 | 20 | 25 | 12 | 12 | 20 | 12 | 7.5 | 85 Ohms | TOP=L2:L3=L2/L4:L6=L5/L7:BOTTOM=L7 |
| PE_CLK_100M_DR11_2_R_P | PE_CLK_100M_DR11_2_R-DIFF1 | PAIR | 4 | 6.5 | 5 | 10 | 5 | 12 | 20 | 25 | 12 | 12 | 20 | 12 | 7.5 | 85 Ohms | TOP=L2:L3=L2/L4:L6=L5/L7:BOTTOM=L7 |
| PE_CLK_100M_DR11_2_R_P | PE_CLK_100M_DR11_2_R-DIFF1 | PAIR | 5 | 6.5 | 5 | 10 | 5 | 12 | 20 | 25 | 12 | 12 | 20 | 12 | 7.5 | 85 Ohms | TOP=L2:L3=L2/L4:L6=L5/L7:BOTTOM=L7 |
| PE_CLK_100M_DR11_2_R_P | PE_CLK_100M_DR11_2_R-DIFF1 | PAIR | 6 | 6.5 | 5 | 10 | 5 | 12 | 20 | 25 | 12 | 12 | 20 | 12 | 7.5 | 85 Ohms | TOP=L2:L3=L2/L4:L6=L5/L7:BOTTOM=L7 |
| PE_CLK_100M_DR11_2_R_P | PE_CLK_100M_DR11_2_R-DIFF1 | PAIR | 7 | 6.5 | 5 | 10 | 5 | 12 | 20 | 25 | 12 | 12 | 20 | 12 | 7.5 | 85 Ohms | TOP=L2:L3=L2/L4:L6=L5/L7:BOTTOM=L7 |
| PE_CLK_100M_DR11_2_R_P | PE_CLK_100M_DR11_2_R-DIFF1 | PAIR | 8 | 6.88 | 5 | 10 | 5 | 12 | 20 | 36 | 12 | 12 | 20 | 12 | 5.13 | 85 Ohms | TOP=L2:L3=L2/L4:L6=L5/L7:BOTTOM=L7 |
| PE_CLK_100M_DR12_1_R_N | PE_CLK_100M_DR12_1_R-DIFF1 | PAIR | 1 | 6.88 | 5 | 10 | 5 | 12 | 20 | 36 | 12 | 12 | 20 | 12 | 5.13 | 85 Ohms | TOP=L2:L3=L2/L4:L6=L5/L7:BOTTOM=L7 |
| PE_CLK_100M_DR12_1_R_N | PE_CLK_100M_DR12_1_R-DIFF1 | PAIR | 2 | 6.5 | 5 | 10 | 5 | 12 | 20 | 25 | 12 | 12 | 20 | 12 | 7.5 | 85 Ohms | TOP=L2:L3=L2/L4:L6=L5/L7:BOTTOM=L7 |
| PE_CLK_100M_DR12_1_R_N | PE_CLK_100M_DR12_1_R-DIFF1 | PAIR | 3 | 6.5 | 5 | 10 | 5 | 12 | 20 | 25 | 12 | 12 | 20 | 12 | 7.5 | 85 Ohms | TOP=L2:L3=L2/L4:L6=L5/L7:BOTTOM=L7 |
| PE_CLK_100M_DR12_1_R_N | PE_CLK_100M_DR12_1_R-DIFF1 | PAIR | 4 | 6.5 | 5 | 10 | 5 | 12 | 20 | 25 | 12 | 12 | 20 | 12 | 7.5 | 85 Ohms | TOP=L2:L3=L2/L4:L6=L5/L7:BOTTOM=L7 |
| PE_CLK_100M_DR12_1_R_N | PE_CLK_100M_DR12_1_R-DIFF1 | PAIR | 5 | 6.5 | 5 | 10 | 5 | 12 | 20 | 25 | 12 | 12 | 20 | 12 | 7.5 | 85 Ohms | TOP=L2:L3=L2/L4:L6=L5/L7:BOTTOM=L7 |
| PE_CLK_100M_DR12_1_R_N | PE_CLK_100M_DR12_1_R-DIFF1 | PAIR | 6 | 6.5 | 5 | 10 | 5 | 12 | 20 | 25 | 12 | 12 | 20 | 12 | 7.5 | 85 Ohms | TOP=L2:L3=L2/L4:L6=L5/L7:BOTTOM=L7 |
| PE_CLK_100M_DR12_1_R_N | PE_CLK_100M_DR12_1_R-DIFF1 | PAIR | 7 | 6.5 | 5 | 10 | 5 | 12 | 20 | 25 | 12 | 12 | 20 | 12 | 7.5 | 85 Ohms | TOP=L2:L3=L2/L4:L6=L5/L7:BOTTOM=L7 |
| PE_CLK_100M_DR12_1_R_N | PE_CLK_100M_DR12_1_R-DIFF1 | PAIR | 8 | 6.88 | 5 | 10 | 5 | 12 | 20 | 36 | 12 | 12 | 20 | 12 | 5.13 | 85 Ohms | TOP=L2:L3=L2/L4:L6=L5/L7:BOTTOM=L7 |
| PE_CLK_100M_DR12_1_R_P | PE_CLK_100M_DR12_1_R-DIFF1 | PAIR | 1 | 6.88 | 5 | 10 | 5 | 12 | 20 | 36 | 12 | 12 | 20 | 12 | 5.13 | 85 Ohms | TOP=L2:L3=L2/L4:L6=L5/L7:BOTTOM=L7 |
| PE_CLK_100M_DR12_1_R_P | PE_CLK_100M_DR12_1_R-DIFF1 | PAIR | 2 | 6.5 | 5 | 10 | 5 | 12 | 20 | 25 | 12 | 12 | 20 | 12 | 7.5 | 85 Ohms | TOP=L2:L3=L2/L4:L6=L5/L7:BOTTOM=L7 |
| PE_CLK_100M_DR12_1_R_P | PE_CLK_100M_DR12_1_R-DIFF1 | PAIR | 3 | 6.5 | 5 | 10 | 5 | 12 | 20 | 25 | 12 | 12 | 20 | 12 | 7.5 | 85 Ohms | TOP=L2:L3=L2/L4:L6=L5/L7:BOTTOM=L7 |
| PE_CLK_100M_DR12_1_R_P | PE_CLK_100M_DR12_1_R-DIFF1 | PAIR | 4 | 6.5 | 5 | 10 | 5 | 12 | 20 | 25 | 12 | 12 | 20 | 12 | 7.5 | 85 Ohms | TOP=L2:L3=L2/L4:L6=L5/L7:BOTTOM=L7 |
| PE_CLK_100M_DR12_1_R_P | PE_CLK_100M_DR12_1_R-DIFF1 | PAIR | 5 | 6.5 | 5 | 10 | 5 | 12 | 20 | 25 | 12 | 12 | 20 | 12 | 7.5 | 85 Ohms | TOP=L2:L3=L2/L4:L6=L5/L7:BOTTOM=L7 |
| PE_CLK_100M_DR12_1_R_P | PE_CLK_100M_DR12_1_R-DIFF1 | PAIR | 6 | 6.5 | 5 | 10 | 5 | 12 | 20 | 25 | 12 | 12 | 20 | 12 | 7.5 | 85 Ohms | TOP=L2:L3=L2/L4:L6=L5/L7:BOTTOM=L7 |
| PE_CLK_100M_DR12_1_R_P | PE_CLK_100M_DR12_1_R-DIFF1 | PAIR | 7 | 6.5 | 5 | 10 | 5 | 12 | 20 | 25 | 12 | 12 | 20 | 12 | 7.5 | 85 Ohms | TOP=L2:L3=L2/L4:L6=L5/L7:BOTTOM=L7 |
| PE_CLK_100M_DR12_1_R_P | PE_CLK_100M_DR12_1_R-DIFF1 | PAIR | 8 | 6.88 | 5 | 10 | 5 | 12 | 20 | 36 | 12 | 12 | 20 | 12 | 5.13 | 85 Ohms | TOP=L2:L3=L2/L4:L6=L5/L7:BOTTOM=L7 |
| PE_CLK_100M_DR12_2_R_N | PE_CLK_100M_DR12_2_R-DIFF1 | PAIR | 1 | 6.88 | 5 | 10 | 5 | 12 | 20 | 36 | 12 | 12 | 20 | 12 | 5.13 | 85 Ohms | TOP=L2:L3=L2/L4:L6=L5/L7:BOTTOM=L7 |
| PE_CLK_100M_DR12_2_R_N | PE_CLK_100M_DR12_2_R-DIFF1 | PAIR | 2 | 6.5 | 5 | 10 | 5 | 12 | 20 | 25 | 12 | 12 | 20 | 12 | 7.5 | 85 Ohms | TOP=L2:L3=L2/L4:L6=L5/L7:BOTTOM=L7 |
| PE_CLK_100M_DR12_2_R_N | PE_CLK_100M_DR12_2_R-DIFF1 | PAIR | 3 | 6.5 | 5 | 10 | 5 | 12 | 20 | 25 | 12 | 12 | 20 | 12 | 7.5 | 85 Ohms | TOP=L2:L3=L2/L4:L6=L5/L7:BOTTOM=L7 |
| PE_CLK_100M_DR12_2_R_N | PE_CLK_100M_DR12_2_R-DIFF1 | PAIR | 4 | 6.5 | 5 | 10 | 5 | 12 | 20 | 25 | 12 | 12 | 20 | 12 | 7.5 | 85 Ohms | TOP=L2:L3=L2/L4:L6=L5/L7:BOTTOM=L7 |
| PE_CLK_100M_DR12_2_R_N | PE_CLK_100M_DR12_2_R-DIFF1 | PAIR | 5 | 6.5 | 5 | 10 | 5 | 12 | 20 | 25 | 12 | 12 | 20 | 12 | 7.5 | 85 Ohms | TOP=L2:L3=L2/L4:L6=L5/L7:BOTTOM=L7 |
| PE_CLK_100M_DR12_2_R_N | PE_CLK_100M_DR12_2_R-DIFF1 | PAIR | 6 | 6.5 | 5 | 10 | 5 | 12 | 20 | 25 | 12 | 12 | 20 | 12 | 7.5 | 85 Ohms | TOP=L2:L3=L2/L4:L6=L5/L7:BOTTOM=L7 |
| PE_CLK_100M_DR12_2_R_N | PE_CLK_100M_DR12_2_R-DIFF1 | PAIR | 7 | 6.5 | 5 | 10 | 5 | 12 | 20 | 25 | 12 | 12 | 20 | 12 | 7.5 | 85 Ohms | TOP=L2:L3=L2/L4:L6=L5/L7:BOTTOM=L7 |
| PE_CLK_100M_DR12_2_R_N | PE_CLK_100M_DR12_2_R-DIFF1 | PAIR | 8 | 6.88 | 5 | 10 | 5 | 12 | 20 | 36 | 12 | 12 | 20 | 12 | 5.13 | 85 Ohms | TOP=L2:L3=L2/L4:L6=L5/L7:BOTTOM=L7 |
| PE_CLK_100M_DR12_2_R_P | PE_CLK_100M_DR12_2_R-DIFF1 | PAIR | 1 | 6.88 | 5 | 10 | 5 | 12 | 20 | 36 | 12 | 12 | 20 | 12 | 5.13 | 85 Ohms | TOP=L2:L3=L2/L4:L6=L5/L7:BOTTOM=L7 |
| PE_CLK_100M_DR12_2_R_P | PE_CLK_100M_DR12_2_R-DIFF1 | PAIR | 2 | 6.5 | 5 | 10 | 5 | 12 | 20 | 25 | 12 | 12 | 20 | 12 | 7.5 | 85 Ohms | TOP=L2:L3=L2/L4:L6=L5/L7:BOTTOM=L7 |
| PE_CLK_100M_DR12_2_R_P | PE_CLK_100M_DR12_2_R-DIFF1 | PAIR | 3 | 6.5 | 5 | 10 | 5 | 12 | 20 | 25 | 12 | 12 | 20 | 12 | 7.5 | 85 Ohms | TOP=L2:L3=L2/L4:L6=L5/L7:BOTTOM=L7 |
| PE_CLK_100M_DR12_2_R_P | PE_CLK_100M_DR12_2_R-DIFF1 | PAIR | 4 | 6.5 | 5 | 10 | 5 | 12 | 20 | 25 | 12 | 12 | 20 | 12 | 7.5 | 85 Ohms | TOP=L2:L3=L2/L4:L6=L5/L7:BOTTOM=L7 |
| PE_CLK_100M_DR12_2_R_P | PE_CLK_100M_DR12_2_R-DIFF1 | PAIR | 5 | 6.5 | 5 | 10 | 5 | 12 | 20 | 25 | 12 | 12 | 20 | 12 | 7.5 | 85 Ohms | TOP=L2:L3=L2/L4:L6=L5/L7:BOTTOM=L7 |
| PE_CLK_100M_DR12_2_R_P | PE_CLK_100M_DR12_2_R-DIFF1 | PAIR | 6 | 6.5 | 5 | 10 | 5 | 12 | 20 | 25 | 12 | 12 | 20 | 12 | 7.5 | 85 Ohms | TOP=L2:L3=L2/L4:L6=L5/L7:BOTTOM=L7 |
| PE_CLK_100M_DR12_2_R_P | PE_CLK_100M_DR12_2_R-DIFF1 | PAIR | 7 | 6.5 | 5 | 10 | 5 | 12 | 20 | 25 | 12 | 12 | 20 | 12 | 7.5 | 85 Ohms | TOP=L2:L3=L2/L4:L6=L5/L7:BOTTOM=L7 |
| PE_CLK_100M_DR12_2_R_P | PE_CLK_100M_DR12_2_R-DIFF1 | PAIR | 8 | 6.88 | 5 | 10 | 5 | 12 | 20 | 36 | 12 | 12 | 20 | 12 | 5.13 | 85 Ohms | TOP=L2:L3=L2/L4:L6=L5/L7:BOTTOM=L7 |
| PE_CLK_100M_DR13_1_R_N | PE_CLK_100M_DR13_1_R-DIFF1 | PAIR | 1 | 6.88 | 5 | 10 | 5 | 12 | 20 | 36 | 12 | 12 | 20 | 12 | 5.13 | 85 Ohms | TOP=L2:L3=L2/L4:L6=L5/L7:BOTTOM=L7 |
| PE_CLK_100M_DR13_1_R_N | PE_CLK_100M_DR13_1_R-DIFF1 | PAIR | 2 | 6.5 | 5 | 10 | 5 | 12 | 20 | 25 | 12 | 12 | 20 | 12 | 7.5 | 85 Ohms | TOP=L2:L3=L2/L4:L6=L5/L7:BOTTOM=L7 |
| PE_CLK_100M_DR13_1_R_N | PE_CLK_100M_DR13_1_R-DIFF1 | PAIR | 3 | 6.5 | 5 | 10 | 5 | 12 | 20 | 25 | 12 | 12 | 20 | 12 | 7.5 | 85 Ohms | TOP=L2:L3=L2/L4:L6=L5/L7:BOTTOM=L7 |
| PE_CLK_100M_DR13_1_R_N | PE_CLK_100M_DR13_1_R-DIFF1 | PAIR | 4 | 6.5 | 5 | 10 | 5 | 12 | 20 | 25 | 12 | 12 | 20 | 12 | 7.5 | 85 Ohms | TOP=L2:L3=L2/L4:L6=L5/L7:BOTTOM=L7 |
| PE_CLK_100M_DR13_1_R_N | PE_CLK_100M_DR13_1_R-DIFF1 | PAIR | 5 | 6.5 | 5 | 10 | 5 | 12 | 20 | 25 | 12 | 12 | 20 | 12 | 7.5 | 85 Ohms | TOP=L2:L3=L2/L4:L6=L5/L7:BOTTOM=L7 |
| PE_CLK_100M_DR13_1_R_N | PE_CLK_100M_DR13_1_R-DIFF1 | PAIR | 6 | 6.5 | 5 | 10 | 5 | 12 | 20 | 25 | 12 | 12 | 20 | 12 | 7.5 | 85 Ohms | TOP=L2:L3=L2/L4:L6=L5/L7:BOTTOM=L7 |
| PE_CLK_100M_DR13_1_R_N | PE_CLK_100M_DR13_1_R-DIFF1 | PAIR | 7 | 6.5 | 5 | 10 | 5 | 12 | 20 | 25 | 12 | 12 | 20 | 12 | 7.5 | 85 Ohms | TOP=L2:L3=L2/L4:L6=L5/L7:BOTTOM=L7 |
| PE_CLK_100M_DR13_1_R_N | PE_CLK_100M_DR13_1_R-DIFF1 | PAIR | 8 | 6.88 | 5 | 10 | 5 | 12 | 20 | 36 | 12 | 12 | 20 | 12 | 5.13 | 85 Ohms | TOP=L2:L3=L2/L4:L6=L5/L7:BOTTOM=L7 |
| PE_CLK_100M_DR13_1_R_P | PE_CLK_100M_DR13_1_R-DIFF1 | PAIR | 1 | 6.88 | 5 | 10 | 5 | 12 | 20 | 36 | 12 | 12 | 20 | 12 | 5.13 | 85 Ohms | TOP=L2:L3=L2/L4:L6=L5/L7:BOTTOM=L7 |
| PE_CLK_100M_DR13_1_R_P | PE_CLK_100M_DR13_1_R-DIFF1 | PAIR | 2 | 6.5 | 5 | 10 | 5 | 12 | 20 | 25 | 12 | 12 | 20 | 12 | 7.5 | 85 Ohms | TOP=L2:L3=L2/L4:L6=L5/L7:BOTTOM=L7 |
| PE_CLK_100M_DR13_1_R_P | PE_CLK_100M_DR13_1_R-DIFF1 | PAIR | 3 | 6.5 | 5 | 10 | 5 | 12 | 20 | 25 | 12 | 12 | 20 | 12 | 7.5 | 85 Ohms | TOP=L2:L3=L2/L4:L6=L5/L7:BOTTOM=L7 |
| PE_CLK_100M_DR13_1_R_P | PE_CLK_100M_DR13_1_R-DIFF1 | PAIR | 4 | 6.5 | 5 | 10 | 5 | 12 | 20 | 25 | 12 | 12 | 20 | 12 | 7.5 | 85 Ohms | TOP=L2:L3=L2/L4:L6=L5/L7:BOTTOM=L7 |
| PE_CLK_100M_DR13_1_R_P | PE_CLK_100M_DR13_1_R-DIFF1 | PAIR | 5 | 6.5 | 5 | 10 | 5 | 12 | 20 | 25 | 12 | 12 | 20 | 12 | 7.5 | 85 Ohms | TOP=L2:L3=L2/L4:L6=L5/L7:BOTTOM=L7 |
| PE_CLK_100M_DR13_1_R_P | PE_CLK_100M_DR13_1_R-DIFF1 | PAIR | 6 | 6.5 | 5 | 10 | 5 | 12 | 20 | 25 | 12 | 12 | 20 | 12 | 7.5 | 85 Ohms | TOP=L2:L3=L2/L4:L6=L5/L7:BOTTOM=L7 |
| PE_CLK_100M_DR13_1_R_P | PE_CLK_100M_DR13_1_R-DIFF1 | PAIR | 7 | 6.5 | 5 | 10 | 5 | 12 | 20 | 25 | 12 | 12 | 20 | 12 | 7.5 | 85 Ohms | TOP=L2:L3=L2/L4:L6=L5/L7:BOTTOM=L7 |
| PE_CLK_100M_DR13_1_R_P | PE_CLK_100M_DR13_1_R-DIFF1 | PAIR | 8 | 6.88 | 5 | 10 | 5 | 12 | 20 | 36 | 12 | 12 | 20 | 12 | 5.13 | 85 Ohms | TOP=L2:L3=L2/L4:L6=L5/L7:BOTTOM=L7 |
| PE_CLK_100M_DR13_2_R_N | PE_CLK_100M_DR13_2_R-DIFF1 | PAIR | 1 | 6.88 | 5 | 10 | 5 | 12 | 20 | 36 | 12 | 12 | 20 | 12 | 5.13 | 85 Ohms | TOP=L2:L3=L2/L4:L6=L5/L7:BOTTOM=L7 |
| PE_CLK_100M_DR13_2_R_N | PE_CLK_100M_DR13_2_R-DIFF1 | PAIR | 2 | 6.5 | 5 | 10 | 5 | 12 | 20 | 25 | 12 | 12 | 20 | 12 | 7.5 | 85 Ohms | TOP=L2:L3=L2/L4:L6=L5/L7:BOTTOM=L7 |
| PE_CLK_100M_DR13_2_R_N | PE_CLK_100M_DR13_2_R-DIFF1 | PAIR | 3 | 6.5 | 5 | 10 | 5 | 12 | 20 | 25 | 12 | 12 | 20 | 12 | 7.5 | 85 Ohms | TOP=L2:L3=L2/L4:L6=L5/L7:BOTTOM=L7 |
| PE_CLK_100M_DR13_2_R_N | PE_CLK_100M_DR13_2_R-DIFF1 | PAIR | 4 | 6.5 | 5 | 10 | 5 | 12 | 20 | 25 | 12 | 12 | 20 | 12 | 7.5 | 85 Ohms | TOP=L2:L3=L2/L4:L6=L5/L7:BOTTOM=L7 |
| PE_CLK_100M_DR13_2_R_N | PE_CLK_100M_DR13_2_R-DIFF1 | PAIR | 5 | 6.5 | 5 | 10 | 5 | 12 | 20 | 25 | 12 | 12 | 20 | 12 | 7.5 | 85 Ohms | TOP=L2:L3=L2/L4:L6=L5/L7:BOTTOM=L7 |
| PE_CLK_100M_DR13_2_R_N | PE_CLK_100M_DR13_2_R-DIFF1 | PAIR | 6 | 6.5 | 5 | 10 | 5 | 12 | 20 | 25 | 12 | 12 | 20 | 12 | 7.5 | 85 Ohms | TOP=L2:L3=L2/L4:L6=L5/L7:BOTTOM=L7 |
| PE_CLK_100M_DR13_2_R_N | PE_CLK_100M_DR13_2_R-DIFF1 | PAIR | 7 | 6.5 | 5 | 10 | 5 | 12 | 20 | 25 | 12 | 12 | 20 | 12 | 7.5 | 85 Ohms | TOP=L2:L3=L2/L4:L6=L5/L7:BOTTOM=L7 |
| PE_CLK_100M_DR13_2_R_N | PE_CLK_100M_DR13_2_R-DIFF1 | PAIR | 8 | 6.88 | 5 | 10 | 5 | 12 | 20 | 36 | 12 | 12 | 20 | 12 | 5.13 | 85 Ohms | TOP=L2:L3=L2/L4:L6=L5/L7:BOTTOM=L7 |
| PE_CLK_100M_DR13_2_R_P | PE_CLK_100M_DR13_2_R-DIFF1 | PAIR | 1 | 6.88 | 5 | 10 | 5 | 12 | 20 | 36 | 12 | 12 | 20 | 12 | 5.13 | 85 Ohms | TOP=L2:L3=L2/L4:L6=L5/L7:BOTTOM=L7 |
| PE_CLK_100M_DR13_2_R_P | PE_CLK_100M_DR13_2_R-DIFF1 | PAIR | 2 | 6.5 | 5 | 10 | 5 | 12 | 20 | 25 | 12 | 12 | 20 | 12 | 7.5 | 85 Ohms | TOP=L2:L3=L2/L4:L6=L5/L7:BOTTOM=L7 |
| PE_CLK_100M_DR13_2_R_P | PE_CLK_100M_DR13_2_R-DIFF1 | PAIR | 3 | 6.5 | 5 | 10 | 5 | 12 | 20 | 25 | 12 | 12 | 20 | 12 | 7.5 | 85 Ohms | TOP=L2:L3=L2/L4:L6=L5/L7:BOTTOM=L7 |
| PE_CLK_100M_DR13_2_R_P | PE_CLK_100M_DR13_2_R-DIFF1 | PAIR | 4 | 6.5 | 5 | 10 | 5 | 12 | 20 | 25 | 12 | 12 | 20 | 12 | 7.5 | 85 Ohms | TOP=L2:L3=L2/L4:L6=L5/L7:BOTTOM=L7 |
| PE_CLK_100M_DR13_2_R_P | PE_CLK_100M_DR13_2_R-DIFF1 | PAIR | 5 | 6.5 | 5 | 10 | 5 | 12 | 20 | 25 | 12 | 12 | 20 | 12 | 7.5 | 85 Ohms | TOP=L2:L3=L2/L4:L6=L5/L7:BOTTOM=L7 |
| PE_CLK_100M_DR13_2_R_P | PE_CLK_100M_DR13_2_R-DIFF1 | PAIR | 6 | 6.5 | 5 | 10 | 5 | 12 | 20 | 25 | 12 | 12 | 20 | 12 | 7.5 | 85 Ohms | TOP=L2:L3=L2/L4:L6=L5/L7:BOTTOM=L7 |
| PE_CLK_100M_DR13_2_R_P | PE_CLK_100M_DR13_2_R-DIFF1 | PAIR | 7 | 6.5 | 5 | 10 | 5 | 12 | 20 | 25 | 12 | 12 | 20 | 12 | 7.5 | 85 Ohms | TOP=L2:L3=L2/L4:L6=L5/L7:BOTTOM=L7 |
| PE_CLK_100M_DR13_2_R_P | PE_CLK_100M_DR13_2_R-DIFF1 | PAIR | 8 | 6.88 | 5 | 10 | 5 | 12 | 20 | 36 | 12 | 12 | 20 | 12 | 5.13 | 85 Ohms | TOP=L2:L3=L2/L4:L6=L5/L7:BOTTOM=L7 |
| PE_CLK_100M_DR14_1_R_N | PE_CLK_100M_DR14_1_R-DIFF1 | PAIR | 1 | 6.88 | 5 | 10 | 5 | 12 | 20 | 36 | 12 | 12 | 20 | 12 | 5.13 | 85 Ohms | TOP=L2:L3=L2/L4:L6=L5/L7:BOTTOM=L7 |
| PE_CLK_100M_DR14_1_R_N | PE_CLK_100M_DR14_1_R-DIFF1 | PAIR | 2 | 6.5 | 5 | 10 | 5 | 12 | 20 | 25 | 12 | 12 | 20 | 12 | 7.5 | 85 Ohms | TOP=L2:L3=L2/L4:L6=L5/L7:BOTTOM=L7 |
| PE_CLK_100M_DR14_1_R_N | PE_CLK_100M_DR14_1_R-DIFF1 | PAIR | 3 | 6.5 | 5 | 10 | 5 | 12 | 20 | 25 | 12 | 12 | 20 | 12 | 7.5 | 85 Ohms | TOP=L2:L3=L2/L4:L6=L5/L7:BOTTOM=L7 |
| PE_CLK_100M_DR14_1_R_N | PE_CLK_100M_DR14_1_R-DIFF1 | PAIR | 4 | 6.5 | 5 | 10 | 5 | 12 | 20 | 25 | 12 | 12 | 20 | 12 | 7.5 | 85 Ohms | TOP=L2:L3=L2/L4:L6=L5/L7:BOTTOM=L7 |
| PE_CLK_100M_DR14_1_R_N | PE_CLK_100M_DR14_1_R-DIFF1 | PAIR | 5 | 6.5 | 5 | 10 | 5 | 12 | 20 | 25 | 12 | 12 | 20 | 12 | 7.5 | 85 Ohms | TOP=L2:L3=L2/L4:L6=L5/L7:BOTTOM=L7 |
| PE_CLK_100M_DR14_1_R_N | PE_CLK_100M_DR14_1_R-DIFF1 | PAIR | 6 | 6.5 | 5 | 10 | 5 | 12 | 20 | 25 | 12 | 12 | 20 | 12 | 7.5 | 85 Ohms | TOP=L2:L3=L2/L4:L6=L5/L7:BOTTOM=L7 |
| PE_CLK_100M_DR14_1_R_N | PE_CLK_100M_DR14_1_R-DIFF1 | PAIR | 7 | 6.5 | 5 | 10 | 5 | 12 | 20 | 25 | 12 | 12 | 20 | 12 | 7.5 | 85 Ohms | TOP=L2:L3=L2/L4:L6=L5/L7:BOTTOM=L7 |
| PE_CLK_100M_DR14_1_R_N | PE_CLK_100M_DR14_1_R-DIFF1 | PAIR | 8 | 6.88 | 5 | 10 | 5 | 12 | 20 | 36 | 12 | 12 | 20 | 12 | 5.13 | 85 Ohms | TOP=L2:L3=L2/L4:L6=L5/L7:BOTTOM=L7 |
| PE_CLK_100M_DR14_1_R_P | PE_CLK_100M_DR14_1_R-DIFF1 | PAIR | 1 | 6.88 | 5 | 10 | 5 | 12 | 20 | 36 | 12 | 12 | 20 | 12 | 5.13 | 85 Ohms | TOP=L2:L3=L2/L4:L6=L5/L7:BOTTOM=L7 |
| PE_CLK_100M_DR14_1_R_P | PE_CLK_100M_DR14_1_R-DIFF1 | PAIR | 2 | 6.5 | 5 | 10 | 5 | 12 | 20 | 25 | 12 | 12 | 20 | 12 | 7.5 | 85 Ohms | TOP=L2:L3=L2/L4:L6=L5/L7:BOTTOM=L7 |
| PE_CLK_100M_DR14_1_R_P | PE_CLK_100M_DR14_1_R-DIFF1 | PAIR | 3 | 6.5 | 5 | 10 | 5 | 12 | 20 | 25 | 12 | 12 | 20 | 12 | 7.5 | 85 Ohms | TOP=L2:L3=L2/L4:L6=L5/L7:BOTTOM=L7 |
| PE_CLK_100M_DR14_1_R_P | PE_CLK_100M_DR14_1_R-DIFF1 | PAIR | 4 | 6.5 | 5 | 10 | 5 | 12 | 20 | 25 | 12 | 12 | 20 | 12 | 7.5 | 85 Ohms | TOP=L2:L3=L2/L4:L6=L5/L7:BOTTOM=L7 |
| PE_CLK_100M_DR14_1_R_P | PE_CLK_100M_DR14_1_R-DIFF1 | PAIR | 5 | 6.5 | 5 | 10 | 5 | 12 | 20 | 25 | 12 | 12 | 20 | 12 | 7.5 | 85 Ohms | TOP=L2:L3=L2/L4:L6=L5/L7:BOTTOM=L7 |
| PE_CLK_100M_DR14_1_R_P | PE_CLK_100M_DR14_1_R-DIFF1 | PAIR | 6 | 6.5 | 5 | 10 | 5 | 12 | 20 | 25 | 12 | 12 | 20 | 12 | 7.5 | 85 Ohms | TOP=L2:L3=L2/L4:L6=L5/L7:BOTTOM=L7 |
| PE_CLK_100M_DR14_1_R_P | PE_CLK_100M_DR14_1_R-DIFF1 | PAIR | 7 | 6.5 | 5 | 10 | 5 | 12 | 20 | 25 | 12 | 12 | 20 | 12 | 7.5 | 85 Ohms | TOP=L2:L3=L2/L4:L6=L5/L7:BOTTOM=L7 |
| PE_CLK_100M_DR14_1_R_P | PE_CLK_100M_DR14_1_R-DIFF1 | PAIR | 8 | 6.88 | 5 | 10 | 5 | 12 | 20 | 36 | 12 | 12 | 20 | 12 | 5.13 | 85 Ohms | TOP=L2:L3=L2/L4:L6=L5/L7:BOTTOM=L7 |
| PE_CLK_100M_DR14_2_R_N | PE_CLK_100M_DR14_2_R-DIFF1 | PAIR | 1 | 6.88 | 5 | 10 | 5 | 12 | 20 | 36 | 12 | 12 | 20 | 12 | 5.13 | 85 Ohms | TOP=L2:L3=L2/L4:L6=L5/L7:BOTTOM=L7 |
| PE_CLK_100M_DR14_2_R_N | PE_CLK_100M_DR14_2_R-DIFF1 | PAIR | 2 | 6.5 | 5 | 10 | 5 | 12 | 20 | 25 | 12 | 12 | 20 | 12 | 7.5 | 85 Ohms | TOP=L2:L3=L2/L4:L6=L5/L7:BOTTOM=L7 |
| PE_CLK_100M_DR14_2_R_N | PE_CLK_100M_DR14_2_R-DIFF1 | PAIR | 3 | 6.5 | 5 | 10 | 5 | 12 | 20 | 25 | 12 | 12 | 20 | 12 | 7.5 | 85 Ohms | TOP=L2:L3=L2/L4:L6=L5/L7:BOTTOM=L7 |
| PE_CLK_100M_DR14_2_R_N | PE_CLK_100M_DR14_2_R-DIFF1 | PAIR | 4 | 6.5 | 5 | 10 | 5 | 12 | 20 | 25 | 12 | 12 | 20 | 12 | 7.5 | 85 Ohms | TOP=L2:L3=L2/L4:L6=L5/L7:BOTTOM=L7 |
| PE_CLK_100M_DR14_2_R_N | PE_CLK_100M_DR14_2_R-DIFF1 | PAIR | 5 | 6.5 | 5 | 10 | 5 | 12 | 20 | 25 | 12 | 12 | 20 | 12 | 7.5 | 85 Ohms | TOP=L2:L3=L2/L4:L6=L5/L7:BOTTOM=L7 |
| PE_CLK_100M_DR14_2_R_N | PE_CLK_100M_DR14_2_R-DIFF1 | PAIR | 6 | 6.5 | 5 | 10 | 5 | 12 | 20 | 25 | 12 | 12 | 20 | 12 | 7.5 | 85 Ohms | TOP=L2:L3=L2/L4:L6=L5/L7:BOTTOM=L7 |
| PE_CLK_100M_DR14_2_R_N | PE_CLK_100M_DR14_2_R-DIFF1 | PAIR | 7 | 6.5 | 5 | 10 | 5 | 12 | 20 | 25 | 12 | 12 | 20 | 12 | 7.5 | 85 Ohms | TOP=L2:L3=L2/L4:L6=L5/L7:BOTTOM=L7 |
| PE_CLK_100M_DR14_2_R_N | PE_CLK_100M_DR14_2_R-DIFF1 | PAIR | 8 | 6.88 | 5 | 10 | 5 | 12 | 20 | 36 | 12 | 12 | 20 | 12 | 5.13 | 85 Ohms | TOP=L2:L3=L2/L4:L6=L5/L7:BOTTOM=L7 |
| PE_CLK_100M_DR14_2_R_P | PE_CLK_100M_DR14_2_R-DIFF1 | PAIR | 1 | 6.88 | 5 | 10 | 5 | 12 | 20 | 36 | 12 | 12 | 20 | 12 | 5.13 | 85 Ohms | TOP=L2:L3=L2/L4:L6=L5/L7:BOTTOM=L7 |
| PE_CLK_100M_DR14_2_R_P | PE_CLK_100M_DR14_2_R-DIFF1 | PAIR | 2 | 6.5 | 5 | 10 | 5 | 12 | 20 | 25 | 12 | 12 | 20 | 12 | 7.5 | 85 Ohms | TOP=L2:L3=L2/L4:L6=L5/L7:BOTTOM=L7 |
| PE_CLK_100M_DR14_2_R_P | PE_CLK_100M_DR14_2_R-DIFF1 | PAIR | 3 | 6.5 | 5 | 10 | 5 | 12 | 20 | 25 | 12 | 12 | 20 | 12 | 7.5 | 85 Ohms | TOP=L2:L3=L2/L4:L6=L5/L7:BOTTOM=L7 |
| PE_CLK_100M_DR14_2_R_P | PE_CLK_100M_DR14_2_R-DIFF1 | PAIR | 4 | 6.5 | 5 | 10 | 5 | 12 | 20 | 25 | 12 | 12 | 20 | 12 | 7.5 | 85 Ohms | TOP=L2:L3=L2/L4:L6=L5/L7:BOTTOM=L7 |
| PE_CLK_100M_DR14_2_R_P | PE_CLK_100M_DR14_2_R-DIFF1 | PAIR | 5 | 6.5 | 5 | 10 | 5 | 12 | 20 | 25 | 12 | 12 | 20 | 12 | 7.5 | 85 Ohms | TOP=L2:L3=L2/L4:L6=L5/L7:BOTTOM=L7 |
| PE_CLK_100M_DR14_2_R_P | PE_CLK_100M_DR14_2_R-DIFF1 | PAIR | 6 | 6.5 | 5 | 10 | 5 | 12 | 20 | 25 | 12 | 12 | 20 | 12 | 7.5 | 85 Ohms | TOP=L2:L3=L2/L4:L6=L5/L7:BOTTOM=L7 |
| PE_CLK_100M_DR14_2_R_P | PE_CLK_100M_DR14_2_R-DIFF1 | PAIR | 7 | 6.5 | 5 | 10 | 5 | 12 | 20 | 25 | 12 | 12 | 20 | 12 | 7.5 | 85 Ohms | TOP=L2:L3=L2/L4:L6=L5/L7:BOTTOM=L7 |
| PE_CLK_100M_DR14_2_R_P | PE_CLK_100M_DR14_2_R-DIFF1 | PAIR | 8 | 6.88 | 5 | 10 | 5 | 12 | 20 | 36 | 12 | 12 | 20 | 12 | 5.13 | 85 Ohms | TOP=L2:L3=L2/L4:L6=L5/L7:BOTTOM=L7 |
| PE_CLK_100M_DR2_1_R_N | PE_CLK_100M_DR2_1_R-DIFF1 | PAIR | 1 | 6.88 | 5 | 10 | 5 | 12 | 20 | 36 | 12 | 12 | 20 | 12 | 5.13 | 85 Ohms | TOP=L2:L3=L2/L4:L6=L5/L7:BOTTOM=L7 |
| PE_CLK_100M_DR2_1_R_N | PE_CLK_100M_DR2_1_R-DIFF1 | PAIR | 2 | 6.5 | 5 | 10 | 5 | 12 | 20 | 25 | 12 | 12 | 20 | 12 | 7.5 | 85 Ohms | TOP=L2:L3=L2/L4:L6=L5/L7:BOTTOM=L7 |
| PE_CLK_100M_DR2_1_R_N | PE_CLK_100M_DR2_1_R-DIFF1 | PAIR | 3 | 6.5 | 5 | 10 | 5 | 12 | 20 | 25 | 12 | 12 | 20 | 12 | 7.5 | 85 Ohms | TOP=L2:L3=L2/L4:L6=L5/L7:BOTTOM=L7 |
| PE_CLK_100M_DR2_1_R_N | PE_CLK_100M_DR2_1_R-DIFF1 | PAIR | 4 | 6.5 | 5 | 10 | 5 | 12 | 20 | 25 | 12 | 12 | 20 | 12 | 7.5 | 85 Ohms | TOP=L2:L3=L2/L4:L6=L5/L7:BOTTOM=L7 |
| PE_CLK_100M_DR2_1_R_N | PE_CLK_100M_DR2_1_R-DIFF1 | PAIR | 5 | 6.5 | 5 | 10 | 5 | 12 | 20 | 25 | 12 | 12 | 20 | 12 | 7.5 | 85 Ohms | TOP=L2:L3=L2/L4:L6=L5/L7:BOTTOM=L7 |
| PE_CLK_100M_DR2_1_R_N | PE_CLK_100M_DR2_1_R-DIFF1 | PAIR | 6 | 6.5 | 5 | 10 | 5 | 12 | 20 | 25 | 12 | 12 | 20 | 12 | 7.5 | 85 Ohms | TOP=L2:L3=L2/L4:L6=L5/L7:BOTTOM=L7 |
| PE_CLK_100M_DR2_1_R_N | PE_CLK_100M_DR2_1_R-DIFF1 | PAIR | 7 | 6.5 | 5 | 10 | 5 | 12 | 20 | 25 | 12 | 12 | 20 | 12 | 7.5 | 85 Ohms | TOP=L2:L3=L2/L4:L6=L5/L7:BOTTOM=L7 |
| PE_CLK_100M_DR2_1_R_N | PE_CLK_100M_DR2_1_R-DIFF1 | PAIR | 8 | 6.88 | 5 | 10 | 5 | 12 | 20 | 36 | 12 | 12 | 20 | 12 | 5.13 | 85 Ohms | TOP=L2:L3=L2/L4:L6=L5/L7:BOTTOM=L7 |
| PE_CLK_100M_DR2_1_R_P | PE_CLK_100M_DR2_1_R-DIFF1 | PAIR | 1 | 6.88 | 5 | 10 | 5 | 12 | 20 | 36 | 12 | 12 | 20 | 12 | 5.13 | 85 Ohms | TOP=L2:L3=L2/L4:L6=L5/L7:BOTTOM=L7 |
| PE_CLK_100M_DR2_1_R_P | PE_CLK_100M_DR2_1_R-DIFF1 | PAIR | 2 | 6.5 | 5 | 10 | 5 | 12 | 20 | 25 | 12 | 12 | 20 | 12 | 7.5 | 85 Ohms | TOP=L2:L3=L2/L4:L6=L5/L7:BOTTOM=L7 |
| PE_CLK_100M_DR2_1_R_P | PE_CLK_100M_DR2_1_R-DIFF1 | PAIR | 3 | 6.5 | 5 | 10 | 5 | 12 | 20 | 25 | 12 | 12 | 20 | 12 | 7.5 | 85 Ohms | TOP=L2:L3=L2/L4:L6=L5/L7:BOTTOM=L7 |
| PE_CLK_100M_DR2_1_R_P | PE_CLK_100M_DR2_1_R-DIFF1 | PAIR | 4 | 6.5 | 5 | 10 | 5 | 12 | 20 | 25 | 12 | 12 | 20 | 12 | 7.5 | 85 Ohms | TOP=L2:L3=L2/L4:L6=L5/L7:BOTTOM=L7 |
| PE_CLK_100M_DR2_1_R_P | PE_CLK_100M_DR2_1_R-DIFF1 | PAIR | 5 | 6.5 | 5 | 10 | 5 | 12 | 20 | 25 | 12 | 12 | 20 | 12 | 7.5 | 85 Ohms | TOP=L2:L3=L2/L4:L6=L5/L7:BOTTOM=L7 |
| PE_CLK_100M_DR2_1_R_P | PE_CLK_100M_DR2_1_R-DIFF1 | PAIR | 6 | 6.5 | 5 | 10 | 5 | 12 | 20 | 25 | 12 | 12 | 20 | 12 | 7.5 | 85 Ohms | TOP=L2:L3=L2/L4:L6=L5/L7:BOTTOM=L7 |
| PE_CLK_100M_DR2_1_R_P | PE_CLK_100M_DR2_1_R-DIFF1 | PAIR | 7 | 6.5 | 5 | 10 | 5 | 12 | 20 | 25 | 12 | 12 | 20 | 12 | 7.5 | 85 Ohms | TOP=L2:L3=L2/L4:L6=L5/L7:BOTTOM=L7 |
| PE_CLK_100M_DR2_1_R_P | PE_CLK_100M_DR2_1_R-DIFF1 | PAIR | 8 | 6.88 | 5 | 10 | 5 | 12 | 20 | 36 | 12 | 12 | 20 | 12 | 5.13 | 85 Ohms | TOP=L2:L3=L2/L4:L6=L5/L7:BOTTOM=L7 |
| PE_CLK_100M_DR2_2_R_N | PE_CLK_100M_DR2_2_R-DIFF1 | PAIR | 1 | 6.88 | 5 | 10 | 5 | 12 | 20 | 36 | 12 | 12 | 20 | 12 | 5.13 | 85 Ohms | TOP=L2:L3=L2/L4:L6=L5/L7:BOTTOM=L7 |
| PE_CLK_100M_DR2_2_R_N | PE_CLK_100M_DR2_2_R-DIFF1 | PAIR | 2 | 6.5 | 5 | 10 | 5 | 12 | 20 | 25 | 12 | 12 | 20 | 12 | 7.5 | 85 Ohms | TOP=L2:L3=L2/L4:L6=L5/L7:BOTTOM=L7 |
| PE_CLK_100M_DR2_2_R_N | PE_CLK_100M_DR2_2_R-DIFF1 | PAIR | 3 | 6.5 | 5 | 10 | 5 | 12 | 20 | 25 | 12 | 12 | 20 | 12 | 7.5 | 85 Ohms | TOP=L2:L3=L2/L4:L6=L5/L7:BOTTOM=L7 |
| PE_CLK_100M_DR2_2_R_N | PE_CLK_100M_DR2_2_R-DIFF1 | PAIR | 4 | 6.5 | 5 | 10 | 5 | 12 | 20 | 25 | 12 | 12 | 20 | 12 | 7.5 | 85 Ohms | TOP=L2:L3=L2/L4:L6=L5/L7:BOTTOM=L7 |
| PE_CLK_100M_DR2_2_R_N | PE_CLK_100M_DR2_2_R-DIFF1 | PAIR | 5 | 6.5 | 5 | 10 | 5 | 12 | 20 | 25 | 12 | 12 | 20 | 12 | 7.5 | 85 Ohms | TOP=L2:L3=L2/L4:L6=L5/L7:BOTTOM=L7 |
| PE_CLK_100M_DR2_2_R_N | PE_CLK_100M_DR2_2_R-DIFF1 | PAIR | 6 | 6.5 | 5 | 10 | 5 | 12 | 20 | 25 | 12 | 12 | 20 | 12 | 7.5 | 85 Ohms | TOP=L2:L3=L2/L4:L6=L5/L7:BOTTOM=L7 |
| PE_CLK_100M_DR2_2_R_N | PE_CLK_100M_DR2_2_R-DIFF1 | PAIR | 7 | 6.5 | 5 | 10 | 5 | 12 | 20 | 25 | 12 | 12 | 20 | 12 | 7.5 | 85 Ohms | TOP=L2:L3=L2/L4:L6=L5/L7:BOTTOM=L7 |
| PE_CLK_100M_DR2_2_R_N | PE_CLK_100M_DR2_2_R-DIFF1 | PAIR | 8 | 6.88 | 5 | 10 | 5 | 12 | 20 | 36 | 12 | 12 | 20 | 12 | 5.13 | 85 Ohms | TOP=L2:L3=L2/L4:L6=L5/L7:BOTTOM=L7 |
| PE_CLK_100M_DR2_2_R_P | PE_CLK_100M_DR2_2_R-DIFF1 | PAIR | 1 | 6.88 | 5 | 10 | 5 | 12 | 20 | 36 | 12 | 12 | 20 | 12 | 5.13 | 85 Ohms | TOP=L2:L3=L2/L4:L6=L5/L7:BOTTOM=L7 |
| PE_CLK_100M_DR2_2_R_P | PE_CLK_100M_DR2_2_R-DIFF1 | PAIR | 2 | 6.5 | 5 | 10 | 5 | 12 | 20 | 25 | 12 | 12 | 20 | 12 | 7.5 | 85 Ohms | TOP=L2:L3=L2/L4:L6=L5/L7:BOTTOM=L7 |
| PE_CLK_100M_DR2_2_R_P | PE_CLK_100M_DR2_2_R-DIFF1 | PAIR | 3 | 6.5 | 5 | 10 | 5 | 12 | 20 | 25 | 12 | 12 | 20 | 12 | 7.5 | 85 Ohms | TOP=L2:L3=L2/L4:L6=L5/L7:BOTTOM=L7 |
| PE_CLK_100M_DR2_2_R_P | PE_CLK_100M_DR2_2_R-DIFF1 | PAIR | 4 | 6.5 | 5 | 10 | 5 | 12 | 20 | 25 | 12 | 12 | 20 | 12 | 7.5 | 85 Ohms | TOP=L2:L3=L2/L4:L6=L5/L7:BOTTOM=L7 |
| PE_CLK_100M_DR2_2_R_P | PE_CLK_100M_DR2_2_R-DIFF1 | PAIR | 5 | 6.5 | 5 | 10 | 5 | 12 | 20 | 25 | 12 | 12 | 20 | 12 | 7.5 | 85 Ohms | TOP=L2:L3=L2/L4:L6=L5/L7:BOTTOM=L7 |
| PE_CLK_100M_DR2_2_R_P | PE_CLK_100M_DR2_2_R-DIFF1 | PAIR | 6 | 6.5 | 5 | 10 | 5 | 12 | 20 | 25 | 12 | 12 | 20 | 12 | 7.5 | 85 Ohms | TOP=L2:L3=L2/L4:L6=L5/L7:BOTTOM=L7 |
| PE_CLK_100M_DR2_2_R_P | PE_CLK_100M_DR2_2_R-DIFF1 | PAIR | 7 | 6.5 | 5 | 10 | 5 | 12 | 20 | 25 | 12 | 12 | 20 | 12 | 7.5 | 85 Ohms | TOP=L2:L3=L2/L4:L6=L5/L7:BOTTOM=L7 |
| PE_CLK_100M_DR2_2_R_P | PE_CLK_100M_DR2_2_R-DIFF1 | PAIR | 8 | 6.88 | 5 | 10 | 5 | 12 | 20 | 36 | 12 | 12 | 20 | 12 | 5.13 | 85 Ohms | TOP=L2:L3=L2/L4:L6=L5/L7:BOTTOM=L7 |
| PE_CLK_100M_DR3_1_R_N | PE_CLK_100M_DR3_1_R-DIFF1 | PAIR | 1 | 6.88 | 5 | 10 | 5 | 12 | 20 | 36 | 12 | 12 | 20 | 12 | 5.13 | 85 Ohms | TOP=L2:L3=L2/L4:L6=L5/L7:BOTTOM=L7 |
| PE_CLK_100M_DR3_1_R_N | PE_CLK_100M_DR3_1_R-DIFF1 | PAIR | 2 | 6.5 | 5 | 10 | 5 | 12 | 20 | 25 | 12 | 12 | 20 | 12 | 7.5 | 85 Ohms | TOP=L2:L3=L2/L4:L6=L5/L7:BOTTOM=L7 |
| PE_CLK_100M_DR3_1_R_N | PE_CLK_100M_DR3_1_R-DIFF1 | PAIR | 3 | 6.5 | 5 | 10 | 5 | 12 | 20 | 25 | 12 | 12 | 20 | 12 | 7.5 | 85 Ohms | TOP=L2:L3=L2/L4:L6=L5/L7:BOTTOM=L7 |
| PE_CLK_100M_DR3_1_R_N | PE_CLK_100M_DR3_1_R-DIFF1 | PAIR | 4 | 6.5 | 5 | 10 | 5 | 12 | 20 | 25 | 12 | 12 | 20 | 12 | 7.5 | 85 Ohms | TOP=L2:L3=L2/L4:L6=L5/L7:BOTTOM=L7 |
| PE_CLK_100M_DR3_1_R_N | PE_CLK_100M_DR3_1_R-DIFF1 | PAIR | 5 | 6.5 | 5 | 10 | 5 | 12 | 20 | 25 | 12 | 12 | 20 | 12 | 7.5 | 85 Ohms | TOP=L2:L3=L2/L4:L6=L5/L7:BOTTOM=L7 |
| PE_CLK_100M_DR3_1_R_N | PE_CLK_100M_DR3_1_R-DIFF1 | PAIR | 6 | 6.5 | 5 | 10 | 5 | 12 | 20 | 25 | 12 | 12 | 20 | 12 | 7.5 | 85 Ohms | TOP=L2:L3=L2/L4:L6=L5/L7:BOTTOM=L7 |
| PE_CLK_100M_DR3_1_R_N | PE_CLK_100M_DR3_1_R-DIFF1 | PAIR | 7 | 6.5 | 5 | 10 | 5 | 12 | 20 | 25 | 12 | 12 | 20 | 12 | 7.5 | 85 Ohms | TOP=L2:L3=L2/L4:L6=L5/L7:BOTTOM=L7 |
| PE_CLK_100M_DR3_1_R_N | PE_CLK_100M_DR3_1_R-DIFF1 | PAIR | 8 | 6.88 | 5 | 10 | 5 | 12 | 20 | 36 | 12 | 12 | 20 | 12 | 5.13 | 85 Ohms | TOP=L2:L3=L2/L4:L6=L5/L7:BOTTOM=L7 |
| PE_CLK_100M_DR3_1_R_P | PE_CLK_100M_DR3_1_R-DIFF1 | PAIR | 1 | 6.88 | 5 | 10 | 5 | 12 | 20 | 36 | 12 | 12 | 20 | 12 | 5.13 | 85 Ohms | TOP=L2:L3=L2/L4:L6=L5/L7:BOTTOM=L7 |
| PE_CLK_100M_DR3_1_R_P | PE_CLK_100M_DR3_1_R-DIFF1 | PAIR | 2 | 6.5 | 5 | 10 | 5 | 12 | 20 | 25 | 12 | 12 | 20 | 12 | 7.5 | 85 Ohms | TOP=L2:L3=L2/L4:L6=L5/L7:BOTTOM=L7 |
| PE_CLK_100M_DR3_1_R_P | PE_CLK_100M_DR3_1_R-DIFF1 | PAIR | 3 | 6.5 | 5 | 10 | 5 | 12 | 20 | 25 | 12 | 12 | 20 | 12 | 7.5 | 85 Ohms | TOP=L2:L3=L2/L4:L6=L5/L7:BOTTOM=L7 |
| PE_CLK_100M_DR3_1_R_P | PE_CLK_100M_DR3_1_R-DIFF1 | PAIR | 4 | 6.5 | 5 | 10 | 5 | 12 | 20 | 25 | 12 | 12 | 20 | 12 | 7.5 | 85 Ohms | TOP=L2:L3=L2/L4:L6=L5/L7:BOTTOM=L7 |
| PE_CLK_100M_DR3_1_R_P | PE_CLK_100M_DR3_1_R-DIFF1 | PAIR | 5 | 6.5 | 5 | 10 | 5 | 12 | 20 | 25 | 12 | 12 | 20 | 12 | 7.5 | 85 Ohms | TOP=L2:L3=L2/L4:L6=L5/L7:BOTTOM=L7 |
| PE_CLK_100M_DR3_1_R_P | PE_CLK_100M_DR3_1_R-DIFF1 | PAIR | 6 | 6.5 | 5 | 10 | 5 | 12 | 20 | 25 | 12 | 12 | 20 | 12 | 7.5 | 85 Ohms | TOP=L2:L3=L2/L4:L6=L5/L7:BOTTOM=L7 |
| PE_CLK_100M_DR3_1_R_P | PE_CLK_100M_DR3_1_R-DIFF1 | PAIR | 7 | 6.5 | 5 | 10 | 5 | 12 | 20 | 25 | 12 | 12 | 20 | 12 | 7.5 | 85 Ohms | TOP=L2:L3=L2/L4:L6=L5/L7:BOTTOM=L7 |
| PE_CLK_100M_DR3_1_R_P | PE_CLK_100M_DR3_1_R-DIFF1 | PAIR | 8 | 6.88 | 5 | 10 | 5 | 12 | 20 | 36 | 12 | 12 | 20 | 12 | 5.13 | 85 Ohms | TOP=L2:L3=L2/L4:L6=L5/L7:BOTTOM=L7 |
| PE_CLK_100M_DR3_2_R_N | PE_CLK_100M_DR3_2_R-DIFF1 | PAIR | 1 | 6.88 | 5 | 10 | 5 | 12 | 20 | 36 | 12 | 12 | 20 | 12 | 5.13 | 85 Ohms | TOP=L2:L3=L2/L4:L6=L5/L7:BOTTOM=L7 |
| PE_CLK_100M_DR3_2_R_N | PE_CLK_100M_DR3_2_R-DIFF1 | PAIR | 2 | 6.5 | 5 | 10 | 5 | 12 | 20 | 25 | 12 | 12 | 20 | 12 | 7.5 | 85 Ohms | TOP=L2:L3=L2/L4:L6=L5/L7:BOTTOM=L7 |
| PE_CLK_100M_DR3_2_R_N | PE_CLK_100M_DR3_2_R-DIFF1 | PAIR | 3 | 6.5 | 5 | 10 | 5 | 12 | 20 | 25 | 12 | 12 | 20 | 12 | 7.5 | 85 Ohms | TOP=L2:L3=L2/L4:L6=L5/L7:BOTTOM=L7 |
| PE_CLK_100M_DR3_2_R_N | PE_CLK_100M_DR3_2_R-DIFF1 | PAIR | 4 | 6.5 | 5 | 10 | 5 | 12 | 20 | 25 | 12 | 12 | 20 | 12 | 7.5 | 85 Ohms | TOP=L2:L3=L2/L4:L6=L5/L7:BOTTOM=L7 |
| PE_CLK_100M_DR3_2_R_N | PE_CLK_100M_DR3_2_R-DIFF1 | PAIR | 5 | 6.5 | 5 | 10 | 5 | 12 | 20 | 25 | 12 | 12 | 20 | 12 | 7.5 | 85 Ohms | TOP=L2:L3=L2/L4:L6=L5/L7:BOTTOM=L7 |
| PE_CLK_100M_DR3_2_R_N | PE_CLK_100M_DR3_2_R-DIFF1 | PAIR | 6 | 6.5 | 5 | 10 | 5 | 12 | 20 | 25 | 12 | 12 | 20 | 12 | 7.5 | 85 Ohms | TOP=L2:L3=L2/L4:L6=L5/L7:BOTTOM=L7 |
| PE_CLK_100M_DR3_2_R_N | PE_CLK_100M_DR3_2_R-DIFF1 | PAIR | 7 | 6.5 | 5 | 10 | 5 | 12 | 20 | 25 | 12 | 12 | 20 | 12 | 7.5 | 85 Ohms | TOP=L2:L3=L2/L4:L6=L5/L7:BOTTOM=L7 |
| PE_CLK_100M_DR3_2_R_N | PE_CLK_100M_DR3_2_R-DIFF1 | PAIR | 8 | 6.88 | 5 | 10 | 5 | 12 | 20 | 36 | 12 | 12 | 20 | 12 | 5.13 | 85 Ohms | TOP=L2:L3=L2/L4:L6=L5/L7:BOTTOM=L7 |
| PE_CLK_100M_DR3_2_R_P | PE_CLK_100M_DR3_2_R-DIFF1 | PAIR | 1 | 6.88 | 5 | 10 | 5 | 12 | 20 | 36 | 12 | 12 | 20 | 12 | 5.13 | 85 Ohms | TOP=L2:L3=L2/L4:L6=L5/L7:BOTTOM=L7 |
| PE_CLK_100M_DR3_2_R_P | PE_CLK_100M_DR3_2_R-DIFF1 | PAIR | 2 | 6.5 | 5 | 10 | 5 | 12 | 20 | 25 | 12 | 12 | 20 | 12 | 7.5 | 85 Ohms | TOP=L2:L3=L2/L4:L6=L5/L7:BOTTOM=L7 |
| PE_CLK_100M_DR3_2_R_P | PE_CLK_100M_DR3_2_R-DIFF1 | PAIR | 3 | 6.5 | 5 | 10 | 5 | 12 | 20 | 25 | 12 | 12 | 20 | 12 | 7.5 | 85 Ohms | TOP=L2:L3=L2/L4:L6=L5/L7:BOTTOM=L7 |
| PE_CLK_100M_DR3_2_R_P | PE_CLK_100M_DR3_2_R-DIFF1 | PAIR | 4 | 6.5 | 5 | 10 | 5 | 12 | 20 | 25 | 12 | 12 | 20 | 12 | 7.5 | 85 Ohms | TOP=L2:L3=L2/L4:L6=L5/L7:BOTTOM=L7 |
| PE_CLK_100M_DR3_2_R_P | PE_CLK_100M_DR3_2_R-DIFF1 | PAIR | 5 | 6.5 | 5 | 10 | 5 | 12 | 20 | 25 | 12 | 12 | 20 | 12 | 7.5 | 85 Ohms | TOP=L2:L3=L2/L4:L6=L5/L7:BOTTOM=L7 |
| PE_CLK_100M_DR3_2_R_P | PE_CLK_100M_DR3_2_R-DIFF1 | PAIR | 6 | 6.5 | 5 | 10 | 5 | 12 | 20 | 25 | 12 | 12 | 20 | 12 | 7.5 | 85 Ohms | TOP=L2:L3=L2/L4:L6=L5/L7:BOTTOM=L7 |
| PE_CLK_100M_DR3_2_R_P | PE_CLK_100M_DR3_2_R-DIFF1 | PAIR | 7 | 6.5 | 5 | 10 | 5 | 12 | 20 | 25 | 12 | 12 | 20 | 12 | 7.5 | 85 Ohms | TOP=L2:L3=L2/L4:L6=L5/L7:BOTTOM=L7 |
| PE_CLK_100M_DR3_2_R_P | PE_CLK_100M_DR3_2_R-DIFF1 | PAIR | 8 | 6.88 | 5 | 10 | 5 | 12 | 20 | 36 | 12 | 12 | 20 | 12 | 5.13 | 85 Ohms | TOP=L2:L3=L2/L4:L6=L5/L7:BOTTOM=L7 |
| PE_CLK_100M_DR4_1_R_N | PE_CLK_100M_DR4_1_R-DIFF1 | PAIR | 1 | 6.88 | 5 | 10 | 5 | 12 | 20 | 36 | 12 | 12 | 20 | 12 | 5.13 | 85 Ohms | TOP=L2:L3=L2/L4:L6=L5/L7:BOTTOM=L7 |
| PE_CLK_100M_DR4_1_R_N | PE_CLK_100M_DR4_1_R-DIFF1 | PAIR | 2 | 6.5 | 5 | 10 | 5 | 12 | 20 | 25 | 12 | 12 | 20 | 12 | 7.5 | 85 Ohms | TOP=L2:L3=L2/L4:L6=L5/L7:BOTTOM=L7 |
| PE_CLK_100M_DR4_1_R_N | PE_CLK_100M_DR4_1_R-DIFF1 | PAIR | 3 | 6.5 | 5 | 10 | 5 | 12 | 20 | 25 | 12 | 12 | 20 | 12 | 7.5 | 85 Ohms | TOP=L2:L3=L2/L4:L6=L5/L7:BOTTOM=L7 |
| PE_CLK_100M_DR4_1_R_N | PE_CLK_100M_DR4_1_R-DIFF1 | PAIR | 4 | 6.5 | 5 | 10 | 5 | 12 | 20 | 25 | 12 | 12 | 20 | 12 | 7.5 | 85 Ohms | TOP=L2:L3=L2/L4:L6=L5/L7:BOTTOM=L7 |
| PE_CLK_100M_DR4_1_R_N | PE_CLK_100M_DR4_1_R-DIFF1 | PAIR | 5 | 6.5 | 5 | 10 | 5 | 12 | 20 | 25 | 12 | 12 | 20 | 12 | 7.5 | 85 Ohms | TOP=L2:L3=L2/L4:L6=L5/L7:BOTTOM=L7 |
| PE_CLK_100M_DR4_1_R_N | PE_CLK_100M_DR4_1_R-DIFF1 | PAIR | 6 | 6.5 | 5 | 10 | 5 | 12 | 20 | 25 | 12 | 12 | 20 | 12 | 7.5 | 85 Ohms | TOP=L2:L3=L2/L4:L6=L5/L7:BOTTOM=L7 |
| PE_CLK_100M_DR4_1_R_N | PE_CLK_100M_DR4_1_R-DIFF1 | PAIR | 7 | 6.5 | 5 | 10 | 5 | 12 | 20 | 25 | 12 | 12 | 20 | 12 | 7.5 | 85 Ohms | TOP=L2:L3=L2/L4:L6=L5/L7:BOTTOM=L7 |
| PE_CLK_100M_DR4_1_R_N | PE_CLK_100M_DR4_1_R-DIFF1 | PAIR | 8 | 6.88 | 5 | 10 | 5 | 12 | 20 | 36 | 12 | 12 | 20 | 12 | 5.13 | 85 Ohms | TOP=L2:L3=L2/L4:L6=L5/L7:BOTTOM=L7 |
| PE_CLK_100M_DR4_1_R_P | PE_CLK_100M_DR4_1_R-DIFF1 | PAIR | 1 | 6.88 | 5 | 10 | 5 | 12 | 20 | 36 | 12 | 12 | 20 | 12 | 5.13 | 85 Ohms | TOP=L2:L3=L2/L4:L6=L5/L7:BOTTOM=L7 |
| PE_CLK_100M_DR4_1_R_P | PE_CLK_100M_DR4_1_R-DIFF1 | PAIR | 2 | 6.5 | 5 | 10 | 5 | 12 | 20 | 25 | 12 | 12 | 20 | 12 | 7.5 | 85 Ohms | TOP=L2:L3=L2/L4:L6=L5/L7:BOTTOM=L7 |
| PE_CLK_100M_DR4_1_R_P | PE_CLK_100M_DR4_1_R-DIFF1 | PAIR | 3 | 6.5 | 5 | 10 | 5 | 12 | 20 | 25 | 12 | 12 | 20 | 12 | 7.5 | 85 Ohms | TOP=L2:L3=L2/L4:L6=L5/L7:BOTTOM=L7 |
| PE_CLK_100M_DR4_1_R_P | PE_CLK_100M_DR4_1_R-DIFF1 | PAIR | 4 | 6.5 | 5 | 10 | 5 | 12 | 20 | 25 | 12 | 12 | 20 | 12 | 7.5 | 85 Ohms | TOP=L2:L3=L2/L4:L6=L5/L7:BOTTOM=L7 |
| PE_CLK_100M_DR4_1_R_P | PE_CLK_100M_DR4_1_R-DIFF1 | PAIR | 5 | 6.5 | 5 | 10 | 5 | 12 | 20 | 25 | 12 | 12 | 20 | 12 | 7.5 | 85 Ohms | TOP=L2:L3=L2/L4:L6=L5/L7:BOTTOM=L7 |
| PE_CLK_100M_DR4_1_R_P | PE_CLK_100M_DR4_1_R-DIFF1 | PAIR | 6 | 6.5 | 5 | 10 | 5 | 12 | 20 | 25 | 12 | 12 | 20 | 12 | 7.5 | 85 Ohms | TOP=L2:L3=L2/L4:L6=L5/L7:BOTTOM=L7 |
| PE_CLK_100M_DR4_1_R_P | PE_CLK_100M_DR4_1_R-DIFF1 | PAIR | 7 | 6.5 | 5 | 10 | 5 | 12 | 20 | 25 | 12 | 12 | 20 | 12 | 7.5 | 85 Ohms | TOP=L2:L3=L2/L4:L6=L5/L7:BOTTOM=L7 |
| PE_CLK_100M_DR4_1_R_P | PE_CLK_100M_DR4_1_R-DIFF1 | PAIR | 8 | 6.88 | 5 | 10 | 5 | 12 | 20 | 36 | 12 | 12 | 20 | 12 | 5.13 | 85 Ohms | TOP=L2:L3=L2/L4:L6=L5/L7:BOTTOM=L7 |
| PE_CLK_100M_DR4_2_R_N | PE_CLK_100M_DR4_2_R-DIFF1 | PAIR | 1 | 6.88 | 5 | 10 | 5 | 12 | 20 | 36 | 12 | 12 | 20 | 12 | 5.13 | 85 Ohms | TOP=L2:L3=L2/L4:L6=L5/L7:BOTTOM=L7 |
| PE_CLK_100M_DR4_2_R_N | PE_CLK_100M_DR4_2_R-DIFF1 | PAIR | 2 | 6.5 | 5 | 10 | 5 | 12 | 20 | 25 | 12 | 12 | 20 | 12 | 7.5 | 85 Ohms | TOP=L2:L3=L2/L4:L6=L5/L7:BOTTOM=L7 |
| PE_CLK_100M_DR4_2_R_N | PE_CLK_100M_DR4_2_R-DIFF1 | PAIR | 3 | 6.5 | 5 | 10 | 5 | 12 | 20 | 25 | 12 | 12 | 20 | 12 | 7.5 | 85 Ohms | TOP=L2:L3=L2/L4:L6=L5/L7:BOTTOM=L7 |
| PE_CLK_100M_DR4_2_R_N | PE_CLK_100M_DR4_2_R-DIFF1 | PAIR | 4 | 6.5 | 5 | 10 | 5 | 12 | 20 | 25 | 12 | 12 | 20 | 12 | 7.5 | 85 Ohms | TOP=L2:L3=L2/L4:L6=L5/L7:BOTTOM=L7 |
| PE_CLK_100M_DR4_2_R_N | PE_CLK_100M_DR4_2_R-DIFF1 | PAIR | 5 | 6.5 | 5 | 10 | 5 | 12 | 20 | 25 | 12 | 12 | 20 | 12 | 7.5 | 85 Ohms | TOP=L2:L3=L2/L4:L6=L5/L7:BOTTOM=L7 |
| PE_CLK_100M_DR4_2_R_N | PE_CLK_100M_DR4_2_R-DIFF1 | PAIR | 6 | 6.5 | 5 | 10 | 5 | 12 | 20 | 25 | 12 | 12 | 20 | 12 | 7.5 | 85 Ohms | TOP=L2:L3=L2/L4:L6=L5/L7:BOTTOM=L7 |
| PE_CLK_100M_DR4_2_R_N | PE_CLK_100M_DR4_2_R-DIFF1 | PAIR | 7 | 6.5 | 5 | 10 | 5 | 12 | 20 | 25 | 12 | 12 | 20 | 12 | 7.5 | 85 Ohms | TOP=L2:L3=L2/L4:L6=L5/L7:BOTTOM=L7 |
| PE_CLK_100M_DR4_2_R_N | PE_CLK_100M_DR4_2_R-DIFF1 | PAIR | 8 | 6.88 | 5 | 10 | 5 | 12 | 20 | 36 | 12 | 12 | 20 | 12 | 5.13 | 85 Ohms | TOP=L2:L3=L2/L4:L6=L5/L7:BOTTOM=L7 |
| PE_CLK_100M_DR4_2_R_P | PE_CLK_100M_DR4_2_R-DIFF1 | PAIR | 1 | 6.88 | 5 | 10 | 5 | 12 | 20 | 36 | 12 | 12 | 20 | 12 | 5.13 | 85 Ohms | TOP=L2:L3=L2/L4:L6=L5/L7:BOTTOM=L7 |
| PE_CLK_100M_DR4_2_R_P | PE_CLK_100M_DR4_2_R-DIFF1 | PAIR | 2 | 6.5 | 5 | 10 | 5 | 12 | 20 | 25 | 12 | 12 | 20 | 12 | 7.5 | 85 Ohms | TOP=L2:L3=L2/L4:L6=L5/L7:BOTTOM=L7 |
| PE_CLK_100M_DR4_2_R_P | PE_CLK_100M_DR4_2_R-DIFF1 | PAIR | 3 | 6.5 | 5 | 10 | 5 | 12 | 20 | 25 | 12 | 12 | 20 | 12 | 7.5 | 85 Ohms | TOP=L2:L3=L2/L4:L6=L5/L7:BOTTOM=L7 |
| PE_CLK_100M_DR4_2_R_P | PE_CLK_100M_DR4_2_R-DIFF1 | PAIR | 4 | 6.5 | 5 | 10 | 5 | 12 | 20 | 25 | 12 | 12 | 20 | 12 | 7.5 | 85 Ohms | TOP=L2:L3=L2/L4:L6=L5/L7:BOTTOM=L7 |
| PE_CLK_100M_DR4_2_R_P | PE_CLK_100M_DR4_2_R-DIFF1 | PAIR | 5 | 6.5 | 5 | 10 | 5 | 12 | 20 | 25 | 12 | 12 | 20 | 12 | 7.5 | 85 Ohms | TOP=L2:L3=L2/L4:L6=L5/L7:BOTTOM=L7 |
| PE_CLK_100M_DR4_2_R_P | PE_CLK_100M_DR4_2_R-DIFF1 | PAIR | 6 | 6.5 | 5 | 10 | 5 | 12 | 20 | 25 | 12 | 12 | 20 | 12 | 7.5 | 85 Ohms | TOP=L2:L3=L2/L4:L6=L5/L7:BOTTOM=L7 |
| PE_CLK_100M_DR4_2_R_P | PE_CLK_100M_DR4_2_R-DIFF1 | PAIR | 7 | 6.5 | 5 | 10 | 5 | 12 | 20 | 25 | 12 | 12 | 20 | 12 | 7.5 | 85 Ohms | TOP=L2:L3=L2/L4:L6=L5/L7:BOTTOM=L7 |
| PE_CLK_100M_DR4_2_R_P | PE_CLK_100M_DR4_2_R-DIFF1 | PAIR | 8 | 6.88 | 5 | 10 | 5 | 12 | 20 | 36 | 12 | 12 | 20 | 12 | 5.13 | 85 Ohms | TOP=L2:L3=L2/L4:L6=L5/L7:BOTTOM=L7 |
| PE_CLK_100M_DR5_1_R_N | PE_CLK_100M_DR5_1_R-DIFF1 | PAIR | 1 | 6.88 | 5 | 10 | 5 | 12 | 20 | 36 | 12 | 12 | 20 | 12 | 5.13 | 85 Ohms | TOP=L2:L3=L2/L4:L6=L5/L7:BOTTOM=L7 |
| PE_CLK_100M_DR5_1_R_N | PE_CLK_100M_DR5_1_R-DIFF1 | PAIR | 2 | 6.5 | 5 | 10 | 5 | 12 | 20 | 25 | 12 | 12 | 20 | 12 | 7.5 | 85 Ohms | TOP=L2:L3=L2/L4:L6=L5/L7:BOTTOM=L7 |
| PE_CLK_100M_DR5_1_R_N | PE_CLK_100M_DR5_1_R-DIFF1 | PAIR | 3 | 6.5 | 5 | 10 | 5 | 12 | 20 | 25 | 12 | 12 | 20 | 12 | 7.5 | 85 Ohms | TOP=L2:L3=L2/L4:L6=L5/L7:BOTTOM=L7 |
| PE_CLK_100M_DR5_1_R_N | PE_CLK_100M_DR5_1_R-DIFF1 | PAIR | 4 | 6.5 | 5 | 10 | 5 | 12 | 20 | 25 | 12 | 12 | 20 | 12 | 7.5 | 85 Ohms | TOP=L2:L3=L2/L4:L6=L5/L7:BOTTOM=L7 |
| PE_CLK_100M_DR5_1_R_N | PE_CLK_100M_DR5_1_R-DIFF1 | PAIR | 5 | 6.5 | 5 | 10 | 5 | 12 | 20 | 25 | 12 | 12 | 20 | 12 | 7.5 | 85 Ohms | TOP=L2:L3=L2/L4:L6=L5/L7:BOTTOM=L7 |
| PE_CLK_100M_DR5_1_R_N | PE_CLK_100M_DR5_1_R-DIFF1 | PAIR | 6 | 6.5 | 5 | 10 | 5 | 12 | 20 | 25 | 12 | 12 | 20 | 12 | 7.5 | 85 Ohms | TOP=L2:L3=L2/L4:L6=L5/L7:BOTTOM=L7 |
| PE_CLK_100M_DR5_1_R_N | PE_CLK_100M_DR5_1_R-DIFF1 | PAIR | 7 | 6.5 | 5 | 10 | 5 | 12 | 20 | 25 | 12 | 12 | 20 | 12 | 7.5 | 85 Ohms | TOP=L2:L3=L2/L4:L6=L5/L7:BOTTOM=L7 |
| PE_CLK_100M_DR5_1_R_N | PE_CLK_100M_DR5_1_R-DIFF1 | PAIR | 8 | 6.88 | 5 | 10 | 5 | 12 | 20 | 36 | 12 | 12 | 20 | 12 | 5.13 | 85 Ohms | TOP=L2:L3=L2/L4:L6=L5/L7:BOTTOM=L7 |
| PE_CLK_100M_DR5_1_R_P | PE_CLK_100M_DR5_1_R-DIFF1 | PAIR | 1 | 6.88 | 5 | 10 | 5 | 12 | 20 | 36 | 12 | 12 | 20 | 12 | 5.13 | 85 Ohms | TOP=L2:L3=L2/L4:L6=L5/L7:BOTTOM=L7 |
| PE_CLK_100M_DR5_1_R_P | PE_CLK_100M_DR5_1_R-DIFF1 | PAIR | 2 | 6.5 | 5 | 10 | 5 | 12 | 20 | 25 | 12 | 12 | 20 | 12 | 7.5 | 85 Ohms | TOP=L2:L3=L2/L4:L6=L5/L7:BOTTOM=L7 |
| PE_CLK_100M_DR5_1_R_P | PE_CLK_100M_DR5_1_R-DIFF1 | PAIR | 3 | 6.5 | 5 | 10 | 5 | 12 | 20 | 25 | 12 | 12 | 20 | 12 | 7.5 | 85 Ohms | TOP=L2:L3=L2/L4:L6=L5/L7:BOTTOM=L7 |
| PE_CLK_100M_DR5_1_R_P | PE_CLK_100M_DR5_1_R-DIFF1 | PAIR | 4 | 6.5 | 5 | 10 | 5 | 12 | 20 | 25 | 12 | 12 | 20 | 12 | 7.5 | 85 Ohms | TOP=L2:L3=L2/L4:L6=L5/L7:BOTTOM=L7 |
| PE_CLK_100M_DR5_1_R_P | PE_CLK_100M_DR5_1_R-DIFF1 | PAIR | 5 | 6.5 | 5 | 10 | 5 | 12 | 20 | 25 | 12 | 12 | 20 | 12 | 7.5 | 85 Ohms | TOP=L2:L3=L2/L4:L6=L5/L7:BOTTOM=L7 |
| PE_CLK_100M_DR5_1_R_P | PE_CLK_100M_DR5_1_R-DIFF1 | PAIR | 6 | 6.5 | 5 | 10 | 5 | 12 | 20 | 25 | 12 | 12 | 20 | 12 | 7.5 | 85 Ohms | TOP=L2:L3=L2/L4:L6=L5/L7:BOTTOM=L7 |
| PE_CLK_100M_DR5_1_R_P | PE_CLK_100M_DR5_1_R-DIFF1 | PAIR | 7 | 6.5 | 5 | 10 | 5 | 12 | 20 | 25 | 12 | 12 | 20 | 12 | 7.5 | 85 Ohms | TOP=L2:L3=L2/L4:L6=L5/L7:BOTTOM=L7 |
| PE_CLK_100M_DR5_1_R_P | PE_CLK_100M_DR5_1_R-DIFF1 | PAIR | 8 | 6.88 | 5 | 10 | 5 | 12 | 20 | 36 | 12 | 12 | 20 | 12 | 5.13 | 85 Ohms | TOP=L2:L3=L2/L4:L6=L5/L7:BOTTOM=L7 |
| PE_CLK_100M_DR5_2_R_N | PE_CLK_100M_DR5_2_R-DIFF1 | PAIR | 1 | 6.88 | 5 | 10 | 5 | 12 | 20 | 36 | 12 | 12 | 20 | 12 | 5.13 | 85 Ohms | TOP=L2:L3=L2/L4:L6=L5/L7:BOTTOM=L7 |
| PE_CLK_100M_DR5_2_R_N | PE_CLK_100M_DR5_2_R-DIFF1 | PAIR | 2 | 6.5 | 5 | 10 | 5 | 12 | 20 | 25 | 12 | 12 | 20 | 12 | 7.5 | 85 Ohms | TOP=L2:L3=L2/L4:L6=L5/L7:BOTTOM=L7 |
| PE_CLK_100M_DR5_2_R_N | PE_CLK_100M_DR5_2_R-DIFF1 | PAIR | 3 | 6.5 | 5 | 10 | 5 | 12 | 20 | 25 | 12 | 12 | 20 | 12 | 7.5 | 85 Ohms | TOP=L2:L3=L2/L4:L6=L5/L7:BOTTOM=L7 |
| PE_CLK_100M_DR5_2_R_N | PE_CLK_100M_DR5_2_R-DIFF1 | PAIR | 4 | 6.5 | 5 | 10 | 5 | 12 | 20 | 25 | 12 | 12 | 20 | 12 | 7.5 | 85 Ohms | TOP=L2:L3=L2/L4:L6=L5/L7:BOTTOM=L7 |
| PE_CLK_100M_DR5_2_R_N | PE_CLK_100M_DR5_2_R-DIFF1 | PAIR | 5 | 6.5 | 5 | 10 | 5 | 12 | 20 | 25 | 12 | 12 | 20 | 12 | 7.5 | 85 Ohms | TOP=L2:L3=L2/L4:L6=L5/L7:BOTTOM=L7 |
| PE_CLK_100M_DR5_2_R_N | PE_CLK_100M_DR5_2_R-DIFF1 | PAIR | 6 | 6.5 | 5 | 10 | 5 | 12 | 20 | 25 | 12 | 12 | 20 | 12 | 7.5 | 85 Ohms | TOP=L2:L3=L2/L4:L6=L5/L7:BOTTOM=L7 |
| PE_CLK_100M_DR5_2_R_N | PE_CLK_100M_DR5_2_R-DIFF1 | PAIR | 7 | 6.5 | 5 | 10 | 5 | 12 | 20 | 25 | 12 | 12 | 20 | 12 | 7.5 | 85 Ohms | TOP=L2:L3=L2/L4:L6=L5/L7:BOTTOM=L7 |
| PE_CLK_100M_DR5_2_R_N | PE_CLK_100M_DR5_2_R-DIFF1 | PAIR | 8 | 6.88 | 5 | 10 | 5 | 12 | 20 | 36 | 12 | 12 | 20 | 12 | 5.13 | 85 Ohms | TOP=L2:L3=L2/L4:L6=L5/L7:BOTTOM=L7 |
| PE_CLK_100M_DR5_2_R_P | PE_CLK_100M_DR5_2_R-DIFF1 | PAIR | 1 | 6.88 | 5 | 10 | 5 | 12 | 20 | 36 | 12 | 12 | 20 | 12 | 5.13 | 85 Ohms | TOP=L2:L3=L2/L4:L6=L5/L7:BOTTOM=L7 |
| PE_CLK_100M_DR5_2_R_P | PE_CLK_100M_DR5_2_R-DIFF1 | PAIR | 2 | 6.5 | 5 | 10 | 5 | 12 | 20 | 25 | 12 | 12 | 20 | 12 | 7.5 | 85 Ohms | TOP=L2:L3=L2/L4:L6=L5/L7:BOTTOM=L7 |
| PE_CLK_100M_DR5_2_R_P | PE_CLK_100M_DR5_2_R-DIFF1 | PAIR | 3 | 6.5 | 5 | 10 | 5 | 12 | 20 | 25 | 12 | 12 | 20 | 12 | 7.5 | 85 Ohms | TOP=L2:L3=L2/L4:L6=L5/L7:BOTTOM=L7 |
| PE_CLK_100M_DR5_2_R_P | PE_CLK_100M_DR5_2_R-DIFF1 | PAIR | 4 | 6.5 | 5 | 10 | 5 | 12 | 20 | 25 | 12 | 12 | 20 | 12 | 7.5 | 85 Ohms | TOP=L2:L3=L2/L4:L6=L5/L7:BOTTOM=L7 |
| PE_CLK_100M_DR5_2_R_P | PE_CLK_100M_DR5_2_R-DIFF1 | PAIR | 5 | 6.5 | 5 | 10 | 5 | 12 | 20 | 25 | 12 | 12 | 20 | 12 | 7.5 | 85 Ohms | TOP=L2:L3=L2/L4:L6=L5/L7:BOTTOM=L7 |
| PE_CLK_100M_DR5_2_R_P | PE_CLK_100M_DR5_2_R-DIFF1 | PAIR | 6 | 6.5 | 5 | 10 | 5 | 12 | 20 | 25 | 12 | 12 | 20 | 12 | 7.5 | 85 Ohms | TOP=L2:L3=L2/L4:L6=L5/L7:BOTTOM=L7 |
| PE_CLK_100M_DR5_2_R_P | PE_CLK_100M_DR5_2_R-DIFF1 | PAIR | 7 | 6.5 | 5 | 10 | 5 | 12 | 20 | 25 | 12 | 12 | 20 | 12 | 7.5 | 85 Ohms | TOP=L2:L3=L2/L4:L6=L5/L7:BOTTOM=L7 |
| PE_CLK_100M_DR5_2_R_P | PE_CLK_100M_DR5_2_R-DIFF1 | PAIR | 8 | 6.88 | 5 | 10 | 5 | 12 | 20 | 36 | 12 | 12 | 20 | 12 | 5.13 | 85 Ohms | TOP=L2:L3=L2/L4:L6=L5/L7:BOTTOM=L7 |
| PE_CLK_100M_DR6_1_R_N | PE_CLK_100M_DR6_1_R-DIFF1 | PAIR | 1 | 6.88 | 5 | 10 | 5 | 12 | 20 | 36 | 12 | 12 | 20 | 12 | 5.13 | 85 Ohms | TOP=L2:L3=L2/L4:L6=L5/L7:BOTTOM=L7 |
| PE_CLK_100M_DR6_1_R_N | PE_CLK_100M_DR6_1_R-DIFF1 | PAIR | 2 | 6.5 | 5 | 10 | 5 | 12 | 20 | 25 | 12 | 12 | 20 | 12 | 7.5 | 85 Ohms | TOP=L2:L3=L2/L4:L6=L5/L7:BOTTOM=L7 |
| PE_CLK_100M_DR6_1_R_N | PE_CLK_100M_DR6_1_R-DIFF1 | PAIR | 3 | 6.5 | 5 | 10 | 5 | 12 | 20 | 25 | 12 | 12 | 20 | 12 | 7.5 | 85 Ohms | TOP=L2:L3=L2/L4:L6=L5/L7:BOTTOM=L7 |
| PE_CLK_100M_DR6_1_R_N | PE_CLK_100M_DR6_1_R-DIFF1 | PAIR | 4 | 6.5 | 5 | 10 | 5 | 12 | 20 | 25 | 12 | 12 | 20 | 12 | 7.5 | 85 Ohms | TOP=L2:L3=L2/L4:L6=L5/L7:BOTTOM=L7 |
| PE_CLK_100M_DR6_1_R_N | PE_CLK_100M_DR6_1_R-DIFF1 | PAIR | 5 | 6.5 | 5 | 10 | 5 | 12 | 20 | 25 | 12 | 12 | 20 | 12 | 7.5 | 85 Ohms | TOP=L2:L3=L2/L4:L6=L5/L7:BOTTOM=L7 |
| PE_CLK_100M_DR6_1_R_N | PE_CLK_100M_DR6_1_R-DIFF1 | PAIR | 6 | 6.5 | 5 | 10 | 5 | 12 | 20 | 25 | 12 | 12 | 20 | 12 | 7.5 | 85 Ohms | TOP=L2:L3=L2/L4:L6=L5/L7:BOTTOM=L7 |
| PE_CLK_100M_DR6_1_R_N | PE_CLK_100M_DR6_1_R-DIFF1 | PAIR | 7 | 6.5 | 5 | 10 | 5 | 12 | 20 | 25 | 12 | 12 | 20 | 12 | 7.5 | 85 Ohms | TOP=L2:L3=L2/L4:L6=L5/L7:BOTTOM=L7 |
| PE_CLK_100M_DR6_1_R_N | PE_CLK_100M_DR6_1_R-DIFF1 | PAIR | 8 | 6.88 | 5 | 10 | 5 | 12 | 20 | 36 | 12 | 12 | 20 | 12 | 5.13 | 85 Ohms | TOP=L2:L3=L2/L4:L6=L5/L7:BOTTOM=L7 |
| PE_CLK_100M_DR6_1_R_P | PE_CLK_100M_DR6_1_R-DIFF1 | PAIR | 1 | 6.88 | 5 | 10 | 5 | 12 | 20 | 36 | 12 | 12 | 20 | 12 | 5.13 | 85 Ohms | TOP=L2:L3=L2/L4:L6=L5/L7:BOTTOM=L7 |
| PE_CLK_100M_DR6_1_R_P | PE_CLK_100M_DR6_1_R-DIFF1 | PAIR | 2 | 6.5 | 5 | 10 | 5 | 12 | 20 | 25 | 12 | 12 | 20 | 12 | 7.5 | 85 Ohms | TOP=L2:L3=L2/L4:L6=L5/L7:BOTTOM=L7 |
| PE_CLK_100M_DR6_1_R_P | PE_CLK_100M_DR6_1_R-DIFF1 | PAIR | 3 | 6.5 | 5 | 10 | 5 | 12 | 20 | 25 | 12 | 12 | 20 | 12 | 7.5 | 85 Ohms | TOP=L2:L3=L2/L4:L6=L5/L7:BOTTOM=L7 |
| PE_CLK_100M_DR6_1_R_P | PE_CLK_100M_DR6_1_R-DIFF1 | PAIR | 4 | 6.5 | 5 | 10 | 5 | 12 | 20 | 25 | 12 | 12 | 20 | 12 | 7.5 | 85 Ohms | TOP=L2:L3=L2/L4:L6=L5/L7:BOTTOM=L7 |
| PE_CLK_100M_DR6_1_R_P | PE_CLK_100M_DR6_1_R-DIFF1 | PAIR | 5 | 6.5 | 5 | 10 | 5 | 12 | 20 | 25 | 12 | 12 | 20 | 12 | 7.5 | 85 Ohms | TOP=L2:L3=L2/L4:L6=L5/L7:BOTTOM=L7 |
| PE_CLK_100M_DR6_1_R_P | PE_CLK_100M_DR6_1_R-DIFF1 | PAIR | 6 | 6.5 | 5 | 10 | 5 | 12 | 20 | 25 | 12 | 12 | 20 | 12 | 7.5 | 85 Ohms | TOP=L2:L3=L2/L4:L6=L5/L7:BOTTOM=L7 |
| PE_CLK_100M_DR6_1_R_P | PE_CLK_100M_DR6_1_R-DIFF1 | PAIR | 7 | 6.5 | 5 | 10 | 5 | 12 | 20 | 25 | 12 | 12 | 20 | 12 | 7.5 | 85 Ohms | TOP=L2:L3=L2/L4:L6=L5/L7:BOTTOM=L7 |
| PE_CLK_100M_DR6_1_R_P | PE_CLK_100M_DR6_1_R-DIFF1 | PAIR | 8 | 6.88 | 5 | 10 | 5 | 12 | 20 | 36 | 12 | 12 | 20 | 12 | 5.13 | 85 Ohms | TOP=L2:L3=L2/L4:L6=L5/L7:BOTTOM=L7 |
| PE_CLK_100M_DR6_2_R_N | PE_CLK_100M_DR6_2_R-DIFF1 | PAIR | 1 | 6.88 | 5 | 10 | 5 | 12 | 20 | 36 | 12 | 12 | 20 | 12 | 5.13 | 85 Ohms | TOP=L2:L3=L2/L4:L6=L5/L7:BOTTOM=L7 |
| PE_CLK_100M_DR6_2_R_N | PE_CLK_100M_DR6_2_R-DIFF1 | PAIR | 2 | 6.5 | 5 | 10 | 5 | 12 | 20 | 25 | 12 | 12 | 20 | 12 | 7.5 | 85 Ohms | TOP=L2:L3=L2/L4:L6=L5/L7:BOTTOM=L7 |
| PE_CLK_100M_DR6_2_R_N | PE_CLK_100M_DR6_2_R-DIFF1 | PAIR | 3 | 6.5 | 5 | 10 | 5 | 12 | 20 | 25 | 12 | 12 | 20 | 12 | 7.5 | 85 Ohms | TOP=L2:L3=L2/L4:L6=L5/L7:BOTTOM=L7 |
| PE_CLK_100M_DR6_2_R_N | PE_CLK_100M_DR6_2_R-DIFF1 | PAIR | 4 | 6.5 | 5 | 10 | 5 | 12 | 20 | 25 | 12 | 12 | 20 | 12 | 7.5 | 85 Ohms | TOP=L2:L3=L2/L4:L6=L5/L7:BOTTOM=L7 |
| PE_CLK_100M_DR6_2_R_N | PE_CLK_100M_DR6_2_R-DIFF1 | PAIR | 5 | 6.5 | 5 | 10 | 5 | 12 | 20 | 25 | 12 | 12 | 20 | 12 | 7.5 | 85 Ohms | TOP=L2:L3=L2/L4:L6=L5/L7:BOTTOM=L7 |
| PE_CLK_100M_DR6_2_R_N | PE_CLK_100M_DR6_2_R-DIFF1 | PAIR | 6 | 6.5 | 5 | 10 | 5 | 12 | 20 | 25 | 12 | 12 | 20 | 12 | 7.5 | 85 Ohms | TOP=L2:L3=L2/L4:L6=L5/L7:BOTTOM=L7 |
| PE_CLK_100M_DR6_2_R_N | PE_CLK_100M_DR6_2_R-DIFF1 | PAIR | 7 | 6.5 | 5 | 10 | 5 | 12 | 20 | 25 | 12 | 12 | 20 | 12 | 7.5 | 85 Ohms | TOP=L2:L3=L2/L4:L6=L5/L7:BOTTOM=L7 |
| PE_CLK_100M_DR6_2_R_N | PE_CLK_100M_DR6_2_R-DIFF1 | PAIR | 8 | 6.88 | 5 | 10 | 5 | 12 | 20 | 36 | 12 | 12 | 20 | 12 | 5.13 | 85 Ohms | TOP=L2:L3=L2/L4:L6=L5/L7:BOTTOM=L7 |
| PE_CLK_100M_DR6_2_R_P | PE_CLK_100M_DR6_2_R-DIFF1 | PAIR | 1 | 6.88 | 5 | 10 | 5 | 12 | 20 | 36 | 12 | 12 | 20 | 12 | 5.13 | 85 Ohms | TOP=L2:L3=L2/L4:L6=L5/L7:BOTTOM=L7 |
| PE_CLK_100M_DR6_2_R_P | PE_CLK_100M_DR6_2_R-DIFF1 | PAIR | 2 | 6.5 | 5 | 10 | 5 | 12 | 20 | 25 | 12 | 12 | 20 | 12 | 7.5 | 85 Ohms | TOP=L2:L3=L2/L4:L6=L5/L7:BOTTOM=L7 |
| PE_CLK_100M_DR6_2_R_P | PE_CLK_100M_DR6_2_R-DIFF1 | PAIR | 3 | 6.5 | 5 | 10 | 5 | 12 | 20 | 25 | 12 | 12 | 20 | 12 | 7.5 | 85 Ohms | TOP=L2:L3=L2/L4:L6=L5/L7:BOTTOM=L7 |
| PE_CLK_100M_DR6_2_R_P | PE_CLK_100M_DR6_2_R-DIFF1 | PAIR | 4 | 6.5 | 5 | 10 | 5 | 12 | 20 | 25 | 12 | 12 | 20 | 12 | 7.5 | 85 Ohms | TOP=L2:L3=L2/L4:L6=L5/L7:BOTTOM=L7 |
| PE_CLK_100M_DR6_2_R_P | PE_CLK_100M_DR6_2_R-DIFF1 | PAIR | 5 | 6.5 | 5 | 10 | 5 | 12 | 20 | 25 | 12 | 12 | 20 | 12 | 7.5 | 85 Ohms | TOP=L2:L3=L2/L4:L6=L5/L7:BOTTOM=L7 |
| PE_CLK_100M_DR6_2_R_P | PE_CLK_100M_DR6_2_R-DIFF1 | PAIR | 6 | 6.5 | 5 | 10 | 5 | 12 | 20 | 25 | 12 | 12 | 20 | 12 | 7.5 | 85 Ohms | TOP=L2:L3=L2/L4:L6=L5/L7:BOTTOM=L7 |
| PE_CLK_100M_DR6_2_R_P | PE_CLK_100M_DR6_2_R-DIFF1 | PAIR | 7 | 6.5 | 5 | 10 | 5 | 12 | 20 | 25 | 12 | 12 | 20 | 12 | 7.5 | 85 Ohms | TOP=L2:L3=L2/L4:L6=L5/L7:BOTTOM=L7 |
| PE_CLK_100M_DR6_2_R_P | PE_CLK_100M_DR6_2_R-DIFF1 | PAIR | 8 | 6.88 | 5 | 10 | 5 | 12 | 20 | 36 | 12 | 12 | 20 | 12 | 5.13 | 85 Ohms | TOP=L2:L3=L2/L4:L6=L5/L7:BOTTOM=L7 |
| PE_CLK_100M_DR7_1_R_N | PE_CLK_100M_DR7_1_R-DIFF1 | PAIR | 1 | 6.88 | 5 | 10 | 5 | 12 | 20 | 36 | 12 | 12 | 20 | 12 | 5.13 | 85 Ohms | TOP=L2:L3=L2/L4:L6=L5/L7:BOTTOM=L7 |
| PE_CLK_100M_DR7_1_R_N | PE_CLK_100M_DR7_1_R-DIFF1 | PAIR | 2 | 6.5 | 5 | 10 | 5 | 12 | 20 | 25 | 12 | 12 | 20 | 12 | 7.5 | 85 Ohms | TOP=L2:L3=L2/L4:L6=L5/L7:BOTTOM=L7 |
| PE_CLK_100M_DR7_1_R_N | PE_CLK_100M_DR7_1_R-DIFF1 | PAIR | 3 | 6.5 | 5 | 10 | 5 | 12 | 20 | 25 | 12 | 12 | 20 | 12 | 7.5 | 85 Ohms | TOP=L2:L3=L2/L4:L6=L5/L7:BOTTOM=L7 |
| PE_CLK_100M_DR7_1_R_N | PE_CLK_100M_DR7_1_R-DIFF1 | PAIR | 4 | 6.5 | 5 | 10 | 5 | 12 | 20 | 25 | 12 | 12 | 20 | 12 | 7.5 | 85 Ohms | TOP=L2:L3=L2/L4:L6=L5/L7:BOTTOM=L7 |
| PE_CLK_100M_DR7_1_R_N | PE_CLK_100M_DR7_1_R-DIFF1 | PAIR | 5 | 6.5 | 5 | 10 | 5 | 12 | 20 | 25 | 12 | 12 | 20 | 12 | 7.5 | 85 Ohms | TOP=L2:L3=L2/L4:L6=L5/L7:BOTTOM=L7 |
| PE_CLK_100M_DR7_1_R_N | PE_CLK_100M_DR7_1_R-DIFF1 | PAIR | 6 | 6.5 | 5 | 10 | 5 | 12 | 20 | 25 | 12 | 12 | 20 | 12 | 7.5 | 85 Ohms | TOP=L2:L3=L2/L4:L6=L5/L7:BOTTOM=L7 |
| PE_CLK_100M_DR7_1_R_N | PE_CLK_100M_DR7_1_R-DIFF1 | PAIR | 7 | 6.5 | 5 | 10 | 5 | 12 | 20 | 25 | 12 | 12 | 20 | 12 | 7.5 | 85 Ohms | TOP=L2:L3=L2/L4:L6=L5/L7:BOTTOM=L7 |
| PE_CLK_100M_DR7_1_R_N | PE_CLK_100M_DR7_1_R-DIFF1 | PAIR | 8 | 6.88 | 5 | 10 | 5 | 12 | 20 | 36 | 12 | 12 | 20 | 12 | 5.13 | 85 Ohms | TOP=L2:L3=L2/L4:L6=L5/L7:BOTTOM=L7 |
| PE_CLK_100M_DR7_1_R_P | PE_CLK_100M_DR7_1_R-DIFF1 | PAIR | 1 | 6.88 | 5 | 10 | 5 | 12 | 20 | 36 | 12 | 12 | 20 | 12 | 5.13 | 85 Ohms | TOP=L2:L3=L2/L4:L6=L5/L7:BOTTOM=L7 |
| PE_CLK_100M_DR7_1_R_P | PE_CLK_100M_DR7_1_R-DIFF1 | PAIR | 2 | 6.5 | 5 | 10 | 5 | 12 | 20 | 25 | 12 | 12 | 20 | 12 | 7.5 | 85 Ohms | TOP=L2:L3=L2/L4:L6=L5/L7:BOTTOM=L7 |
| PE_CLK_100M_DR7_1_R_P | PE_CLK_100M_DR7_1_R-DIFF1 | PAIR | 3 | 6.5 | 5 | 10 | 5 | 12 | 20 | 25 | 12 | 12 | 20 | 12 | 7.5 | 85 Ohms | TOP=L2:L3=L2/L4:L6=L5/L7:BOTTOM=L7 |
| PE_CLK_100M_DR7_1_R_P | PE_CLK_100M_DR7_1_R-DIFF1 | PAIR | 4 | 6.5 | 5 | 10 | 5 | 12 | 20 | 25 | 12 | 12 | 20 | 12 | 7.5 | 85 Ohms | TOP=L2:L3=L2/L4:L6=L5/L7:BOTTOM=L7 |
| PE_CLK_100M_DR7_1_R_P | PE_CLK_100M_DR7_1_R-DIFF1 | PAIR | 5 | 6.5 | 5 | 10 | 5 | 12 | 20 | 25 | 12 | 12 | 20 | 12 | 7.5 | 85 Ohms | TOP=L2:L3=L2/L4:L6=L5/L7:BOTTOM=L7 |
| PE_CLK_100M_DR7_1_R_P | PE_CLK_100M_DR7_1_R-DIFF1 | PAIR | 6 | 6.5 | 5 | 10 | 5 | 12 | 20 | 25 | 12 | 12 | 20 | 12 | 7.5 | 85 Ohms | TOP=L2:L3=L2/L4:L6=L5/L7:BOTTOM=L7 |
| PE_CLK_100M_DR7_1_R_P | PE_CLK_100M_DR7_1_R-DIFF1 | PAIR | 7 | 6.5 | 5 | 10 | 5 | 12 | 20 | 25 | 12 | 12 | 20 | 12 | 7.5 | 85 Ohms | TOP=L2:L3=L2/L4:L6=L5/L7:BOTTOM=L7 |
| PE_CLK_100M_DR7_1_R_P | PE_CLK_100M_DR7_1_R-DIFF1 | PAIR | 8 | 6.88 | 5 | 10 | 5 | 12 | 20 | 36 | 12 | 12 | 20 | 12 | 5.13 | 85 Ohms | TOP=L2:L3=L2/L4:L6=L5/L7:BOTTOM=L7 |
| PE_CLK_100M_DR7_2_R_N | PE_CLK_100M_DR7_2_R-DIFF1 | PAIR | 1 | 6.88 | 5 | 10 | 5 | 12 | 20 | 36 | 12 | 12 | 20 | 12 | 5.13 | 85 Ohms | TOP=L2:L3=L2/L4:L6=L5/L7:BOTTOM=L7 |
| PE_CLK_100M_DR7_2_R_N | PE_CLK_100M_DR7_2_R-DIFF1 | PAIR | 2 | 6.5 | 5 | 10 | 5 | 12 | 20 | 25 | 12 | 12 | 20 | 12 | 7.5 | 85 Ohms | TOP=L2:L3=L2/L4:L6=L5/L7:BOTTOM=L7 |
| PE_CLK_100M_DR7_2_R_N | PE_CLK_100M_DR7_2_R-DIFF1 | PAIR | 3 | 6.5 | 5 | 10 | 5 | 12 | 20 | 25 | 12 | 12 | 20 | 12 | 7.5 | 85 Ohms | TOP=L2:L3=L2/L4:L6=L5/L7:BOTTOM=L7 |
| PE_CLK_100M_DR7_2_R_N | PE_CLK_100M_DR7_2_R-DIFF1 | PAIR | 4 | 6.5 | 5 | 10 | 5 | 12 | 20 | 25 | 12 | 12 | 20 | 12 | 7.5 | 85 Ohms | TOP=L2:L3=L2/L4:L6=L5/L7:BOTTOM=L7 |
| PE_CLK_100M_DR7_2_R_N | PE_CLK_100M_DR7_2_R-DIFF1 | PAIR | 5 | 6.5 | 5 | 10 | 5 | 12 | 20 | 25 | 12 | 12 | 20 | 12 | 7.5 | 85 Ohms | TOP=L2:L3=L2/L4:L6=L5/L7:BOTTOM=L7 |
| PE_CLK_100M_DR7_2_R_N | PE_CLK_100M_DR7_2_R-DIFF1 | PAIR | 6 | 6.5 | 5 | 10 | 5 | 12 | 20 | 25 | 12 | 12 | 20 | 12 | 7.5 | 85 Ohms | TOP=L2:L3=L2/L4:L6=L5/L7:BOTTOM=L7 |
| PE_CLK_100M_DR7_2_R_N | PE_CLK_100M_DR7_2_R-DIFF1 | PAIR | 7 | 6.5 | 5 | 10 | 5 | 12 | 20 | 25 | 12 | 12 | 20 | 12 | 7.5 | 85 Ohms | TOP=L2:L3=L2/L4:L6=L5/L7:BOTTOM=L7 |
| PE_CLK_100M_DR7_2_R_N | PE_CLK_100M_DR7_2_R-DIFF1 | PAIR | 8 | 6.88 | 5 | 10 | 5 | 12 | 20 | 36 | 12 | 12 | 20 | 12 | 5.13 | 85 Ohms | TOP=L2:L3=L2/L4:L6=L5/L7:BOTTOM=L7 |
| PE_CLK_100M_DR7_2_R_P | PE_CLK_100M_DR7_2_R-DIFF1 | PAIR | 1 | 6.88 | 5 | 10 | 5 | 12 | 20 | 36 | 12 | 12 | 20 | 12 | 5.13 | 85 Ohms | TOP=L2:L3=L2/L4:L6=L5/L7:BOTTOM=L7 |
| PE_CLK_100M_DR7_2_R_P | PE_CLK_100M_DR7_2_R-DIFF1 | PAIR | 2 | 6.5 | 5 | 10 | 5 | 12 | 20 | 25 | 12 | 12 | 20 | 12 | 7.5 | 85 Ohms | TOP=L2:L3=L2/L4:L6=L5/L7:BOTTOM=L7 |
| PE_CLK_100M_DR7_2_R_P | PE_CLK_100M_DR7_2_R-DIFF1 | PAIR | 3 | 6.5 | 5 | 10 | 5 | 12 | 20 | 25 | 12 | 12 | 20 | 12 | 7.5 | 85 Ohms | TOP=L2:L3=L2/L4:L6=L5/L7:BOTTOM=L7 |
| PE_CLK_100M_DR7_2_R_P | PE_CLK_100M_DR7_2_R-DIFF1 | PAIR | 4 | 6.5 | 5 | 10 | 5 | 12 | 20 | 25 | 12 | 12 | 20 | 12 | 7.5 | 85 Ohms | TOP=L2:L3=L2/L4:L6=L5/L7:BOTTOM=L7 |
| PE_CLK_100M_DR7_2_R_P | PE_CLK_100M_DR7_2_R-DIFF1 | PAIR | 5 | 6.5 | 5 | 10 | 5 | 12 | 20 | 25 | 12 | 12 | 20 | 12 | 7.5 | 85 Ohms | TOP=L2:L3=L2/L4:L6=L5/L7:BOTTOM=L7 |
| PE_CLK_100M_DR7_2_R_P | PE_CLK_100M_DR7_2_R-DIFF1 | PAIR | 6 | 6.5 | 5 | 10 | 5 | 12 | 20 | 25 | 12 | 12 | 20 | 12 | 7.5 | 85 Ohms | TOP=L2:L3=L2/L4:L6=L5/L7:BOTTOM=L7 |
| PE_CLK_100M_DR7_2_R_P | PE_CLK_100M_DR7_2_R-DIFF1 | PAIR | 7 | 6.5 | 5 | 10 | 5 | 12 | 20 | 25 | 12 | 12 | 20 | 12 | 7.5 | 85 Ohms | TOP=L2:L3=L2/L4:L6=L5/L7:BOTTOM=L7 |
| PE_CLK_100M_DR7_2_R_P | PE_CLK_100M_DR7_2_R-DIFF1 | PAIR | 8 | 6.88 | 5 | 10 | 5 | 12 | 20 | 36 | 12 | 12 | 20 | 12 | 5.13 | 85 Ohms | TOP=L2:L3=L2/L4:L6=L5/L7:BOTTOM=L7 |
| PE_CLK_100M_DR8_1_R_N | PE_CLK_100M_DR8_1_R-DIFF1 | PAIR | 1 | 6.88 | 5 | 10 | 5 | 12 | 20 | 36 | 12 | 12 | 20 | 12 | 5.13 | 85 Ohms | TOP=L2:L3=L2/L4:L6=L5/L7:BOTTOM=L7 |
| PE_CLK_100M_DR8_1_R_N | PE_CLK_100M_DR8_1_R-DIFF1 | PAIR | 2 | 6.5 | 5 | 10 | 5 | 12 | 20 | 25 | 12 | 12 | 20 | 12 | 7.5 | 85 Ohms | TOP=L2:L3=L2/L4:L6=L5/L7:BOTTOM=L7 |
| PE_CLK_100M_DR8_1_R_N | PE_CLK_100M_DR8_1_R-DIFF1 | PAIR | 3 | 6.5 | 5 | 10 | 5 | 12 | 20 | 25 | 12 | 12 | 20 | 12 | 7.5 | 85 Ohms | TOP=L2:L3=L2/L4:L6=L5/L7:BOTTOM=L7 |
| PE_CLK_100M_DR8_1_R_N | PE_CLK_100M_DR8_1_R-DIFF1 | PAIR | 4 | 6.5 | 5 | 10 | 5 | 12 | 20 | 25 | 12 | 12 | 20 | 12 | 7.5 | 85 Ohms | TOP=L2:L3=L2/L4:L6=L5/L7:BOTTOM=L7 |
| PE_CLK_100M_DR8_1_R_N | PE_CLK_100M_DR8_1_R-DIFF1 | PAIR | 5 | 6.5 | 5 | 10 | 5 | 12 | 20 | 25 | 12 | 12 | 20 | 12 | 7.5 | 85 Ohms | TOP=L2:L3=L2/L4:L6=L5/L7:BOTTOM=L7 |
| PE_CLK_100M_DR8_1_R_N | PE_CLK_100M_DR8_1_R-DIFF1 | PAIR | 6 | 6.5 | 5 | 10 | 5 | 12 | 20 | 25 | 12 | 12 | 20 | 12 | 7.5 | 85 Ohms | TOP=L2:L3=L2/L4:L6=L5/L7:BOTTOM=L7 |
| PE_CLK_100M_DR8_1_R_N | PE_CLK_100M_DR8_1_R-DIFF1 | PAIR | 7 | 6.5 | 5 | 10 | 5 | 12 | 20 | 25 | 12 | 12 | 20 | 12 | 7.5 | 85 Ohms | TOP=L2:L3=L2/L4:L6=L5/L7:BOTTOM=L7 |
| PE_CLK_100M_DR8_1_R_N | PE_CLK_100M_DR8_1_R-DIFF1 | PAIR | 8 | 6.88 | 5 | 10 | 5 | 12 | 20 | 36 | 12 | 12 | 20 | 12 | 5.13 | 85 Ohms | TOP=L2:L3=L2/L4:L6=L5/L7:BOTTOM=L7 |
| PE_CLK_100M_DR8_1_R_P | PE_CLK_100M_DR8_1_R-DIFF1 | PAIR | 1 | 6.88 | 5 | 10 | 5 | 12 | 20 | 36 | 12 | 12 | 20 | 12 | 5.13 | 85 Ohms | TOP=L2:L3=L2/L4:L6=L5/L7:BOTTOM=L7 |
| PE_CLK_100M_DR8_1_R_P | PE_CLK_100M_DR8_1_R-DIFF1 | PAIR | 2 | 6.5 | 5 | 10 | 5 | 12 | 20 | 25 | 12 | 12 | 20 | 12 | 7.5 | 85 Ohms | TOP=L2:L3=L2/L4:L6=L5/L7:BOTTOM=L7 |
| PE_CLK_100M_DR8_1_R_P | PE_CLK_100M_DR8_1_R-DIFF1 | PAIR | 3 | 6.5 | 5 | 10 | 5 | 12 | 20 | 25 | 12 | 12 | 20 | 12 | 7.5 | 85 Ohms | TOP=L2:L3=L2/L4:L6=L5/L7:BOTTOM=L7 |
| PE_CLK_100M_DR8_1_R_P | PE_CLK_100M_DR8_1_R-DIFF1 | PAIR | 4 | 6.5 | 5 | 10 | 5 | 12 | 20 | 25 | 12 | 12 | 20 | 12 | 7.5 | 85 Ohms | TOP=L2:L3=L2/L4:L6=L5/L7:BOTTOM=L7 |
| PE_CLK_100M_DR8_1_R_P | PE_CLK_100M_DR8_1_R-DIFF1 | PAIR | 5 | 6.5 | 5 | 10 | 5 | 12 | 20 | 25 | 12 | 12 | 20 | 12 | 7.5 | 85 Ohms | TOP=L2:L3=L2/L4:L6=L5/L7:BOTTOM=L7 |
| PE_CLK_100M_DR8_1_R_P | PE_CLK_100M_DR8_1_R-DIFF1 | PAIR | 6 | 6.5 | 5 | 10 | 5 | 12 | 20 | 25 | 12 | 12 | 20 | 12 | 7.5 | 85 Ohms | TOP=L2:L3=L2/L4:L6=L5/L7:BOTTOM=L7 |
| PE_CLK_100M_DR8_1_R_P | PE_CLK_100M_DR8_1_R-DIFF1 | PAIR | 7 | 6.5 | 5 | 10 | 5 | 12 | 20 | 25 | 12 | 12 | 20 | 12 | 7.5 | 85 Ohms | TOP=L2:L3=L2/L4:L6=L5/L7:BOTTOM=L7 |
| PE_CLK_100M_DR8_1_R_P | PE_CLK_100M_DR8_1_R-DIFF1 | PAIR | 8 | 6.88 | 5 | 10 | 5 | 12 | 20 | 36 | 12 | 12 | 20 | 12 | 5.13 | 85 Ohms | TOP=L2:L3=L2/L4:L6=L5/L7:BOTTOM=L7 |
| PE_CLK_100M_DR8_2_R_N | PE_CLK_100M_DR8_2_R-DIFF1 | PAIR | 1 | 6.88 | 5 | 10 | 5 | 12 | 20 | 36 | 12 | 12 | 20 | 12 | 5.13 | 85 Ohms | TOP=L2:L3=L2/L4:L6=L5/L7:BOTTOM=L7 |
| PE_CLK_100M_DR8_2_R_N | PE_CLK_100M_DR8_2_R-DIFF1 | PAIR | 2 | 6.5 | 5 | 10 | 5 | 12 | 20 | 25 | 12 | 12 | 20 | 12 | 7.5 | 85 Ohms | TOP=L2:L3=L2/L4:L6=L5/L7:BOTTOM=L7 |
| PE_CLK_100M_DR8_2_R_N | PE_CLK_100M_DR8_2_R-DIFF1 | PAIR | 3 | 6.5 | 5 | 10 | 5 | 12 | 20 | 25 | 12 | 12 | 20 | 12 | 7.5 | 85 Ohms | TOP=L2:L3=L2/L4:L6=L5/L7:BOTTOM=L7 |
| PE_CLK_100M_DR8_2_R_N | PE_CLK_100M_DR8_2_R-DIFF1 | PAIR | 4 | 6.5 | 5 | 10 | 5 | 12 | 20 | 25 | 12 | 12 | 20 | 12 | 7.5 | 85 Ohms | TOP=L2:L3=L2/L4:L6=L5/L7:BOTTOM=L7 |
| PE_CLK_100M_DR8_2_R_N | PE_CLK_100M_DR8_2_R-DIFF1 | PAIR | 5 | 6.5 | 5 | 10 | 5 | 12 | 20 | 25 | 12 | 12 | 20 | 12 | 7.5 | 85 Ohms | TOP=L2:L3=L2/L4:L6=L5/L7:BOTTOM=L7 |
| PE_CLK_100M_DR8_2_R_N | PE_CLK_100M_DR8_2_R-DIFF1 | PAIR | 6 | 6.5 | 5 | 10 | 5 | 12 | 20 | 25 | 12 | 12 | 20 | 12 | 7.5 | 85 Ohms | TOP=L2:L3=L2/L4:L6=L5/L7:BOTTOM=L7 |
| PE_CLK_100M_DR8_2_R_N | PE_CLK_100M_DR8_2_R-DIFF1 | PAIR | 7 | 6.5 | 5 | 10 | 5 | 12 | 20 | 25 | 12 | 12 | 20 | 12 | 7.5 | 85 Ohms | TOP=L2:L3=L2/L4:L6=L5/L7:BOTTOM=L7 |
| PE_CLK_100M_DR8_2_R_N | PE_CLK_100M_DR8_2_R-DIFF1 | PAIR | 8 | 6.88 | 5 | 10 | 5 | 12 | 20 | 36 | 12 | 12 | 20 | 12 | 5.13 | 85 Ohms | TOP=L2:L3=L2/L4:L6=L5/L7:BOTTOM=L7 |
| PE_CLK_100M_DR8_2_R_P | PE_CLK_100M_DR8_2_R-DIFF1 | PAIR | 1 | 6.88 | 5 | 10 | 5 | 12 | 20 | 36 | 12 | 12 | 20 | 12 | 5.13 | 85 Ohms | TOP=L2:L3=L2/L4:L6=L5/L7:BOTTOM=L7 |
| PE_CLK_100M_DR8_2_R_P | PE_CLK_100M_DR8_2_R-DIFF1 | PAIR | 2 | 6.5 | 5 | 10 | 5 | 12 | 20 | 25 | 12 | 12 | 20 | 12 | 7.5 | 85 Ohms | TOP=L2:L3=L2/L4:L6=L5/L7:BOTTOM=L7 |
| PE_CLK_100M_DR8_2_R_P | PE_CLK_100M_DR8_2_R-DIFF1 | PAIR | 3 | 6.5 | 5 | 10 | 5 | 12 | 20 | 25 | 12 | 12 | 20 | 12 | 7.5 | 85 Ohms | TOP=L2:L3=L2/L4:L6=L5/L7:BOTTOM=L7 |
| PE_CLK_100M_DR8_2_R_P | PE_CLK_100M_DR8_2_R-DIFF1 | PAIR | 4 | 6.5 | 5 | 10 | 5 | 12 | 20 | 25 | 12 | 12 | 20 | 12 | 7.5 | 85 Ohms | TOP=L2:L3=L2/L4:L6=L5/L7:BOTTOM=L7 |
| PE_CLK_100M_DR8_2_R_P | PE_CLK_100M_DR8_2_R-DIFF1 | PAIR | 5 | 6.5 | 5 | 10 | 5 | 12 | 20 | 25 | 12 | 12 | 20 | 12 | 7.5 | 85 Ohms | TOP=L2:L3=L2/L4:L6=L5/L7:BOTTOM=L7 |
| PE_CLK_100M_DR8_2_R_P | PE_CLK_100M_DR8_2_R-DIFF1 | PAIR | 6 | 6.5 | 5 | 10 | 5 | 12 | 20 | 25 | 12 | 12 | 20 | 12 | 7.5 | 85 Ohms | TOP=L2:L3=L2/L4:L6=L5/L7:BOTTOM=L7 |
| PE_CLK_100M_DR8_2_R_P | PE_CLK_100M_DR8_2_R-DIFF1 | PAIR | 7 | 6.5 | 5 | 10 | 5 | 12 | 20 | 25 | 12 | 12 | 20 | 12 | 7.5 | 85 Ohms | TOP=L2:L3=L2/L4:L6=L5/L7:BOTTOM=L7 |
| PE_CLK_100M_DR8_2_R_P | PE_CLK_100M_DR8_2_R-DIFF1 | PAIR | 8 | 6.88 | 5 | 10 | 5 | 12 | 20 | 36 | 12 | 12 | 20 | 12 | 5.13 | 85 Ohms | TOP=L2:L3=L2/L4:L6=L5/L7:BOTTOM=L7 |
| PE_CLK_100M_DR9_1_R_N | PE_CLK_100M_DR9_1_R-DIFF1 | PAIR | 1 | 6.88 | 5 | 10 | 5 | 12 | 20 | 36 | 12 | 12 | 20 | 12 | 5.13 | 85 Ohms | TOP=L2:L3=L2/L4:L6=L5/L7:BOTTOM=L7 |
| PE_CLK_100M_DR9_1_R_N | PE_CLK_100M_DR9_1_R-DIFF1 | PAIR | 2 | 6.5 | 5 | 10 | 5 | 12 | 20 | 25 | 12 | 12 | 20 | 12 | 7.5 | 85 Ohms | TOP=L2:L3=L2/L4:L6=L5/L7:BOTTOM=L7 |
| PE_CLK_100M_DR9_1_R_N | PE_CLK_100M_DR9_1_R-DIFF1 | PAIR | 3 | 6.5 | 5 | 10 | 5 | 12 | 20 | 25 | 12 | 12 | 20 | 12 | 7.5 | 85 Ohms | TOP=L2:L3=L2/L4:L6=L5/L7:BOTTOM=L7 |
| PE_CLK_100M_DR9_1_R_N | PE_CLK_100M_DR9_1_R-DIFF1 | PAIR | 4 | 6.5 | 5 | 10 | 5 | 12 | 20 | 25 | 12 | 12 | 20 | 12 | 7.5 | 85 Ohms | TOP=L2:L3=L2/L4:L6=L5/L7:BOTTOM=L7 |
| PE_CLK_100M_DR9_1_R_N | PE_CLK_100M_DR9_1_R-DIFF1 | PAIR | 5 | 6.5 | 5 | 10 | 5 | 12 | 20 | 25 | 12 | 12 | 20 | 12 | 7.5 | 85 Ohms | TOP=L2:L3=L2/L4:L6=L5/L7:BOTTOM=L7 |
| PE_CLK_100M_DR9_1_R_N | PE_CLK_100M_DR9_1_R-DIFF1 | PAIR | 6 | 6.5 | 5 | 10 | 5 | 12 | 20 | 25 | 12 | 12 | 20 | 12 | 7.5 | 85 Ohms | TOP=L2:L3=L2/L4:L6=L5/L7:BOTTOM=L7 |
| PE_CLK_100M_DR9_1_R_N | PE_CLK_100M_DR9_1_R-DIFF1 | PAIR | 7 | 6.5 | 5 | 10 | 5 | 12 | 20 | 25 | 12 | 12 | 20 | 12 | 7.5 | 85 Ohms | TOP=L2:L3=L2/L4:L6=L5/L7:BOTTOM=L7 |
| PE_CLK_100M_DR9_1_R_N | PE_CLK_100M_DR9_1_R-DIFF1 | PAIR | 8 | 6.88 | 5 | 10 | 5 | 12 | 20 | 36 | 12 | 12 | 20 | 12 | 5.13 | 85 Ohms | TOP=L2:L3=L2/L4:L6=L5/L7:BOTTOM=L7 |
| PE_CLK_100M_DR9_1_R_P | PE_CLK_100M_DR9_1_R-DIFF1 | PAIR | 1 | 6.88 | 5 | 10 | 5 | 12 | 20 | 36 | 12 | 12 | 20 | 12 | 5.13 | 85 Ohms | TOP=L2:L3=L2/L4:L6=L5/L7:BOTTOM=L7 |
| PE_CLK_100M_DR9_1_R_P | PE_CLK_100M_DR9_1_R-DIFF1 | PAIR | 2 | 6.5 | 5 | 10 | 5 | 12 | 20 | 25 | 12 | 12 | 20 | 12 | 7.5 | 85 Ohms | TOP=L2:L3=L2/L4:L6=L5/L7:BOTTOM=L7 |
| PE_CLK_100M_DR9_1_R_P | PE_CLK_100M_DR9_1_R-DIFF1 | PAIR | 3 | 6.5 | 5 | 10 | 5 | 12 | 20 | 25 | 12 | 12 | 20 | 12 | 7.5 | 85 Ohms | TOP=L2:L3=L2/L4:L6=L5/L7:BOTTOM=L7 |
| PE_CLK_100M_DR9_1_R_P | PE_CLK_100M_DR9_1_R-DIFF1 | PAIR | 4 | 6.5 | 5 | 10 | 5 | 12 | 20 | 25 | 12 | 12 | 20 | 12 | 7.5 | 85 Ohms | TOP=L2:L3=L2/L4:L6=L5/L7:BOTTOM=L7 |
| PE_CLK_100M_DR9_1_R_P | PE_CLK_100M_DR9_1_R-DIFF1 | PAIR | 5 | 6.5 | 5 | 10 | 5 | 12 | 20 | 25 | 12 | 12 | 20 | 12 | 7.5 | 85 Ohms | TOP=L2:L3=L2/L4:L6=L5/L7:BOTTOM=L7 |
| PE_CLK_100M_DR9_1_R_P | PE_CLK_100M_DR9_1_R-DIFF1 | PAIR | 6 | 6.5 | 5 | 10 | 5 | 12 | 20 | 25 | 12 | 12 | 20 | 12 | 7.5 | 85 Ohms | TOP=L2:L3=L2/L4:L6=L5/L7:BOTTOM=L7 |
| PE_CLK_100M_DR9_1_R_P | PE_CLK_100M_DR9_1_R-DIFF1 | PAIR | 7 | 6.5 | 5 | 10 | 5 | 12 | 20 | 25 | 12 | 12 | 20 | 12 | 7.5 | 85 Ohms | TOP=L2:L3=L2/L4:L6=L5/L7:BOTTOM=L7 |
| PE_CLK_100M_DR9_1_R_P | PE_CLK_100M_DR9_1_R-DIFF1 | PAIR | 8 | 6.88 | 5 | 10 | 5 | 12 | 20 | 36 | 12 | 12 | 20 | 12 | 5.13 | 85 Ohms | TOP=L2:L3=L2/L4:L6=L5/L7:BOTTOM=L7 |
| PE_CLK_100M_DR9_2_R_N | PE_CLK_100M_DR9_2_R-DIFF1 | PAIR | 1 | 6.88 | 5 | 10 | 5 | 12 | 20 | 36 | 12 | 12 | 20 | 12 | 5.13 | 85 Ohms | TOP=L2:L3=L2/L4:L6=L5/L7:BOTTOM=L7 |
| PE_CLK_100M_DR9_2_R_N | PE_CLK_100M_DR9_2_R-DIFF1 | PAIR | 2 | 6.5 | 5 | 10 | 5 | 12 | 20 | 25 | 12 | 12 | 20 | 12 | 7.5 | 85 Ohms | TOP=L2:L3=L2/L4:L6=L5/L7:BOTTOM=L7 |
| PE_CLK_100M_DR9_2_R_N | PE_CLK_100M_DR9_2_R-DIFF1 | PAIR | 3 | 6.5 | 5 | 10 | 5 | 12 | 20 | 25 | 12 | 12 | 20 | 12 | 7.5 | 85 Ohms | TOP=L2:L3=L2/L4:L6=L5/L7:BOTTOM=L7 |
| PE_CLK_100M_DR9_2_R_N | PE_CLK_100M_DR9_2_R-DIFF1 | PAIR | 4 | 6.5 | 5 | 10 | 5 | 12 | 20 | 25 | 12 | 12 | 20 | 12 | 7.5 | 85 Ohms | TOP=L2:L3=L2/L4:L6=L5/L7:BOTTOM=L7 |
| PE_CLK_100M_DR9_2_R_N | PE_CLK_100M_DR9_2_R-DIFF1 | PAIR | 5 | 6.5 | 5 | 10 | 5 | 12 | 20 | 25 | 12 | 12 | 20 | 12 | 7.5 | 85 Ohms | TOP=L2:L3=L2/L4:L6=L5/L7:BOTTOM=L7 |
| PE_CLK_100M_DR9_2_R_N | PE_CLK_100M_DR9_2_R-DIFF1 | PAIR | 6 | 6.5 | 5 | 10 | 5 | 12 | 20 | 25 | 12 | 12 | 20 | 12 | 7.5 | 85 Ohms | TOP=L2:L3=L2/L4:L6=L5/L7:BOTTOM=L7 |
| PE_CLK_100M_DR9_2_R_N | PE_CLK_100M_DR9_2_R-DIFF1 | PAIR | 7 | 6.5 | 5 | 10 | 5 | 12 | 20 | 25 | 12 | 12 | 20 | 12 | 7.5 | 85 Ohms | TOP=L2:L3=L2/L4:L6=L5/L7:BOTTOM=L7 |
| PE_CLK_100M_DR9_2_R_N | PE_CLK_100M_DR9_2_R-DIFF1 | PAIR | 8 | 6.88 | 5 | 10 | 5 | 12 | 20 | 36 | 12 | 12 | 20 | 12 | 5.13 | 85 Ohms | TOP=L2:L3=L2/L4:L6=L5/L7:BOTTOM=L7 |
| PE_CLK_100M_DR9_2_R_P | PE_CLK_100M_DR9_2_R-DIFF1 | PAIR | 1 | 6.88 | 5 | 10 | 5 | 12 | 20 | 36 | 12 | 12 | 20 | 12 | 5.13 | 85 Ohms | TOP=L2:L3=L2/L4:L6=L5/L7:BOTTOM=L7 |
| PE_CLK_100M_DR9_2_R_P | PE_CLK_100M_DR9_2_R-DIFF1 | PAIR | 2 | 6.5 | 5 | 10 | 5 | 12 | 20 | 25 | 12 | 12 | 20 | 12 | 7.5 | 85 Ohms | TOP=L2:L3=L2/L4:L6=L5/L7:BOTTOM=L7 |
| PE_CLK_100M_DR9_2_R_P | PE_CLK_100M_DR9_2_R-DIFF1 | PAIR | 3 | 6.5 | 5 | 10 | 5 | 12 | 20 | 25 | 12 | 12 | 20 | 12 | 7.5 | 85 Ohms | TOP=L2:L3=L2/L4:L6=L5/L7:BOTTOM=L7 |
| PE_CLK_100M_DR9_2_R_P | PE_CLK_100M_DR9_2_R-DIFF1 | PAIR | 4 | 6.5 | 5 | 10 | 5 | 12 | 20 | 25 | 12 | 12 | 20 | 12 | 7.5 | 85 Ohms | TOP=L2:L3=L2/L4:L6=L5/L7:BOTTOM=L7 |
| PE_CLK_100M_DR9_2_R_P | PE_CLK_100M_DR9_2_R-DIFF1 | PAIR | 5 | 6.5 | 5 | 10 | 5 | 12 | 20 | 25 | 12 | 12 | 20 | 12 | 7.5 | 85 Ohms | TOP=L2:L3=L2/L4:L6=L5/L7:BOTTOM=L7 |
| PE_CLK_100M_DR9_2_R_P | PE_CLK_100M_DR9_2_R-DIFF1 | PAIR | 6 | 6.5 | 5 | 10 | 5 | 12 | 20 | 25 | 12 | 12 | 20 | 12 | 7.5 | 85 Ohms | TOP=L2:L3=L2/L4:L6=L5/L7:BOTTOM=L7 |
| PE_CLK_100M_DR9_2_R_P | PE_CLK_100M_DR9_2_R-DIFF1 | PAIR | 7 | 6.5 | 5 | 10 | 5 | 12 | 20 | 25 | 12 | 12 | 20 | 12 | 7.5 | 85 Ohms | TOP=L2:L3=L2/L4:L6=L5/L7:BOTTOM=L7 |
| PE_CLK_100M_DR9_2_R_P | PE_CLK_100M_DR9_2_R-DIFF1 | PAIR | 8 | 6.88 | 5 | 10 | 5 | 12 | 20 | 36 | 12 | 12 | 20 | 12 | 5.13 | 85 Ohms | TOP=L2:L3=L2/L4:L6=L5/L7:BOTTOM=L7 |
| PE_CLK100M_DR0_1_N | PE_CLK100M_DR0_1-DIFF1 | PAIR | 1 | 6.88 | 5 | 10 | 5 | 12 | 20 | 36 | 12 | 12 | 20 | 12 | 5.13 | 85 Ohms | TOP=L2:L3=L2/L4:L6=L5/L7:BOTTOM=L7 |
| PE_CLK100M_DR0_1_N | PE_CLK100M_DR0_1-DIFF1 | PAIR | 2 | 6.5 | 5 | 10 | 5 | 12 | 20 | 25 | 12 | 12 | 20 | 12 | 7.5 | 85 Ohms | TOP=L2:L3=L2/L4:L6=L5/L7:BOTTOM=L7 |
| PE_CLK100M_DR0_1_N | PE_CLK100M_DR0_1-DIFF1 | PAIR | 3 | 6.5 | 5 | 10 | 5 | 12 | 20 | 25 | 12 | 12 | 20 | 12 | 7.5 | 85 Ohms | TOP=L2:L3=L2/L4:L6=L5/L7:BOTTOM=L7 |
| PE_CLK100M_DR0_1_N | PE_CLK100M_DR0_1-DIFF1 | PAIR | 4 | 6.5 | 5 | 10 | 5 | 12 | 20 | 25 | 12 | 12 | 20 | 12 | 7.5 | 85 Ohms | TOP=L2:L3=L2/L4:L6=L5/L7:BOTTOM=L7 |
| PE_CLK100M_DR0_1_N | PE_CLK100M_DR0_1-DIFF1 | PAIR | 5 | 6.5 | 5 | 10 | 5 | 12 | 20 | 25 | 12 | 12 | 20 | 12 | 7.5 | 85 Ohms | TOP=L2:L3=L2/L4:L6=L5/L7:BOTTOM=L7 |
| PE_CLK100M_DR0_1_N | PE_CLK100M_DR0_1-DIFF1 | PAIR | 6 | 6.5 | 5 | 10 | 5 | 12 | 20 | 25 | 12 | 12 | 20 | 12 | 7.5 | 85 Ohms | TOP=L2:L3=L2/L4:L6=L5/L7:BOTTOM=L7 |
| PE_CLK100M_DR0_1_N | PE_CLK100M_DR0_1-DIFF1 | PAIR | 7 | 6.5 | 5 | 10 | 5 | 12 | 20 | 25 | 12 | 12 | 20 | 12 | 7.5 | 85 Ohms | TOP=L2:L3=L2/L4:L6=L5/L7:BOTTOM=L7 |
| PE_CLK100M_DR0_1_N | PE_CLK100M_DR0_1-DIFF1 | PAIR | 8 | 6.88 | 5 | 10 | 5 | 12 | 20 | 36 | 12 | 12 | 20 | 12 | 5.13 | 85 Ohms | TOP=L2:L3=L2/L4:L6=L5/L7:BOTTOM=L7 |
| PE_CLK100M_DR0_1_P | PE_CLK100M_DR0_1-DIFF1 | PAIR | 1 | 6.88 | 5 | 10 | 5 | 12 | 20 | 36 | 12 | 12 | 20 | 12 | 5.13 | 85 Ohms | TOP=L2:L3=L2/L4:L6=L5/L7:BOTTOM=L7 |
| PE_CLK100M_DR0_1_P | PE_CLK100M_DR0_1-DIFF1 | PAIR | 2 | 6.5 | 5 | 10 | 5 | 12 | 20 | 25 | 12 | 12 | 20 | 12 | 7.5 | 85 Ohms | TOP=L2:L3=L2/L4:L6=L5/L7:BOTTOM=L7 |
| PE_CLK100M_DR0_1_P | PE_CLK100M_DR0_1-DIFF1 | PAIR | 3 | 6.5 | 5 | 10 | 5 | 12 | 20 | 25 | 12 | 12 | 20 | 12 | 7.5 | 85 Ohms | TOP=L2:L3=L2/L4:L6=L5/L7:BOTTOM=L7 |
| PE_CLK100M_DR0_1_P | PE_CLK100M_DR0_1-DIFF1 | PAIR | 4 | 6.5 | 5 | 10 | 5 | 12 | 20 | 25 | 12 | 12 | 20 | 12 | 7.5 | 85 Ohms | TOP=L2:L3=L2/L4:L6=L5/L7:BOTTOM=L7 |
| PE_CLK100M_DR0_1_P | PE_CLK100M_DR0_1-DIFF1 | PAIR | 5 | 6.5 | 5 | 10 | 5 | 12 | 20 | 25 | 12 | 12 | 20 | 12 | 7.5 | 85 Ohms | TOP=L2:L3=L2/L4:L6=L5/L7:BOTTOM=L7 |
| PE_CLK100M_DR0_1_P | PE_CLK100M_DR0_1-DIFF1 | PAIR | 6 | 6.5 | 5 | 10 | 5 | 12 | 20 | 25 | 12 | 12 | 20 | 12 | 7.5 | 85 Ohms | TOP=L2:L3=L2/L4:L6=L5/L7:BOTTOM=L7 |
| PE_CLK100M_DR0_1_P | PE_CLK100M_DR0_1-DIFF1 | PAIR | 7 | 6.5 | 5 | 10 | 5 | 12 | 20 | 25 | 12 | 12 | 20 | 12 | 7.5 | 85 Ohms | TOP=L2:L3=L2/L4:L6=L5/L7:BOTTOM=L7 |
| PE_CLK100M_DR0_1_P | PE_CLK100M_DR0_1-DIFF1 | PAIR | 8 | 6.88 | 5 | 10 | 5 | 12 | 20 | 36 | 12 | 12 | 20 | 12 | 5.13 | 85 Ohms | TOP=L2:L3=L2/L4:L6=L5/L7:BOTTOM=L7 |
| PE_CLK100M_DR0_2_N | PE_CLK100M_DR0_2-DIFF1 | PAIR | 1 | 6.88 | 5 | 10 | 5 | 12 | 20 | 36 | 12 | 12 | 20 | 12 | 5.13 | 85 Ohms | TOP=L2:L3=L2/L4:L6=L5/L7:BOTTOM=L7 |
| PE_CLK100M_DR0_2_N | PE_CLK100M_DR0_2-DIFF1 | PAIR | 2 | 6.5 | 5 | 10 | 5 | 12 | 20 | 25 | 12 | 12 | 20 | 12 | 7.5 | 85 Ohms | TOP=L2:L3=L2/L4:L6=L5/L7:BOTTOM=L7 |
| PE_CLK100M_DR0_2_N | PE_CLK100M_DR0_2-DIFF1 | PAIR | 3 | 6.5 | 5 | 10 | 5 | 12 | 20 | 25 | 12 | 12 | 20 | 12 | 7.5 | 85 Ohms | TOP=L2:L3=L2/L4:L6=L5/L7:BOTTOM=L7 |
| PE_CLK100M_DR0_2_N | PE_CLK100M_DR0_2-DIFF1 | PAIR | 4 | 6.5 | 5 | 10 | 5 | 12 | 20 | 25 | 12 | 12 | 20 | 12 | 7.5 | 85 Ohms | TOP=L2:L3=L2/L4:L6=L5/L7:BOTTOM=L7 |
| PE_CLK100M_DR0_2_N | PE_CLK100M_DR0_2-DIFF1 | PAIR | 5 | 6.5 | 5 | 10 | 5 | 12 | 20 | 25 | 12 | 12 | 20 | 12 | 7.5 | 85 Ohms | TOP=L2:L3=L2/L4:L6=L5/L7:BOTTOM=L7 |
| PE_CLK100M_DR0_2_N | PE_CLK100M_DR0_2-DIFF1 | PAIR | 6 | 6.5 | 5 | 10 | 5 | 12 | 20 | 25 | 12 | 12 | 20 | 12 | 7.5 | 85 Ohms | TOP=L2:L3=L2/L4:L6=L5/L7:BOTTOM=L7 |
| PE_CLK100M_DR0_2_N | PE_CLK100M_DR0_2-DIFF1 | PAIR | 7 | 6.5 | 5 | 10 | 5 | 12 | 20 | 25 | 12 | 12 | 20 | 12 | 7.5 | 85 Ohms | TOP=L2:L3=L2/L4:L6=L5/L7:BOTTOM=L7 |
| PE_CLK100M_DR0_2_N | PE_CLK100M_DR0_2-DIFF1 | PAIR | 8 | 6.88 | 5 | 10 | 5 | 12 | 20 | 36 | 12 | 12 | 20 | 12 | 5.13 | 85 Ohms | TOP=L2:L3=L2/L4:L6=L5/L7:BOTTOM=L7 |
| PE_CLK100M_DR0_2_P | PE_CLK100M_DR0_2-DIFF1 | PAIR | 1 | 6.88 | 5 | 10 | 5 | 12 | 20 | 36 | 12 | 12 | 20 | 12 | 5.13 | 85 Ohms | TOP=L2:L3=L2/L4:L6=L5/L7:BOTTOM=L7 |
| PE_CLK100M_DR0_2_P | PE_CLK100M_DR0_2-DIFF1 | PAIR | 2 | 6.5 | 5 | 10 | 5 | 12 | 20 | 25 | 12 | 12 | 20 | 12 | 7.5 | 85 Ohms | TOP=L2:L3=L2/L4:L6=L5/L7:BOTTOM=L7 |
| PE_CLK100M_DR0_2_P | PE_CLK100M_DR0_2-DIFF1 | PAIR | 3 | 6.5 | 5 | 10 | 5 | 12 | 20 | 25 | 12 | 12 | 20 | 12 | 7.5 | 85 Ohms | TOP=L2:L3=L2/L4:L6=L5/L7:BOTTOM=L7 |
| PE_CLK100M_DR0_2_P | PE_CLK100M_DR0_2-DIFF1 | PAIR | 4 | 6.5 | 5 | 10 | 5 | 12 | 20 | 25 | 12 | 12 | 20 | 12 | 7.5 | 85 Ohms | TOP=L2:L3=L2/L4:L6=L5/L7:BOTTOM=L7 |
| PE_CLK100M_DR0_2_P | PE_CLK100M_DR0_2-DIFF1 | PAIR | 5 | 6.5 | 5 | 10 | 5 | 12 | 20 | 25 | 12 | 12 | 20 | 12 | 7.5 | 85 Ohms | TOP=L2:L3=L2/L4:L6=L5/L7:BOTTOM=L7 |
| PE_CLK100M_DR0_2_P | PE_CLK100M_DR0_2-DIFF1 | PAIR | 6 | 6.5 | 5 | 10 | 5 | 12 | 20 | 25 | 12 | 12 | 20 | 12 | 7.5 | 85 Ohms | TOP=L2:L3=L2/L4:L6=L5/L7:BOTTOM=L7 |
| PE_CLK100M_DR0_2_P | PE_CLK100M_DR0_2-DIFF1 | PAIR | 7 | 6.5 | 5 | 10 | 5 | 12 | 20 | 25 | 12 | 12 | 20 | 12 | 7.5 | 85 Ohms | TOP=L2:L3=L2/L4:L6=L5/L7:BOTTOM=L7 |
| PE_CLK100M_DR0_2_P | PE_CLK100M_DR0_2-DIFF1 | PAIR | 8 | 6.88 | 5 | 10 | 5 | 12 | 20 | 36 | 12 | 12 | 20 | 12 | 5.13 | 85 Ohms | TOP=L2:L3=L2/L4:L6=L5/L7:BOTTOM=L7 |
| PE_CLK100M_DR1_1_N | PE_CLK100M_DR1_1-DIFF1 | PAIR | 1 | 6.88 | 5 | 10 | 5 | 12 | 20 | 36 | 12 | 12 | 20 | 12 | 5.13 | 85 Ohms | TOP=L2:L3=L2/L4:L6=L5/L7:BOTTOM=L7 |
| PE_CLK100M_DR1_1_N | PE_CLK100M_DR1_1-DIFF1 | PAIR | 2 | 6.5 | 5 | 10 | 5 | 12 | 20 | 25 | 12 | 12 | 20 | 12 | 7.5 | 85 Ohms | TOP=L2:L3=L2/L4:L6=L5/L7:BOTTOM=L7 |
| PE_CLK100M_DR1_1_N | PE_CLK100M_DR1_1-DIFF1 | PAIR | 3 | 6.5 | 5 | 10 | 5 | 12 | 20 | 25 | 12 | 12 | 20 | 12 | 7.5 | 85 Ohms | TOP=L2:L3=L2/L4:L6=L5/L7:BOTTOM=L7 |
| PE_CLK100M_DR1_1_N | PE_CLK100M_DR1_1-DIFF1 | PAIR | 4 | 6.5 | 5 | 10 | 5 | 12 | 20 | 25 | 12 | 12 | 20 | 12 | 7.5 | 85 Ohms | TOP=L2:L3=L2/L4:L6=L5/L7:BOTTOM=L7 |
| PE_CLK100M_DR1_1_N | PE_CLK100M_DR1_1-DIFF1 | PAIR | 5 | 6.5 | 5 | 10 | 5 | 12 | 20 | 25 | 12 | 12 | 20 | 12 | 7.5 | 85 Ohms | TOP=L2:L3=L2/L4:L6=L5/L7:BOTTOM=L7 |
| PE_CLK100M_DR1_1_N | PE_CLK100M_DR1_1-DIFF1 | PAIR | 6 | 6.5 | 5 | 10 | 5 | 12 | 20 | 25 | 12 | 12 | 20 | 12 | 7.5 | 85 Ohms | TOP=L2:L3=L2/L4:L6=L5/L7:BOTTOM=L7 |
| PE_CLK100M_DR1_1_N | PE_CLK100M_DR1_1-DIFF1 | PAIR | 7 | 6.5 | 5 | 10 | 5 | 12 | 20 | 25 | 12 | 12 | 20 | 12 | 7.5 | 85 Ohms | TOP=L2:L3=L2/L4:L6=L5/L7:BOTTOM=L7 |
| PE_CLK100M_DR1_1_N | PE_CLK100M_DR1_1-DIFF1 | PAIR | 8 | 6.88 | 5 | 10 | 5 | 12 | 20 | 36 | 12 | 12 | 20 | 12 | 5.13 | 85 Ohms | TOP=L2:L3=L2/L4:L6=L5/L7:BOTTOM=L7 |
| PE_CLK100M_DR1_1_P | PE_CLK100M_DR1_1-DIFF1 | PAIR | 1 | 6.88 | 5 | 10 | 5 | 12 | 20 | 36 | 12 | 12 | 20 | 12 | 5.13 | 85 Ohms | TOP=L2:L3=L2/L4:L6=L5/L7:BOTTOM=L7 |
| PE_CLK100M_DR1_1_P | PE_CLK100M_DR1_1-DIFF1 | PAIR | 2 | 6.5 | 5 | 10 | 5 | 12 | 20 | 25 | 12 | 12 | 20 | 12 | 7.5 | 85 Ohms | TOP=L2:L3=L2/L4:L6=L5/L7:BOTTOM=L7 |
| PE_CLK100M_DR1_1_P | PE_CLK100M_DR1_1-DIFF1 | PAIR | 3 | 6.5 | 5 | 10 | 5 | 12 | 20 | 25 | 12 | 12 | 20 | 12 | 7.5 | 85 Ohms | TOP=L2:L3=L2/L4:L6=L5/L7:BOTTOM=L7 |
| PE_CLK100M_DR1_1_P | PE_CLK100M_DR1_1-DIFF1 | PAIR | 4 | 6.5 | 5 | 10 | 5 | 12 | 20 | 25 | 12 | 12 | 20 | 12 | 7.5 | 85 Ohms | TOP=L2:L3=L2/L4:L6=L5/L7:BOTTOM=L7 |
| PE_CLK100M_DR1_1_P | PE_CLK100M_DR1_1-DIFF1 | PAIR | 5 | 6.5 | 5 | 10 | 5 | 12 | 20 | 25 | 12 | 12 | 20 | 12 | 7.5 | 85 Ohms | TOP=L2:L3=L2/L4:L6=L5/L7:BOTTOM=L7 |
| PE_CLK100M_DR1_1_P | PE_CLK100M_DR1_1-DIFF1 | PAIR | 6 | 6.5 | 5 | 10 | 5 | 12 | 20 | 25 | 12 | 12 | 20 | 12 | 7.5 | 85 Ohms | TOP=L2:L3=L2/L4:L6=L5/L7:BOTTOM=L7 |
| PE_CLK100M_DR1_1_P | PE_CLK100M_DR1_1-DIFF1 | PAIR | 7 | 6.5 | 5 | 10 | 5 | 12 | 20 | 25 | 12 | 12 | 20 | 12 | 7.5 | 85 Ohms | TOP=L2:L3=L2/L4:L6=L5/L7:BOTTOM=L7 |
| PE_CLK100M_DR1_1_P | PE_CLK100M_DR1_1-DIFF1 | PAIR | 8 | 6.88 | 5 | 10 | 5 | 12 | 20 | 36 | 12 | 12 | 20 | 12 | 5.13 | 85 Ohms | TOP=L2:L3=L2/L4:L6=L5/L7:BOTTOM=L7 |
| PE_CLK100M_DR1_2_N | PE_CLK100M_DR1_2-DIFF1 | PAIR | 1 | 6.88 | 5 | 10 | 5 | 12 | 20 | 36 | 12 | 12 | 20 | 12 | 5.13 | 85 Ohms | TOP=L2:L3=L2/L4:L6=L5/L7:BOTTOM=L7 |
| PE_CLK100M_DR1_2_N | PE_CLK100M_DR1_2-DIFF1 | PAIR | 2 | 6.5 | 5 | 10 | 5 | 12 | 20 | 25 | 12 | 12 | 20 | 12 | 7.5 | 85 Ohms | TOP=L2:L3=L2/L4:L6=L5/L7:BOTTOM=L7 |
| PE_CLK100M_DR1_2_N | PE_CLK100M_DR1_2-DIFF1 | PAIR | 3 | 6.5 | 5 | 10 | 5 | 12 | 20 | 25 | 12 | 12 | 20 | 12 | 7.5 | 85 Ohms | TOP=L2:L3=L2/L4:L6=L5/L7:BOTTOM=L7 |
| PE_CLK100M_DR1_2_N | PE_CLK100M_DR1_2-DIFF1 | PAIR | 4 | 6.5 | 5 | 10 | 5 | 12 | 20 | 25 | 12 | 12 | 20 | 12 | 7.5 | 85 Ohms | TOP=L2:L3=L2/L4:L6=L5/L7:BOTTOM=L7 |
| PE_CLK100M_DR1_2_N | PE_CLK100M_DR1_2-DIFF1 | PAIR | 5 | 6.5 | 5 | 10 | 5 | 12 | 20 | 25 | 12 | 12 | 20 | 12 | 7.5 | 85 Ohms | TOP=L2:L3=L2/L4:L6=L5/L7:BOTTOM=L7 |
| PE_CLK100M_DR1_2_N | PE_CLK100M_DR1_2-DIFF1 | PAIR | 6 | 6.5 | 5 | 10 | 5 | 12 | 20 | 25 | 12 | 12 | 20 | 12 | 7.5 | 85 Ohms | TOP=L2:L3=L2/L4:L6=L5/L7:BOTTOM=L7 |
| PE_CLK100M_DR1_2_N | PE_CLK100M_DR1_2-DIFF1 | PAIR | 7 | 6.5 | 5 | 10 | 5 | 12 | 20 | 25 | 12 | 12 | 20 | 12 | 7.5 | 85 Ohms | TOP=L2:L3=L2/L4:L6=L5/L7:BOTTOM=L7 |
| PE_CLK100M_DR1_2_N | PE_CLK100M_DR1_2-DIFF1 | PAIR | 8 | 6.88 | 5 | 10 | 5 | 12 | 20 | 36 | 12 | 12 | 20 | 12 | 5.13 | 85 Ohms | TOP=L2:L3=L2/L4:L6=L5/L7:BOTTOM=L7 |
| PE_CLK100M_DR1_2_P | PE_CLK100M_DR1_2-DIFF1 | PAIR | 1 | 6.88 | 5 | 10 | 5 | 12 | 20 | 36 | 12 | 12 | 20 | 12 | 5.13 | 85 Ohms | TOP=L2:L3=L2/L4:L6=L5/L7:BOTTOM=L7 |
| PE_CLK100M_DR1_2_P | PE_CLK100M_DR1_2-DIFF1 | PAIR | 2 | 6.5 | 5 | 10 | 5 | 12 | 20 | 25 | 12 | 12 | 20 | 12 | 7.5 | 85 Ohms | TOP=L2:L3=L2/L4:L6=L5/L7:BOTTOM=L7 |
| PE_CLK100M_DR1_2_P | PE_CLK100M_DR1_2-DIFF1 | PAIR | 3 | 6.5 | 5 | 10 | 5 | 12 | 20 | 25 | 12 | 12 | 20 | 12 | 7.5 | 85 Ohms | TOP=L2:L3=L2/L4:L6=L5/L7:BOTTOM=L7 |
| PE_CLK100M_DR1_2_P | PE_CLK100M_DR1_2-DIFF1 | PAIR | 4 | 6.5 | 5 | 10 | 5 | 12 | 20 | 25 | 12 | 12 | 20 | 12 | 7.5 | 85 Ohms | TOP=L2:L3=L2/L4:L6=L5/L7:BOTTOM=L7 |
| PE_CLK100M_DR1_2_P | PE_CLK100M_DR1_2-DIFF1 | PAIR | 5 | 6.5 | 5 | 10 | 5 | 12 | 20 | 25 | 12 | 12 | 20 | 12 | 7.5 | 85 Ohms | TOP=L2:L3=L2/L4:L6=L5/L7:BOTTOM=L7 |
| PE_CLK100M_DR1_2_P | PE_CLK100M_DR1_2-DIFF1 | PAIR | 6 | 6.5 | 5 | 10 | 5 | 12 | 20 | 25 | 12 | 12 | 20 | 12 | 7.5 | 85 Ohms | TOP=L2:L3=L2/L4:L6=L5/L7:BOTTOM=L7 |
| PE_CLK100M_DR1_2_P | PE_CLK100M_DR1_2-DIFF1 | PAIR | 7 | 6.5 | 5 | 10 | 5 | 12 | 20 | 25 | 12 | 12 | 20 | 12 | 7.5 | 85 Ohms | TOP=L2:L3=L2/L4:L6=L5/L7:BOTTOM=L7 |
| PE_CLK100M_DR1_2_P | PE_CLK100M_DR1_2-DIFF1 | PAIR | 8 | 6.88 | 5 | 10 | 5 | 12 | 20 | 36 | 12 | 12 | 20 | 12 | 5.13 | 85 Ohms | TOP=L2:L3=L2/L4:L6=L5/L7:BOTTOM=L7 |
| PE_CLK100M_DR10_1_N | PE_CLK100M_DR10_1-DIFF1 | PAIR | 1 | 6.88 | 5 | 10 | 5 | 12 | 20 | 36 | 12 | 12 | 20 | 12 | 5.13 | 85 Ohms | TOP=L2:L3=L2/L4:L6=L5/L7:BOTTOM=L7 |
| PE_CLK100M_DR10_1_N | PE_CLK100M_DR10_1-DIFF1 | PAIR | 2 | 6.5 | 5 | 10 | 5 | 12 | 20 | 25 | 12 | 12 | 20 | 12 | 7.5 | 85 Ohms | TOP=L2:L3=L2/L4:L6=L5/L7:BOTTOM=L7 |
| PE_CLK100M_DR10_1_N | PE_CLK100M_DR10_1-DIFF1 | PAIR | 3 | 6.5 | 5 | 10 | 5 | 12 | 20 | 25 | 12 | 12 | 20 | 12 | 7.5 | 85 Ohms | TOP=L2:L3=L2/L4:L6=L5/L7:BOTTOM=L7 |
| PE_CLK100M_DR10_1_N | PE_CLK100M_DR10_1-DIFF1 | PAIR | 4 | 6.5 | 5 | 10 | 5 | 12 | 20 | 25 | 12 | 12 | 20 | 12 | 7.5 | 85 Ohms | TOP=L2:L3=L2/L4:L6=L5/L7:BOTTOM=L7 |
| PE_CLK100M_DR10_1_N | PE_CLK100M_DR10_1-DIFF1 | PAIR | 5 | 6.5 | 5 | 10 | 5 | 12 | 20 | 25 | 12 | 12 | 20 | 12 | 7.5 | 85 Ohms | TOP=L2:L3=L2/L4:L6=L5/L7:BOTTOM=L7 |
| PE_CLK100M_DR10_1_N | PE_CLK100M_DR10_1-DIFF1 | PAIR | 6 | 6.5 | 5 | 10 | 5 | 12 | 20 | 25 | 12 | 12 | 20 | 12 | 7.5 | 85 Ohms | TOP=L2:L3=L2/L4:L6=L5/L7:BOTTOM=L7 |
| PE_CLK100M_DR10_1_N | PE_CLK100M_DR10_1-DIFF1 | PAIR | 7 | 6.5 | 5 | 10 | 5 | 12 | 20 | 25 | 12 | 12 | 20 | 12 | 7.5 | 85 Ohms | TOP=L2:L3=L2/L4:L6=L5/L7:BOTTOM=L7 |
| PE_CLK100M_DR10_1_N | PE_CLK100M_DR10_1-DIFF1 | PAIR | 8 | 6.88 | 5 | 10 | 5 | 12 | 20 | 36 | 12 | 12 | 20 | 12 | 5.13 | 85 Ohms | TOP=L2:L3=L2/L4:L6=L5/L7:BOTTOM=L7 |
| PE_CLK100M_DR10_1_P | PE_CLK100M_DR10_1-DIFF1 | PAIR | 1 | 6.88 | 5 | 10 | 5 | 12 | 20 | 36 | 12 | 12 | 20 | 12 | 5.13 | 85 Ohms | TOP=L2:L3=L2/L4:L6=L5/L7:BOTTOM=L7 |
| PE_CLK100M_DR10_1_P | PE_CLK100M_DR10_1-DIFF1 | PAIR | 2 | 6.5 | 5 | 10 | 5 | 12 | 20 | 25 | 12 | 12 | 20 | 12 | 7.5 | 85 Ohms | TOP=L2:L3=L2/L4:L6=L5/L7:BOTTOM=L7 |
| PE_CLK100M_DR10_1_P | PE_CLK100M_DR10_1-DIFF1 | PAIR | 3 | 6.5 | 5 | 10 | 5 | 12 | 20 | 25 | 12 | 12 | 20 | 12 | 7.5 | 85 Ohms | TOP=L2:L3=L2/L4:L6=L5/L7:BOTTOM=L7 |
| PE_CLK100M_DR10_1_P | PE_CLK100M_DR10_1-DIFF1 | PAIR | 4 | 6.5 | 5 | 10 | 5 | 12 | 20 | 25 | 12 | 12 | 20 | 12 | 7.5 | 85 Ohms | TOP=L2:L3=L2/L4:L6=L5/L7:BOTTOM=L7 |
| PE_CLK100M_DR10_1_P | PE_CLK100M_DR10_1-DIFF1 | PAIR | 5 | 6.5 | 5 | 10 | 5 | 12 | 20 | 25 | 12 | 12 | 20 | 12 | 7.5 | 85 Ohms | TOP=L2:L3=L2/L4:L6=L5/L7:BOTTOM=L7 |
| PE_CLK100M_DR10_1_P | PE_CLK100M_DR10_1-DIFF1 | PAIR | 6 | 6.5 | 5 | 10 | 5 | 12 | 20 | 25 | 12 | 12 | 20 | 12 | 7.5 | 85 Ohms | TOP=L2:L3=L2/L4:L6=L5/L7:BOTTOM=L7 |
| PE_CLK100M_DR10_1_P | PE_CLK100M_DR10_1-DIFF1 | PAIR | 7 | 6.5 | 5 | 10 | 5 | 12 | 20 | 25 | 12 | 12 | 20 | 12 | 7.5 | 85 Ohms | TOP=L2:L3=L2/L4:L6=L5/L7:BOTTOM=L7 |
| PE_CLK100M_DR10_1_P | PE_CLK100M_DR10_1-DIFF1 | PAIR | 8 | 6.88 | 5 | 10 | 5 | 12 | 20 | 36 | 12 | 12 | 20 | 12 | 5.13 | 85 Ohms | TOP=L2:L3=L2/L4:L6=L5/L7:BOTTOM=L7 |
| PE_CLK100M_DR10_2_N | PE_CLK100M_DR10_2-DIFF1 | PAIR | 1 | 6.88 | 5 | 10 | 5 | 12 | 20 | 36 | 12 | 12 | 20 | 12 | 5.13 | 85 Ohms | TOP=L2:L3=L2/L4:L6=L5/L7:BOTTOM=L7 |
| PE_CLK100M_DR10_2_N | PE_CLK100M_DR10_2-DIFF1 | PAIR | 2 | 6.5 | 5 | 10 | 5 | 12 | 20 | 25 | 12 | 12 | 20 | 12 | 7.5 | 85 Ohms | TOP=L2:L3=L2/L4:L6=L5/L7:BOTTOM=L7 |
| PE_CLK100M_DR10_2_N | PE_CLK100M_DR10_2-DIFF1 | PAIR | 3 | 6.5 | 5 | 10 | 5 | 12 | 20 | 25 | 12 | 12 | 20 | 12 | 7.5 | 85 Ohms | TOP=L2:L3=L2/L4:L6=L5/L7:BOTTOM=L7 |
| PE_CLK100M_DR10_2_N | PE_CLK100M_DR10_2-DIFF1 | PAIR | 4 | 6.5 | 5 | 10 | 5 | 12 | 20 | 25 | 12 | 12 | 20 | 12 | 7.5 | 85 Ohms | TOP=L2:L3=L2/L4:L6=L5/L7:BOTTOM=L7 |
| PE_CLK100M_DR10_2_N | PE_CLK100M_DR10_2-DIFF1 | PAIR | 5 | 6.5 | 5 | 10 | 5 | 12 | 20 | 25 | 12 | 12 | 20 | 12 | 7.5 | 85 Ohms | TOP=L2:L3=L2/L4:L6=L5/L7:BOTTOM=L7 |
| PE_CLK100M_DR10_2_N | PE_CLK100M_DR10_2-DIFF1 | PAIR | 6 | 6.5 | 5 | 10 | 5 | 12 | 20 | 25 | 12 | 12 | 20 | 12 | 7.5 | 85 Ohms | TOP=L2:L3=L2/L4:L6=L5/L7:BOTTOM=L7 |
| PE_CLK100M_DR10_2_N | PE_CLK100M_DR10_2-DIFF1 | PAIR | 7 | 6.5 | 5 | 10 | 5 | 12 | 20 | 25 | 12 | 12 | 20 | 12 | 7.5 | 85 Ohms | TOP=L2:L3=L2/L4:L6=L5/L7:BOTTOM=L7 |
| PE_CLK100M_DR10_2_N | PE_CLK100M_DR10_2-DIFF1 | PAIR | 8 | 6.88 | 5 | 10 | 5 | 12 | 20 | 36 | 12 | 12 | 20 | 12 | 5.13 | 85 Ohms | TOP=L2:L3=L2/L4:L6=L5/L7:BOTTOM=L7 |
| PE_CLK100M_DR10_2_P | PE_CLK100M_DR10_2-DIFF1 | PAIR | 1 | 6.88 | 5 | 10 | 5 | 12 | 20 | 36 | 12 | 12 | 20 | 12 | 5.13 | 85 Ohms | TOP=L2:L3=L2/L4:L6=L5/L7:BOTTOM=L7 |
| PE_CLK100M_DR10_2_P | PE_CLK100M_DR10_2-DIFF1 | PAIR | 2 | 6.5 | 5 | 10 | 5 | 12 | 20 | 25 | 12 | 12 | 20 | 12 | 7.5 | 85 Ohms | TOP=L2:L3=L2/L4:L6=L5/L7:BOTTOM=L7 |
| PE_CLK100M_DR10_2_P | PE_CLK100M_DR10_2-DIFF1 | PAIR | 3 | 6.5 | 5 | 10 | 5 | 12 | 20 | 25 | 12 | 12 | 20 | 12 | 7.5 | 85 Ohms | TOP=L2:L3=L2/L4:L6=L5/L7:BOTTOM=L7 |
| PE_CLK100M_DR10_2_P | PE_CLK100M_DR10_2-DIFF1 | PAIR | 4 | 6.5 | 5 | 10 | 5 | 12 | 20 | 25 | 12 | 12 | 20 | 12 | 7.5 | 85 Ohms | TOP=L2:L3=L2/L4:L6=L5/L7:BOTTOM=L7 |
| PE_CLK100M_DR10_2_P | PE_CLK100M_DR10_2-DIFF1 | PAIR | 5 | 6.5 | 5 | 10 | 5 | 12 | 20 | 25 | 12 | 12 | 20 | 12 | 7.5 | 85 Ohms | TOP=L2:L3=L2/L4:L6=L5/L7:BOTTOM=L7 |
| PE_CLK100M_DR10_2_P | PE_CLK100M_DR10_2-DIFF1 | PAIR | 6 | 6.5 | 5 | 10 | 5 | 12 | 20 | 25 | 12 | 12 | 20 | 12 | 7.5 | 85 Ohms | TOP=L2:L3=L2/L4:L6=L5/L7:BOTTOM=L7 |
| PE_CLK100M_DR10_2_P | PE_CLK100M_DR10_2-DIFF1 | PAIR | 7 | 6.5 | 5 | 10 | 5 | 12 | 20 | 25 | 12 | 12 | 20 | 12 | 7.5 | 85 Ohms | TOP=L2:L3=L2/L4:L6=L5/L7:BOTTOM=L7 |
| PE_CLK100M_DR10_2_P | PE_CLK100M_DR10_2-DIFF1 | PAIR | 8 | 6.88 | 5 | 10 | 5 | 12 | 20 | 36 | 12 | 12 | 20 | 12 | 5.13 | 85 Ohms | TOP=L2:L3=L2/L4:L6=L5/L7:BOTTOM=L7 |
| PE_CLK100M_DR11_1_N | PE_CLK100M_DR11_1-DIFF1 | PAIR | 1 | 6.88 | 5 | 10 | 5 | 12 | 20 | 36 | 12 | 12 | 20 | 12 | 5.13 | 85 Ohms | TOP=L2:L3=L2/L4:L6=L5/L7:BOTTOM=L7 |
| PE_CLK100M_DR11_1_N | PE_CLK100M_DR11_1-DIFF1 | PAIR | 2 | 6.5 | 5 | 10 | 5 | 12 | 20 | 25 | 12 | 12 | 20 | 12 | 7.5 | 85 Ohms | TOP=L2:L3=L2/L4:L6=L5/L7:BOTTOM=L7 |
| PE_CLK100M_DR11_1_N | PE_CLK100M_DR11_1-DIFF1 | PAIR | 3 | 6.5 | 5 | 10 | 5 | 12 | 20 | 25 | 12 | 12 | 20 | 12 | 7.5 | 85 Ohms | TOP=L2:L3=L2/L4:L6=L5/L7:BOTTOM=L7 |
| PE_CLK100M_DR11_1_N | PE_CLK100M_DR11_1-DIFF1 | PAIR | 4 | 6.5 | 5 | 10 | 5 | 12 | 20 | 25 | 12 | 12 | 20 | 12 | 7.5 | 85 Ohms | TOP=L2:L3=L2/L4:L6=L5/L7:BOTTOM=L7 |
| PE_CLK100M_DR11_1_N | PE_CLK100M_DR11_1-DIFF1 | PAIR | 5 | 6.5 | 5 | 10 | 5 | 12 | 20 | 25 | 12 | 12 | 20 | 12 | 7.5 | 85 Ohms | TOP=L2:L3=L2/L4:L6=L5/L7:BOTTOM=L7 |
| PE_CLK100M_DR11_1_N | PE_CLK100M_DR11_1-DIFF1 | PAIR | 6 | 6.5 | 5 | 10 | 5 | 12 | 20 | 25 | 12 | 12 | 20 | 12 | 7.5 | 85 Ohms | TOP=L2:L3=L2/L4:L6=L5/L7:BOTTOM=L7 |
| PE_CLK100M_DR11_1_N | PE_CLK100M_DR11_1-DIFF1 | PAIR | 7 | 6.5 | 5 | 10 | 5 | 12 | 20 | 25 | 12 | 12 | 20 | 12 | 7.5 | 85 Ohms | TOP=L2:L3=L2/L4:L6=L5/L7:BOTTOM=L7 |
| PE_CLK100M_DR11_1_N | PE_CLK100M_DR11_1-DIFF1 | PAIR | 8 | 6.88 | 5 | 10 | 5 | 12 | 20 | 36 | 12 | 12 | 20 | 12 | 5.13 | 85 Ohms | TOP=L2:L3=L2/L4:L6=L5/L7:BOTTOM=L7 |
| PE_CLK100M_DR11_1_P | PE_CLK100M_DR11_1-DIFF1 | PAIR | 1 | 6.88 | 5 | 10 | 5 | 12 | 20 | 36 | 12 | 12 | 20 | 12 | 5.13 | 85 Ohms | TOP=L2:L3=L2/L4:L6=L5/L7:BOTTOM=L7 |
| PE_CLK100M_DR11_1_P | PE_CLK100M_DR11_1-DIFF1 | PAIR | 2 | 6.5 | 5 | 10 | 5 | 12 | 20 | 25 | 12 | 12 | 20 | 12 | 7.5 | 85 Ohms | TOP=L2:L3=L2/L4:L6=L5/L7:BOTTOM=L7 |
| PE_CLK100M_DR11_1_P | PE_CLK100M_DR11_1-DIFF1 | PAIR | 3 | 6.5 | 5 | 10 | 5 | 12 | 20 | 25 | 12 | 12 | 20 | 12 | 7.5 | 85 Ohms | TOP=L2:L3=L2/L4:L6=L5/L7:BOTTOM=L7 |
| PE_CLK100M_DR11_1_P | PE_CLK100M_DR11_1-DIFF1 | PAIR | 4 | 6.5 | 5 | 10 | 5 | 12 | 20 | 25 | 12 | 12 | 20 | 12 | 7.5 | 85 Ohms | TOP=L2:L3=L2/L4:L6=L5/L7:BOTTOM=L7 |
| PE_CLK100M_DR11_1_P | PE_CLK100M_DR11_1-DIFF1 | PAIR | 5 | 6.5 | 5 | 10 | 5 | 12 | 20 | 25 | 12 | 12 | 20 | 12 | 7.5 | 85 Ohms | TOP=L2:L3=L2/L4:L6=L5/L7:BOTTOM=L7 |
| PE_CLK100M_DR11_1_P | PE_CLK100M_DR11_1-DIFF1 | PAIR | 6 | 6.5 | 5 | 10 | 5 | 12 | 20 | 25 | 12 | 12 | 20 | 12 | 7.5 | 85 Ohms | TOP=L2:L3=L2/L4:L6=L5/L7:BOTTOM=L7 |
| PE_CLK100M_DR11_1_P | PE_CLK100M_DR11_1-DIFF1 | PAIR | 7 | 6.5 | 5 | 10 | 5 | 12 | 20 | 25 | 12 | 12 | 20 | 12 | 7.5 | 85 Ohms | TOP=L2:L3=L2/L4:L6=L5/L7:BOTTOM=L7 |
| PE_CLK100M_DR11_1_P | PE_CLK100M_DR11_1-DIFF1 | PAIR | 8 | 6.88 | 5 | 10 | 5 | 12 | 20 | 36 | 12 | 12 | 20 | 12 | 5.13 | 85 Ohms | TOP=L2:L3=L2/L4:L6=L5/L7:BOTTOM=L7 |
| PE_CLK100M_DR11_2_N | PE_CLK100M_DR11_2-DIFF1 | PAIR | 1 | 6.88 | 5 | 10 | 5 | 12 | 20 | 36 | 12 | 12 | 20 | 12 | 5.13 | 85 Ohms | TOP=L2:L3=L2/L4:L6=L5/L7:BOTTOM=L7 |
| PE_CLK100M_DR11_2_N | PE_CLK100M_DR11_2-DIFF1 | PAIR | 2 | 6.5 | 5 | 10 | 5 | 12 | 20 | 25 | 12 | 12 | 20 | 12 | 7.5 | 85 Ohms | TOP=L2:L3=L2/L4:L6=L5/L7:BOTTOM=L7 |
| PE_CLK100M_DR11_2_N | PE_CLK100M_DR11_2-DIFF1 | PAIR | 3 | 6.5 | 5 | 10 | 5 | 12 | 20 | 25 | 12 | 12 | 20 | 12 | 7.5 | 85 Ohms | TOP=L2:L3=L2/L4:L6=L5/L7:BOTTOM=L7 |
| PE_CLK100M_DR11_2_N | PE_CLK100M_DR11_2-DIFF1 | PAIR | 4 | 6.5 | 5 | 10 | 5 | 12 | 20 | 25 | 12 | 12 | 20 | 12 | 7.5 | 85 Ohms | TOP=L2:L3=L2/L4:L6=L5/L7:BOTTOM=L7 |
| PE_CLK100M_DR11_2_N | PE_CLK100M_DR11_2-DIFF1 | PAIR | 5 | 6.5 | 5 | 10 | 5 | 12 | 20 | 25 | 12 | 12 | 20 | 12 | 7.5 | 85 Ohms | TOP=L2:L3=L2/L4:L6=L5/L7:BOTTOM=L7 |
| PE_CLK100M_DR11_2_N | PE_CLK100M_DR11_2-DIFF1 | PAIR | 6 | 6.5 | 5 | 10 | 5 | 12 | 20 | 25 | 12 | 12 | 20 | 12 | 7.5 | 85 Ohms | TOP=L2:L3=L2/L4:L6=L5/L7:BOTTOM=L7 |
| PE_CLK100M_DR11_2_N | PE_CLK100M_DR11_2-DIFF1 | PAIR | 7 | 6.5 | 5 | 10 | 5 | 12 | 20 | 25 | 12 | 12 | 20 | 12 | 7.5 | 85 Ohms | TOP=L2:L3=L2/L4:L6=L5/L7:BOTTOM=L7 |
| PE_CLK100M_DR11_2_N | PE_CLK100M_DR11_2-DIFF1 | PAIR | 8 | 6.88 | 5 | 10 | 5 | 12 | 20 | 36 | 12 | 12 | 20 | 12 | 5.13 | 85 Ohms | TOP=L2:L3=L2/L4:L6=L5/L7:BOTTOM=L7 |
| PE_CLK100M_DR11_2_P | PE_CLK100M_DR11_2-DIFF1 | PAIR | 1 | 6.88 | 5 | 10 | 5 | 12 | 20 | 36 | 12 | 12 | 20 | 12 | 5.13 | 85 Ohms | TOP=L2:L3=L2/L4:L6=L5/L7:BOTTOM=L7 |
| PE_CLK100M_DR11_2_P | PE_CLK100M_DR11_2-DIFF1 | PAIR | 2 | 6.5 | 5 | 10 | 5 | 12 | 20 | 25 | 12 | 12 | 20 | 12 | 7.5 | 85 Ohms | TOP=L2:L3=L2/L4:L6=L5/L7:BOTTOM=L7 |
| PE_CLK100M_DR11_2_P | PE_CLK100M_DR11_2-DIFF1 | PAIR | 3 | 6.5 | 5 | 10 | 5 | 12 | 20 | 25 | 12 | 12 | 20 | 12 | 7.5 | 85 Ohms | TOP=L2:L3=L2/L4:L6=L5/L7:BOTTOM=L7 |
| PE_CLK100M_DR11_2_P | PE_CLK100M_DR11_2-DIFF1 | PAIR | 4 | 6.5 | 5 | 10 | 5 | 12 | 20 | 25 | 12 | 12 | 20 | 12 | 7.5 | 85 Ohms | TOP=L2:L3=L2/L4:L6=L5/L7:BOTTOM=L7 |
| PE_CLK100M_DR11_2_P | PE_CLK100M_DR11_2-DIFF1 | PAIR | 5 | 6.5 | 5 | 10 | 5 | 12 | 20 | 25 | 12 | 12 | 20 | 12 | 7.5 | 85 Ohms | TOP=L2:L3=L2/L4:L6=L5/L7:BOTTOM=L7 |
| PE_CLK100M_DR11_2_P | PE_CLK100M_DR11_2-DIFF1 | PAIR | 6 | 6.5 | 5 | 10 | 5 | 12 | 20 | 25 | 12 | 12 | 20 | 12 | 7.5 | 85 Ohms | TOP=L2:L3=L2/L4:L6=L5/L7:BOTTOM=L7 |
| PE_CLK100M_DR11_2_P | PE_CLK100M_DR11_2-DIFF1 | PAIR | 7 | 6.5 | 5 | 10 | 5 | 12 | 20 | 25 | 12 | 12 | 20 | 12 | 7.5 | 85 Ohms | TOP=L2:L3=L2/L4:L6=L5/L7:BOTTOM=L7 |
| PE_CLK100M_DR11_2_P | PE_CLK100M_DR11_2-DIFF1 | PAIR | 8 | 6.88 | 5 | 10 | 5 | 12 | 20 | 36 | 12 | 12 | 20 | 12 | 5.13 | 85 Ohms | TOP=L2:L3=L2/L4:L6=L5/L7:BOTTOM=L7 |
| PE_CLK100M_DR12_1_N | PE_CLK100M_DR12_1-DIFF1 | PAIR | 1 | 6.88 | 5 | 10 | 5 | 12 | 20 | 36 | 12 | 12 | 20 | 12 | 5.13 | 85 Ohms | TOP=L2:L3=L2/L4:L6=L5/L7:BOTTOM=L7 |
| PE_CLK100M_DR12_1_N | PE_CLK100M_DR12_1-DIFF1 | PAIR | 2 | 6.5 | 5 | 10 | 5 | 12 | 20 | 25 | 12 | 12 | 20 | 12 | 7.5 | 85 Ohms | TOP=L2:L3=L2/L4:L6=L5/L7:BOTTOM=L7 |
| PE_CLK100M_DR12_1_N | PE_CLK100M_DR12_1-DIFF1 | PAIR | 3 | 6.5 | 5 | 10 | 5 | 12 | 20 | 25 | 12 | 12 | 20 | 12 | 7.5 | 85 Ohms | TOP=L2:L3=L2/L4:L6=L5/L7:BOTTOM=L7 |
| PE_CLK100M_DR12_1_N | PE_CLK100M_DR12_1-DIFF1 | PAIR | 4 | 6.5 | 5 | 10 | 5 | 12 | 20 | 25 | 12 | 12 | 20 | 12 | 7.5 | 85 Ohms | TOP=L2:L3=L2/L4:L6=L5/L7:BOTTOM=L7 |
| PE_CLK100M_DR12_1_N | PE_CLK100M_DR12_1-DIFF1 | PAIR | 5 | 6.5 | 5 | 10 | 5 | 12 | 20 | 25 | 12 | 12 | 20 | 12 | 7.5 | 85 Ohms | TOP=L2:L3=L2/L4:L6=L5/L7:BOTTOM=L7 |
| PE_CLK100M_DR12_1_N | PE_CLK100M_DR12_1-DIFF1 | PAIR | 6 | 6.5 | 5 | 10 | 5 | 12 | 20 | 25 | 12 | 12 | 20 | 12 | 7.5 | 85 Ohms | TOP=L2:L3=L2/L4:L6=L5/L7:BOTTOM=L7 |
| PE_CLK100M_DR12_1_N | PE_CLK100M_DR12_1-DIFF1 | PAIR | 7 | 6.5 | 5 | 10 | 5 | 12 | 20 | 25 | 12 | 12 | 20 | 12 | 7.5 | 85 Ohms | TOP=L2:L3=L2/L4:L6=L5/L7:BOTTOM=L7 |
| PE_CLK100M_DR12_1_N | PE_CLK100M_DR12_1-DIFF1 | PAIR | 8 | 6.88 | 5 | 10 | 5 | 12 | 20 | 36 | 12 | 12 | 20 | 12 | 5.13 | 85 Ohms | TOP=L2:L3=L2/L4:L6=L5/L7:BOTTOM=L7 |
| PE_CLK100M_DR12_1_P | PE_CLK100M_DR12_1-DIFF1 | PAIR | 1 | 6.88 | 5 | 10 | 5 | 12 | 20 | 36 | 12 | 12 | 20 | 12 | 5.13 | 85 Ohms | TOP=L2:L3=L2/L4:L6=L5/L7:BOTTOM=L7 |
| PE_CLK100M_DR12_1_P | PE_CLK100M_DR12_1-DIFF1 | PAIR | 2 | 6.5 | 5 | 10 | 5 | 12 | 20 | 25 | 12 | 12 | 20 | 12 | 7.5 | 85 Ohms | TOP=L2:L3=L2/L4:L6=L5/L7:BOTTOM=L7 |
| PE_CLK100M_DR12_1_P | PE_CLK100M_DR12_1-DIFF1 | PAIR | 3 | 6.5 | 5 | 10 | 5 | 12 | 20 | 25 | 12 | 12 | 20 | 12 | 7.5 | 85 Ohms | TOP=L2:L3=L2/L4:L6=L5/L7:BOTTOM=L7 |
| PE_CLK100M_DR12_1_P | PE_CLK100M_DR12_1-DIFF1 | PAIR | 4 | 6.5 | 5 | 10 | 5 | 12 | 20 | 25 | 12 | 12 | 20 | 12 | 7.5 | 85 Ohms | TOP=L2:L3=L2/L4:L6=L5/L7:BOTTOM=L7 |
| PE_CLK100M_DR12_1_P | PE_CLK100M_DR12_1-DIFF1 | PAIR | 5 | 6.5 | 5 | 10 | 5 | 12 | 20 | 25 | 12 | 12 | 20 | 12 | 7.5 | 85 Ohms | TOP=L2:L3=L2/L4:L6=L5/L7:BOTTOM=L7 |
| PE_CLK100M_DR12_1_P | PE_CLK100M_DR12_1-DIFF1 | PAIR | 6 | 6.5 | 5 | 10 | 5 | 12 | 20 | 25 | 12 | 12 | 20 | 12 | 7.5 | 85 Ohms | TOP=L2:L3=L2/L4:L6=L5/L7:BOTTOM=L7 |
| PE_CLK100M_DR12_1_P | PE_CLK100M_DR12_1-DIFF1 | PAIR | 7 | 6.5 | 5 | 10 | 5 | 12 | 20 | 25 | 12 | 12 | 20 | 12 | 7.5 | 85 Ohms | TOP=L2:L3=L2/L4:L6=L5/L7:BOTTOM=L7 |
| PE_CLK100M_DR12_1_P | PE_CLK100M_DR12_1-DIFF1 | PAIR | 8 | 6.88 | 5 | 10 | 5 | 12 | 20 | 36 | 12 | 12 | 20 | 12 | 5.13 | 85 Ohms | TOP=L2:L3=L2/L4:L6=L5/L7:BOTTOM=L7 |
| PE_CLK100M_DR12_2_N | PE_CLK100M_DR12_2-DIFF1 | PAIR | 1 | 6.88 | 5 | 10 | 5 | 12 | 20 | 36 | 12 | 12 | 20 | 12 | 5.13 | 85 Ohms | TOP=L2:L3=L2/L4:L6=L5/L7:BOTTOM=L7 |
| PE_CLK100M_DR12_2_N | PE_CLK100M_DR12_2-DIFF1 | PAIR | 2 | 6.5 | 5 | 10 | 5 | 12 | 20 | 25 | 12 | 12 | 20 | 12 | 7.5 | 85 Ohms | TOP=L2:L3=L2/L4:L6=L5/L7:BOTTOM=L7 |
| PE_CLK100M_DR12_2_N | PE_CLK100M_DR12_2-DIFF1 | PAIR | 3 | 6.5 | 5 | 10 | 5 | 12 | 20 | 25 | 12 | 12 | 20 | 12 | 7.5 | 85 Ohms | TOP=L2:L3=L2/L4:L6=L5/L7:BOTTOM=L7 |
| PE_CLK100M_DR12_2_N | PE_CLK100M_DR12_2-DIFF1 | PAIR | 4 | 6.5 | 5 | 10 | 5 | 12 | 20 | 25 | 12 | 12 | 20 | 12 | 7.5 | 85 Ohms | TOP=L2:L3=L2/L4:L6=L5/L7:BOTTOM=L7 |
| PE_CLK100M_DR12_2_N | PE_CLK100M_DR12_2-DIFF1 | PAIR | 5 | 6.5 | 5 | 10 | 5 | 12 | 20 | 25 | 12 | 12 | 20 | 12 | 7.5 | 85 Ohms | TOP=L2:L3=L2/L4:L6=L5/L7:BOTTOM=L7 |
| PE_CLK100M_DR12_2_N | PE_CLK100M_DR12_2-DIFF1 | PAIR | 6 | 6.5 | 5 | 10 | 5 | 12 | 20 | 25 | 12 | 12 | 20 | 12 | 7.5 | 85 Ohms | TOP=L2:L3=L2/L4:L6=L5/L7:BOTTOM=L7 |
| PE_CLK100M_DR12_2_N | PE_CLK100M_DR12_2-DIFF1 | PAIR | 7 | 6.5 | 5 | 10 | 5 | 12 | 20 | 25 | 12 | 12 | 20 | 12 | 7.5 | 85 Ohms | TOP=L2:L3=L2/L4:L6=L5/L7:BOTTOM=L7 |
| PE_CLK100M_DR12_2_N | PE_CLK100M_DR12_2-DIFF1 | PAIR | 8 | 6.88 | 5 | 10 | 5 | 12 | 20 | 36 | 12 | 12 | 20 | 12 | 5.13 | 85 Ohms | TOP=L2:L3=L2/L4:L6=L5/L7:BOTTOM=L7 |
| PE_CLK100M_DR12_2_P | PE_CLK100M_DR12_2-DIFF1 | PAIR | 1 | 6.88 | 5 | 10 | 5 | 12 | 20 | 36 | 12 | 12 | 20 | 12 | 5.13 | 85 Ohms | TOP=L2:L3=L2/L4:L6=L5/L7:BOTTOM=L7 |
| PE_CLK100M_DR12_2_P | PE_CLK100M_DR12_2-DIFF1 | PAIR | 2 | 6.5 | 5 | 10 | 5 | 12 | 20 | 25 | 12 | 12 | 20 | 12 | 7.5 | 85 Ohms | TOP=L2:L3=L2/L4:L6=L5/L7:BOTTOM=L7 |
| PE_CLK100M_DR12_2_P | PE_CLK100M_DR12_2-DIFF1 | PAIR | 3 | 6.5 | 5 | 10 | 5 | 12 | 20 | 25 | 12 | 12 | 20 | 12 | 7.5 | 85 Ohms | TOP=L2:L3=L2/L4:L6=L5/L7:BOTTOM=L7 |
| PE_CLK100M_DR12_2_P | PE_CLK100M_DR12_2-DIFF1 | PAIR | 4 | 6.5 | 5 | 10 | 5 | 12 | 20 | 25 | 12 | 12 | 20 | 12 | 7.5 | 85 Ohms | TOP=L2:L3=L2/L4:L6=L5/L7:BOTTOM=L7 |
| PE_CLK100M_DR12_2_P | PE_CLK100M_DR12_2-DIFF1 | PAIR | 5 | 6.5 | 5 | 10 | 5 | 12 | 20 | 25 | 12 | 12 | 20 | 12 | 7.5 | 85 Ohms | TOP=L2:L3=L2/L4:L6=L5/L7:BOTTOM=L7 |
| PE_CLK100M_DR12_2_P | PE_CLK100M_DR12_2-DIFF1 | PAIR | 6 | 6.5 | 5 | 10 | 5 | 12 | 20 | 25 | 12 | 12 | 20 | 12 | 7.5 | 85 Ohms | TOP=L2:L3=L2/L4:L6=L5/L7:BOTTOM=L7 |
| PE_CLK100M_DR12_2_P | PE_CLK100M_DR12_2-DIFF1 | PAIR | 7 | 6.5 | 5 | 10 | 5 | 12 | 20 | 25 | 12 | 12 | 20 | 12 | 7.5 | 85 Ohms | TOP=L2:L3=L2/L4:L6=L5/L7:BOTTOM=L7 |
| PE_CLK100M_DR12_2_P | PE_CLK100M_DR12_2-DIFF1 | PAIR | 8 | 6.88 | 5 | 10 | 5 | 12 | 20 | 36 | 12 | 12 | 20 | 12 | 5.13 | 85 Ohms | TOP=L2:L3=L2/L4:L6=L5/L7:BOTTOM=L7 |
| PE_CLK100M_DR13_1_N | PE_CLK100M_DR13_1-DIFF1 | PAIR | 1 | 6.88 | 5 | 10 | 5 | 12 | 20 | 36 | 12 | 12 | 20 | 12 | 5.13 | 85 Ohms | TOP=L2:L3=L2/L4:L6=L5/L7:BOTTOM=L7 |
| PE_CLK100M_DR13_1_N | PE_CLK100M_DR13_1-DIFF1 | PAIR | 2 | 6.5 | 5 | 10 | 5 | 12 | 20 | 25 | 12 | 12 | 20 | 12 | 7.5 | 85 Ohms | TOP=L2:L3=L2/L4:L6=L5/L7:BOTTOM=L7 |
| PE_CLK100M_DR13_1_N | PE_CLK100M_DR13_1-DIFF1 | PAIR | 3 | 6.5 | 5 | 10 | 5 | 12 | 20 | 25 | 12 | 12 | 20 | 12 | 7.5 | 85 Ohms | TOP=L2:L3=L2/L4:L6=L5/L7:BOTTOM=L7 |
| PE_CLK100M_DR13_1_N | PE_CLK100M_DR13_1-DIFF1 | PAIR | 4 | 6.5 | 5 | 10 | 5 | 12 | 20 | 25 | 12 | 12 | 20 | 12 | 7.5 | 85 Ohms | TOP=L2:L3=L2/L4:L6=L5/L7:BOTTOM=L7 |
| PE_CLK100M_DR13_1_N | PE_CLK100M_DR13_1-DIFF1 | PAIR | 5 | 6.5 | 5 | 10 | 5 | 12 | 20 | 25 | 12 | 12 | 20 | 12 | 7.5 | 85 Ohms | TOP=L2:L3=L2/L4:L6=L5/L7:BOTTOM=L7 |
| PE_CLK100M_DR13_1_N | PE_CLK100M_DR13_1-DIFF1 | PAIR | 6 | 6.5 | 5 | 10 | 5 | 12 | 20 | 25 | 12 | 12 | 20 | 12 | 7.5 | 85 Ohms | TOP=L2:L3=L2/L4:L6=L5/L7:BOTTOM=L7 |
| PE_CLK100M_DR13_1_N | PE_CLK100M_DR13_1-DIFF1 | PAIR | 7 | 6.5 | 5 | 10 | 5 | 12 | 20 | 25 | 12 | 12 | 20 | 12 | 7.5 | 85 Ohms | TOP=L2:L3=L2/L4:L6=L5/L7:BOTTOM=L7 |
| PE_CLK100M_DR13_1_N | PE_CLK100M_DR13_1-DIFF1 | PAIR | 8 | 6.88 | 5 | 10 | 5 | 12 | 20 | 36 | 12 | 12 | 20 | 12 | 5.13 | 85 Ohms | TOP=L2:L3=L2/L4:L6=L5/L7:BOTTOM=L7 |
| PE_CLK100M_DR13_1_P | PE_CLK100M_DR13_1-DIFF1 | PAIR | 1 | 6.88 | 5 | 10 | 5 | 12 | 20 | 36 | 12 | 12 | 20 | 12 | 5.13 | 85 Ohms | TOP=L2:L3=L2/L4:L6=L5/L7:BOTTOM=L7 |
| PE_CLK100M_DR13_1_P | PE_CLK100M_DR13_1-DIFF1 | PAIR | 2 | 6.5 | 5 | 10 | 5 | 12 | 20 | 25 | 12 | 12 | 20 | 12 | 7.5 | 85 Ohms | TOP=L2:L3=L2/L4:L6=L5/L7:BOTTOM=L7 |
| PE_CLK100M_DR13_1_P | PE_CLK100M_DR13_1-DIFF1 | PAIR | 3 | 6.5 | 5 | 10 | 5 | 12 | 20 | 25 | 12 | 12 | 20 | 12 | 7.5 | 85 Ohms | TOP=L2:L3=L2/L4:L6=L5/L7:BOTTOM=L7 |
| PE_CLK100M_DR13_1_P | PE_CLK100M_DR13_1-DIFF1 | PAIR | 4 | 6.5 | 5 | 10 | 5 | 12 | 20 | 25 | 12 | 12 | 20 | 12 | 7.5 | 85 Ohms | TOP=L2:L3=L2/L4:L6=L5/L7:BOTTOM=L7 |
| PE_CLK100M_DR13_1_P | PE_CLK100M_DR13_1-DIFF1 | PAIR | 5 | 6.5 | 5 | 10 | 5 | 12 | 20 | 25 | 12 | 12 | 20 | 12 | 7.5 | 85 Ohms | TOP=L2:L3=L2/L4:L6=L5/L7:BOTTOM=L7 |
| PE_CLK100M_DR13_1_P | PE_CLK100M_DR13_1-DIFF1 | PAIR | 6 | 6.5 | 5 | 10 | 5 | 12 | 20 | 25 | 12 | 12 | 20 | 12 | 7.5 | 85 Ohms | TOP=L2:L3=L2/L4:L6=L5/L7:BOTTOM=L7 |
| PE_CLK100M_DR13_1_P | PE_CLK100M_DR13_1-DIFF1 | PAIR | 7 | 6.5 | 5 | 10 | 5 | 12 | 20 | 25 | 12 | 12 | 20 | 12 | 7.5 | 85 Ohms | TOP=L2:L3=L2/L4:L6=L5/L7:BOTTOM=L7 |
| PE_CLK100M_DR13_1_P | PE_CLK100M_DR13_1-DIFF1 | PAIR | 8 | 6.88 | 5 | 10 | 5 | 12 | 20 | 36 | 12 | 12 | 20 | 12 | 5.13 | 85 Ohms | TOP=L2:L3=L2/L4:L6=L5/L7:BOTTOM=L7 |
| PE_CLK100M_DR13_2_N | PE_CLK100M_DR13_2-DIFF1 | PAIR | 1 | 6.88 | 5 | 10 | 5 | 12 | 20 | 36 | 12 | 12 | 20 | 12 | 5.13 | 85 Ohms | TOP=L2:L3=L2/L4:L6=L5/L7:BOTTOM=L7 |
| PE_CLK100M_DR13_2_N | PE_CLK100M_DR13_2-DIFF1 | PAIR | 2 | 6.5 | 5 | 10 | 5 | 12 | 20 | 25 | 12 | 12 | 20 | 12 | 7.5 | 85 Ohms | TOP=L2:L3=L2/L4:L6=L5/L7:BOTTOM=L7 |
| PE_CLK100M_DR13_2_N | PE_CLK100M_DR13_2-DIFF1 | PAIR | 3 | 6.5 | 5 | 10 | 5 | 12 | 20 | 25 | 12 | 12 | 20 | 12 | 7.5 | 85 Ohms | TOP=L2:L3=L2/L4:L6=L5/L7:BOTTOM=L7 |
| PE_CLK100M_DR13_2_N | PE_CLK100M_DR13_2-DIFF1 | PAIR | 4 | 6.5 | 5 | 10 | 5 | 12 | 20 | 25 | 12 | 12 | 20 | 12 | 7.5 | 85 Ohms | TOP=L2:L3=L2/L4:L6=L5/L7:BOTTOM=L7 |
| PE_CLK100M_DR13_2_N | PE_CLK100M_DR13_2-DIFF1 | PAIR | 5 | 6.5 | 5 | 10 | 5 | 12 | 20 | 25 | 12 | 12 | 20 | 12 | 7.5 | 85 Ohms | TOP=L2:L3=L2/L4:L6=L5/L7:BOTTOM=L7 |
| PE_CLK100M_DR13_2_N | PE_CLK100M_DR13_2-DIFF1 | PAIR | 6 | 6.5 | 5 | 10 | 5 | 12 | 20 | 25 | 12 | 12 | 20 | 12 | 7.5 | 85 Ohms | TOP=L2:L3=L2/L4:L6=L5/L7:BOTTOM=L7 |
| PE_CLK100M_DR13_2_N | PE_CLK100M_DR13_2-DIFF1 | PAIR | 7 | 6.5 | 5 | 10 | 5 | 12 | 20 | 25 | 12 | 12 | 20 | 12 | 7.5 | 85 Ohms | TOP=L2:L3=L2/L4:L6=L5/L7:BOTTOM=L7 |
| PE_CLK100M_DR13_2_N | PE_CLK100M_DR13_2-DIFF1 | PAIR | 8 | 6.88 | 5 | 10 | 5 | 12 | 20 | 36 | 12 | 12 | 20 | 12 | 5.13 | 85 Ohms | TOP=L2:L3=L2/L4:L6=L5/L7:BOTTOM=L7 |
| PE_CLK100M_DR13_2_P | PE_CLK100M_DR13_2-DIFF1 | PAIR | 1 | 6.88 | 5 | 10 | 5 | 12 | 20 | 36 | 12 | 12 | 20 | 12 | 5.13 | 85 Ohms | TOP=L2:L3=L2/L4:L6=L5/L7:BOTTOM=L7 |
| PE_CLK100M_DR13_2_P | PE_CLK100M_DR13_2-DIFF1 | PAIR | 2 | 6.5 | 5 | 10 | 5 | 12 | 20 | 25 | 12 | 12 | 20 | 12 | 7.5 | 85 Ohms | TOP=L2:L3=L2/L4:L6=L5/L7:BOTTOM=L7 |
| PE_CLK100M_DR13_2_P | PE_CLK100M_DR13_2-DIFF1 | PAIR | 3 | 6.5 | 5 | 10 | 5 | 12 | 20 | 25 | 12 | 12 | 20 | 12 | 7.5 | 85 Ohms | TOP=L2:L3=L2/L4:L6=L5/L7:BOTTOM=L7 |
| PE_CLK100M_DR13_2_P | PE_CLK100M_DR13_2-DIFF1 | PAIR | 4 | 6.5 | 5 | 10 | 5 | 12 | 20 | 25 | 12 | 12 | 20 | 12 | 7.5 | 85 Ohms | TOP=L2:L3=L2/L4:L6=L5/L7:BOTTOM=L7 |
| PE_CLK100M_DR13_2_P | PE_CLK100M_DR13_2-DIFF1 | PAIR | 5 | 6.5 | 5 | 10 | 5 | 12 | 20 | 25 | 12 | 12 | 20 | 12 | 7.5 | 85 Ohms | TOP=L2:L3=L2/L4:L6=L5/L7:BOTTOM=L7 |
| PE_CLK100M_DR13_2_P | PE_CLK100M_DR13_2-DIFF1 | PAIR | 6 | 6.5 | 5 | 10 | 5 | 12 | 20 | 25 | 12 | 12 | 20 | 12 | 7.5 | 85 Ohms | TOP=L2:L3=L2/L4:L6=L5/L7:BOTTOM=L7 |
| PE_CLK100M_DR13_2_P | PE_CLK100M_DR13_2-DIFF1 | PAIR | 7 | 6.5 | 5 | 10 | 5 | 12 | 20 | 25 | 12 | 12 | 20 | 12 | 7.5 | 85 Ohms | TOP=L2:L3=L2/L4:L6=L5/L7:BOTTOM=L7 |
| PE_CLK100M_DR13_2_P | PE_CLK100M_DR13_2-DIFF1 | PAIR | 8 | 6.88 | 5 | 10 | 5 | 12 | 20 | 36 | 12 | 12 | 20 | 12 | 5.13 | 85 Ohms | TOP=L2:L3=L2/L4:L6=L5/L7:BOTTOM=L7 |
| PE_CLK100M_DR14_1_N | PE_CLK100M_DR14_1-DIFF1 | PAIR | 1 | 6.88 | 5 | 10 | 5 | 12 | 20 | 36 | 12 | 12 | 20 | 12 | 5.13 | 85 Ohms | TOP=L2:L3=L2/L4:L6=L5/L7:BOTTOM=L7 |
| PE_CLK100M_DR14_1_N | PE_CLK100M_DR14_1-DIFF1 | PAIR | 2 | 6.5 | 5 | 10 | 5 | 12 | 20 | 25 | 12 | 12 | 20 | 12 | 7.5 | 85 Ohms | TOP=L2:L3=L2/L4:L6=L5/L7:BOTTOM=L7 |
| PE_CLK100M_DR14_1_N | PE_CLK100M_DR14_1-DIFF1 | PAIR | 3 | 6.5 | 5 | 10 | 5 | 12 | 20 | 25 | 12 | 12 | 20 | 12 | 7.5 | 85 Ohms | TOP=L2:L3=L2/L4:L6=L5/L7:BOTTOM=L7 |
| PE_CLK100M_DR14_1_N | PE_CLK100M_DR14_1-DIFF1 | PAIR | 4 | 6.5 | 5 | 10 | 5 | 12 | 20 | 25 | 12 | 12 | 20 | 12 | 7.5 | 85 Ohms | TOP=L2:L3=L2/L4:L6=L5/L7:BOTTOM=L7 |
| PE_CLK100M_DR14_1_N | PE_CLK100M_DR14_1-DIFF1 | PAIR | 5 | 6.5 | 5 | 10 | 5 | 12 | 20 | 25 | 12 | 12 | 20 | 12 | 7.5 | 85 Ohms | TOP=L2:L3=L2/L4:L6=L5/L7:BOTTOM=L7 |
| PE_CLK100M_DR14_1_N | PE_CLK100M_DR14_1-DIFF1 | PAIR | 6 | 6.5 | 5 | 10 | 5 | 12 | 20 | 25 | 12 | 12 | 20 | 12 | 7.5 | 85 Ohms | TOP=L2:L3=L2/L4:L6=L5/L7:BOTTOM=L7 |
| PE_CLK100M_DR14_1_N | PE_CLK100M_DR14_1-DIFF1 | PAIR | 7 | 6.5 | 5 | 10 | 5 | 12 | 20 | 25 | 12 | 12 | 20 | 12 | 7.5 | 85 Ohms | TOP=L2:L3=L2/L4:L6=L5/L7:BOTTOM=L7 |
| PE_CLK100M_DR14_1_N | PE_CLK100M_DR14_1-DIFF1 | PAIR | 8 | 6.88 | 5 | 10 | 5 | 12 | 20 | 36 | 12 | 12 | 20 | 12 | 5.13 | 85 Ohms | TOP=L2:L3=L2/L4:L6=L5/L7:BOTTOM=L7 |
| PE_CLK100M_DR14_1_P | PE_CLK100M_DR14_1-DIFF1 | PAIR | 1 | 6.88 | 5 | 10 | 5 | 12 | 20 | 36 | 12 | 12 | 20 | 12 | 5.13 | 85 Ohms | TOP=L2:L3=L2/L4:L6=L5/L7:BOTTOM=L7 |
| PE_CLK100M_DR14_1_P | PE_CLK100M_DR14_1-DIFF1 | PAIR | 2 | 6.5 | 5 | 10 | 5 | 12 | 20 | 25 | 12 | 12 | 20 | 12 | 7.5 | 85 Ohms | TOP=L2:L3=L2/L4:L6=L5/L7:BOTTOM=L7 |
| PE_CLK100M_DR14_1_P | PE_CLK100M_DR14_1-DIFF1 | PAIR | 3 | 6.5 | 5 | 10 | 5 | 12 | 20 | 25 | 12 | 12 | 20 | 12 | 7.5 | 85 Ohms | TOP=L2:L3=L2/L4:L6=L5/L7:BOTTOM=L7 |
| PE_CLK100M_DR14_1_P | PE_CLK100M_DR14_1-DIFF1 | PAIR | 4 | 6.5 | 5 | 10 | 5 | 12 | 20 | 25 | 12 | 12 | 20 | 12 | 7.5 | 85 Ohms | TOP=L2:L3=L2/L4:L6=L5/L7:BOTTOM=L7 |
| PE_CLK100M_DR14_1_P | PE_CLK100M_DR14_1-DIFF1 | PAIR | 5 | 6.5 | 5 | 10 | 5 | 12 | 20 | 25 | 12 | 12 | 20 | 12 | 7.5 | 85 Ohms | TOP=L2:L3=L2/L4:L6=L5/L7:BOTTOM=L7 |
| PE_CLK100M_DR14_1_P | PE_CLK100M_DR14_1-DIFF1 | PAIR | 6 | 6.5 | 5 | 10 | 5 | 12 | 20 | 25 | 12 | 12 | 20 | 12 | 7.5 | 85 Ohms | TOP=L2:L3=L2/L4:L6=L5/L7:BOTTOM=L7 |
| PE_CLK100M_DR14_1_P | PE_CLK100M_DR14_1-DIFF1 | PAIR | 7 | 6.5 | 5 | 10 | 5 | 12 | 20 | 25 | 12 | 12 | 20 | 12 | 7.5 | 85 Ohms | TOP=L2:L3=L2/L4:L6=L5/L7:BOTTOM=L7 |
| PE_CLK100M_DR14_1_P | PE_CLK100M_DR14_1-DIFF1 | PAIR | 8 | 6.88 | 5 | 10 | 5 | 12 | 20 | 36 | 12 | 12 | 20 | 12 | 5.13 | 85 Ohms | TOP=L2:L3=L2/L4:L6=L5/L7:BOTTOM=L7 |
| PE_CLK100M_DR14_2_N | PE_CLK100M_DR14_2-DIFF1 | PAIR | 1 | 6.88 | 5 | 10 | 5 | 12 | 20 | 36 | 12 | 12 | 20 | 12 | 5.13 | 85 Ohms | TOP=L2:L3=L2/L4:L6=L5/L7:BOTTOM=L7 |
| PE_CLK100M_DR14_2_N | PE_CLK100M_DR14_2-DIFF1 | PAIR | 2 | 6.5 | 5 | 10 | 5 | 12 | 20 | 25 | 12 | 12 | 20 | 12 | 7.5 | 85 Ohms | TOP=L2:L3=L2/L4:L6=L5/L7:BOTTOM=L7 |
| PE_CLK100M_DR14_2_N | PE_CLK100M_DR14_2-DIFF1 | PAIR | 3 | 6.5 | 5 | 10 | 5 | 12 | 20 | 25 | 12 | 12 | 20 | 12 | 7.5 | 85 Ohms | TOP=L2:L3=L2/L4:L6=L5/L7:BOTTOM=L7 |
| PE_CLK100M_DR14_2_N | PE_CLK100M_DR14_2-DIFF1 | PAIR | 4 | 6.5 | 5 | 10 | 5 | 12 | 20 | 25 | 12 | 12 | 20 | 12 | 7.5 | 85 Ohms | TOP=L2:L3=L2/L4:L6=L5/L7:BOTTOM=L7 |
| PE_CLK100M_DR14_2_N | PE_CLK100M_DR14_2-DIFF1 | PAIR | 5 | 6.5 | 5 | 10 | 5 | 12 | 20 | 25 | 12 | 12 | 20 | 12 | 7.5 | 85 Ohms | TOP=L2:L3=L2/L4:L6=L5/L7:BOTTOM=L7 |
| PE_CLK100M_DR14_2_N | PE_CLK100M_DR14_2-DIFF1 | PAIR | 6 | 6.5 | 5 | 10 | 5 | 12 | 20 | 25 | 12 | 12 | 20 | 12 | 7.5 | 85 Ohms | TOP=L2:L3=L2/L4:L6=L5/L7:BOTTOM=L7 |
| PE_CLK100M_DR14_2_N | PE_CLK100M_DR14_2-DIFF1 | PAIR | 7 | 6.5 | 5 | 10 | 5 | 12 | 20 | 25 | 12 | 12 | 20 | 12 | 7.5 | 85 Ohms | TOP=L2:L3=L2/L4:L6=L5/L7:BOTTOM=L7 |
| PE_CLK100M_DR14_2_N | PE_CLK100M_DR14_2-DIFF1 | PAIR | 8 | 6.88 | 5 | 10 | 5 | 12 | 20 | 36 | 12 | 12 | 20 | 12 | 5.13 | 85 Ohms | TOP=L2:L3=L2/L4:L6=L5/L7:BOTTOM=L7 |
| PE_CLK100M_DR14_2_P | PE_CLK100M_DR14_2-DIFF1 | PAIR | 1 | 6.88 | 5 | 10 | 5 | 12 | 20 | 36 | 12 | 12 | 20 | 12 | 5.13 | 85 Ohms | TOP=L2:L3=L2/L4:L6=L5/L7:BOTTOM=L7 |
| PE_CLK100M_DR14_2_P | PE_CLK100M_DR14_2-DIFF1 | PAIR | 2 | 6.5 | 5 | 10 | 5 | 12 | 20 | 25 | 12 | 12 | 20 | 12 | 7.5 | 85 Ohms | TOP=L2:L3=L2/L4:L6=L5/L7:BOTTOM=L7 |
| PE_CLK100M_DR14_2_P | PE_CLK100M_DR14_2-DIFF1 | PAIR | 3 | 6.5 | 5 | 10 | 5 | 12 | 20 | 25 | 12 | 12 | 20 | 12 | 7.5 | 85 Ohms | TOP=L2:L3=L2/L4:L6=L5/L7:BOTTOM=L7 |
| PE_CLK100M_DR14_2_P | PE_CLK100M_DR14_2-DIFF1 | PAIR | 4 | 6.5 | 5 | 10 | 5 | 12 | 20 | 25 | 12 | 12 | 20 | 12 | 7.5 | 85 Ohms | TOP=L2:L3=L2/L4:L6=L5/L7:BOTTOM=L7 |
| PE_CLK100M_DR14_2_P | PE_CLK100M_DR14_2-DIFF1 | PAIR | 5 | 6.5 | 5 | 10 | 5 | 12 | 20 | 25 | 12 | 12 | 20 | 12 | 7.5 | 85 Ohms | TOP=L2:L3=L2/L4:L6=L5/L7:BOTTOM=L7 |
| PE_CLK100M_DR14_2_P | PE_CLK100M_DR14_2-DIFF1 | PAIR | 6 | 6.5 | 5 | 10 | 5 | 12 | 20 | 25 | 12 | 12 | 20 | 12 | 7.5 | 85 Ohms | TOP=L2:L3=L2/L4:L6=L5/L7:BOTTOM=L7 |
| PE_CLK100M_DR14_2_P | PE_CLK100M_DR14_2-DIFF1 | PAIR | 7 | 6.5 | 5 | 10 | 5 | 12 | 20 | 25 | 12 | 12 | 20 | 12 | 7.5 | 85 Ohms | TOP=L2:L3=L2/L4:L6=L5/L7:BOTTOM=L7 |
| PE_CLK100M_DR14_2_P | PE_CLK100M_DR14_2-DIFF1 | PAIR | 8 | 6.88 | 5 | 10 | 5 | 12 | 20 | 36 | 12 | 12 | 20 | 12 | 5.13 | 85 Ohms | TOP=L2:L3=L2/L4:L6=L5/L7:BOTTOM=L7 |
| PE_CLK100M_DR2_1_N | PE_CLK100M_DR2_1-DIFF1 | PAIR | 1 | 6.88 | 5 | 10 | 5 | 12 | 20 | 36 | 12 | 12 | 20 | 12 | 5.13 | 85 Ohms | TOP=L2:L3=L2/L4:L6=L5/L7:BOTTOM=L7 |
| PE_CLK100M_DR2_1_N | PE_CLK100M_DR2_1-DIFF1 | PAIR | 2 | 6.5 | 5 | 10 | 5 | 12 | 20 | 25 | 12 | 12 | 20 | 12 | 7.5 | 85 Ohms | TOP=L2:L3=L2/L4:L6=L5/L7:BOTTOM=L7 |
| PE_CLK100M_DR2_1_N | PE_CLK100M_DR2_1-DIFF1 | PAIR | 3 | 6.5 | 5 | 10 | 5 | 12 | 20 | 25 | 12 | 12 | 20 | 12 | 7.5 | 85 Ohms | TOP=L2:L3=L2/L4:L6=L5/L7:BOTTOM=L7 |
| PE_CLK100M_DR2_1_N | PE_CLK100M_DR2_1-DIFF1 | PAIR | 4 | 6.5 | 5 | 10 | 5 | 12 | 20 | 25 | 12 | 12 | 20 | 12 | 7.5 | 85 Ohms | TOP=L2:L3=L2/L4:L6=L5/L7:BOTTOM=L7 |
| PE_CLK100M_DR2_1_N | PE_CLK100M_DR2_1-DIFF1 | PAIR | 5 | 6.5 | 5 | 10 | 5 | 12 | 20 | 25 | 12 | 12 | 20 | 12 | 7.5 | 85 Ohms | TOP=L2:L3=L2/L4:L6=L5/L7:BOTTOM=L7 |
| PE_CLK100M_DR2_1_N | PE_CLK100M_DR2_1-DIFF1 | PAIR | 6 | 6.5 | 5 | 10 | 5 | 12 | 20 | 25 | 12 | 12 | 20 | 12 | 7.5 | 85 Ohms | TOP=L2:L3=L2/L4:L6=L5/L7:BOTTOM=L7 |
| PE_CLK100M_DR2_1_N | PE_CLK100M_DR2_1-DIFF1 | PAIR | 7 | 6.5 | 5 | 10 | 5 | 12 | 20 | 25 | 12 | 12 | 20 | 12 | 7.5 | 85 Ohms | TOP=L2:L3=L2/L4:L6=L5/L7:BOTTOM=L7 |
| PE_CLK100M_DR2_1_N | PE_CLK100M_DR2_1-DIFF1 | PAIR | 8 | 6.88 | 5 | 10 | 5 | 12 | 20 | 36 | 12 | 12 | 20 | 12 | 5.13 | 85 Ohms | TOP=L2:L3=L2/L4:L6=L5/L7:BOTTOM=L7 |
| PE_CLK100M_DR2_1_P | PE_CLK100M_DR2_1-DIFF1 | PAIR | 1 | 6.88 | 5 | 10 | 5 | 12 | 20 | 36 | 12 | 12 | 20 | 12 | 5.13 | 85 Ohms | TOP=L2:L3=L2/L4:L6=L5/L7:BOTTOM=L7 |
| PE_CLK100M_DR2_1_P | PE_CLK100M_DR2_1-DIFF1 | PAIR | 2 | 6.5 | 5 | 10 | 5 | 12 | 20 | 25 | 12 | 12 | 20 | 12 | 7.5 | 85 Ohms | TOP=L2:L3=L2/L4:L6=L5/L7:BOTTOM=L7 |
| PE_CLK100M_DR2_1_P | PE_CLK100M_DR2_1-DIFF1 | PAIR | 3 | 6.5 | 5 | 10 | 5 | 12 | 20 | 25 | 12 | 12 | 20 | 12 | 7.5 | 85 Ohms | TOP=L2:L3=L2/L4:L6=L5/L7:BOTTOM=L7 |
| PE_CLK100M_DR2_1_P | PE_CLK100M_DR2_1-DIFF1 | PAIR | 4 | 6.5 | 5 | 10 | 5 | 12 | 20 | 25 | 12 | 12 | 20 | 12 | 7.5 | 85 Ohms | TOP=L2:L3=L2/L4:L6=L5/L7:BOTTOM=L7 |
| PE_CLK100M_DR2_1_P | PE_CLK100M_DR2_1-DIFF1 | PAIR | 5 | 6.5 | 5 | 10 | 5 | 12 | 20 | 25 | 12 | 12 | 20 | 12 | 7.5 | 85 Ohms | TOP=L2:L3=L2/L4:L6=L5/L7:BOTTOM=L7 |
| PE_CLK100M_DR2_1_P | PE_CLK100M_DR2_1-DIFF1 | PAIR | 6 | 6.5 | 5 | 10 | 5 | 12 | 20 | 25 | 12 | 12 | 20 | 12 | 7.5 | 85 Ohms | TOP=L2:L3=L2/L4:L6=L5/L7:BOTTOM=L7 |
| PE_CLK100M_DR2_1_P | PE_CLK100M_DR2_1-DIFF1 | PAIR | 7 | 6.5 | 5 | 10 | 5 | 12 | 20 | 25 | 12 | 12 | 20 | 12 | 7.5 | 85 Ohms | TOP=L2:L3=L2/L4:L6=L5/L7:BOTTOM=L7 |
| PE_CLK100M_DR2_1_P | PE_CLK100M_DR2_1-DIFF1 | PAIR | 8 | 6.88 | 5 | 10 | 5 | 12 | 20 | 36 | 12 | 12 | 20 | 12 | 5.13 | 85 Ohms | TOP=L2:L3=L2/L4:L6=L5/L7:BOTTOM=L7 |
| PE_CLK100M_DR2_2_N | PE_CLK100M_DR2_2-DIFF1 | PAIR | 1 | 6.88 | 5 | 10 | 5 | 12 | 20 | 36 | 12 | 12 | 20 | 12 | 5.13 | 85 Ohms | TOP=L2:L3=L2/L4:L6=L5/L7:BOTTOM=L7 |
| PE_CLK100M_DR2_2_N | PE_CLK100M_DR2_2-DIFF1 | PAIR | 2 | 6.5 | 5 | 10 | 5 | 12 | 20 | 25 | 12 | 12 | 20 | 12 | 7.5 | 85 Ohms | TOP=L2:L3=L2/L4:L6=L5/L7:BOTTOM=L7 |
| PE_CLK100M_DR2_2_N | PE_CLK100M_DR2_2-DIFF1 | PAIR | 3 | 6.5 | 5 | 10 | 5 | 12 | 20 | 25 | 12 | 12 | 20 | 12 | 7.5 | 85 Ohms | TOP=L2:L3=L2/L4:L6=L5/L7:BOTTOM=L7 |
| PE_CLK100M_DR2_2_N | PE_CLK100M_DR2_2-DIFF1 | PAIR | 4 | 6.5 | 5 | 10 | 5 | 12 | 20 | 25 | 12 | 12 | 20 | 12 | 7.5 | 85 Ohms | TOP=L2:L3=L2/L4:L6=L5/L7:BOTTOM=L7 |
| PE_CLK100M_DR2_2_N | PE_CLK100M_DR2_2-DIFF1 | PAIR | 5 | 6.5 | 5 | 10 | 5 | 12 | 20 | 25 | 12 | 12 | 20 | 12 | 7.5 | 85 Ohms | TOP=L2:L3=L2/L4:L6=L5/L7:BOTTOM=L7 |
| PE_CLK100M_DR2_2_N | PE_CLK100M_DR2_2-DIFF1 | PAIR | 6 | 6.5 | 5 | 10 | 5 | 12 | 20 | 25 | 12 | 12 | 20 | 12 | 7.5 | 85 Ohms | TOP=L2:L3=L2/L4:L6=L5/L7:BOTTOM=L7 |
| PE_CLK100M_DR2_2_N | PE_CLK100M_DR2_2-DIFF1 | PAIR | 7 | 6.5 | 5 | 10 | 5 | 12 | 20 | 25 | 12 | 12 | 20 | 12 | 7.5 | 85 Ohms | TOP=L2:L3=L2/L4:L6=L5/L7:BOTTOM=L7 |
| PE_CLK100M_DR2_2_N | PE_CLK100M_DR2_2-DIFF1 | PAIR | 8 | 6.88 | 5 | 10 | 5 | 12 | 20 | 36 | 12 | 12 | 20 | 12 | 5.13 | 85 Ohms | TOP=L2:L3=L2/L4:L6=L5/L7:BOTTOM=L7 |
| PE_CLK100M_DR2_2_P | PE_CLK100M_DR2_2-DIFF1 | PAIR | 1 | 6.88 | 5 | 10 | 5 | 12 | 20 | 36 | 12 | 12 | 20 | 12 | 5.13 | 85 Ohms | TOP=L2:L3=L2/L4:L6=L5/L7:BOTTOM=L7 |
| PE_CLK100M_DR2_2_P | PE_CLK100M_DR2_2-DIFF1 | PAIR | 2 | 6.5 | 5 | 10 | 5 | 12 | 20 | 25 | 12 | 12 | 20 | 12 | 7.5 | 85 Ohms | TOP=L2:L3=L2/L4:L6=L5/L7:BOTTOM=L7 |
| PE_CLK100M_DR2_2_P | PE_CLK100M_DR2_2-DIFF1 | PAIR | 3 | 6.5 | 5 | 10 | 5 | 12 | 20 | 25 | 12 | 12 | 20 | 12 | 7.5 | 85 Ohms | TOP=L2:L3=L2/L4:L6=L5/L7:BOTTOM=L7 |
| PE_CLK100M_DR2_2_P | PE_CLK100M_DR2_2-DIFF1 | PAIR | 4 | 6.5 | 5 | 10 | 5 | 12 | 20 | 25 | 12 | 12 | 20 | 12 | 7.5 | 85 Ohms | TOP=L2:L3=L2/L4:L6=L5/L7:BOTTOM=L7 |
| PE_CLK100M_DR2_2_P | PE_CLK100M_DR2_2-DIFF1 | PAIR | 5 | 6.5 | 5 | 10 | 5 | 12 | 20 | 25 | 12 | 12 | 20 | 12 | 7.5 | 85 Ohms | TOP=L2:L3=L2/L4:L6=L5/L7:BOTTOM=L7 |
| PE_CLK100M_DR2_2_P | PE_CLK100M_DR2_2-DIFF1 | PAIR | 6 | 6.5 | 5 | 10 | 5 | 12 | 20 | 25 | 12 | 12 | 20 | 12 | 7.5 | 85 Ohms | TOP=L2:L3=L2/L4:L6=L5/L7:BOTTOM=L7 |
| PE_CLK100M_DR2_2_P | PE_CLK100M_DR2_2-DIFF1 | PAIR | 7 | 6.5 | 5 | 10 | 5 | 12 | 20 | 25 | 12 | 12 | 20 | 12 | 7.5 | 85 Ohms | TOP=L2:L3=L2/L4:L6=L5/L7:BOTTOM=L7 |
| PE_CLK100M_DR2_2_P | PE_CLK100M_DR2_2-DIFF1 | PAIR | 8 | 6.88 | 5 | 10 | 5 | 12 | 20 | 36 | 12 | 12 | 20 | 12 | 5.13 | 85 Ohms | TOP=L2:L3=L2/L4:L6=L5/L7:BOTTOM=L7 |
| PE_CLK100M_DR3_1_N | PE_CLK100M_DR3_1-DIFF1 | PAIR | 1 | 6.88 | 5 | 10 | 5 | 12 | 20 | 36 | 12 | 12 | 20 | 12 | 5.13 | 85 Ohms | TOP=L2:L3=L2/L4:L6=L5/L7:BOTTOM=L7 |
| PE_CLK100M_DR3_1_N | PE_CLK100M_DR3_1-DIFF1 | PAIR | 2 | 6.5 | 5 | 10 | 5 | 12 | 20 | 25 | 12 | 12 | 20 | 12 | 7.5 | 85 Ohms | TOP=L2:L3=L2/L4:L6=L5/L7:BOTTOM=L7 |
| PE_CLK100M_DR3_1_N | PE_CLK100M_DR3_1-DIFF1 | PAIR | 3 | 6.5 | 5 | 10 | 5 | 12 | 20 | 25 | 12 | 12 | 20 | 12 | 7.5 | 85 Ohms | TOP=L2:L3=L2/L4:L6=L5/L7:BOTTOM=L7 |
| PE_CLK100M_DR3_1_N | PE_CLK100M_DR3_1-DIFF1 | PAIR | 4 | 6.5 | 5 | 10 | 5 | 12 | 20 | 25 | 12 | 12 | 20 | 12 | 7.5 | 85 Ohms | TOP=L2:L3=L2/L4:L6=L5/L7:BOTTOM=L7 |
| PE_CLK100M_DR3_1_N | PE_CLK100M_DR3_1-DIFF1 | PAIR | 5 | 6.5 | 5 | 10 | 5 | 12 | 20 | 25 | 12 | 12 | 20 | 12 | 7.5 | 85 Ohms | TOP=L2:L3=L2/L4:L6=L5/L7:BOTTOM=L7 |
| PE_CLK100M_DR3_1_N | PE_CLK100M_DR3_1-DIFF1 | PAIR | 6 | 6.5 | 5 | 10 | 5 | 12 | 20 | 25 | 12 | 12 | 20 | 12 | 7.5 | 85 Ohms | TOP=L2:L3=L2/L4:L6=L5/L7:BOTTOM=L7 |
| PE_CLK100M_DR3_1_N | PE_CLK100M_DR3_1-DIFF1 | PAIR | 7 | 6.5 | 5 | 10 | 5 | 12 | 20 | 25 | 12 | 12 | 20 | 12 | 7.5 | 85 Ohms | TOP=L2:L3=L2/L4:L6=L5/L7:BOTTOM=L7 |
| PE_CLK100M_DR3_1_N | PE_CLK100M_DR3_1-DIFF1 | PAIR | 8 | 6.88 | 5 | 10 | 5 | 12 | 20 | 36 | 12 | 12 | 20 | 12 | 5.13 | 85 Ohms | TOP=L2:L3=L2/L4:L6=L5/L7:BOTTOM=L7 |
| PE_CLK100M_DR3_1_P | PE_CLK100M_DR3_1-DIFF1 | PAIR | 1 | 6.88 | 5 | 10 | 5 | 12 | 20 | 36 | 12 | 12 | 20 | 12 | 5.13 | 85 Ohms | TOP=L2:L3=L2/L4:L6=L5/L7:BOTTOM=L7 |
| PE_CLK100M_DR3_1_P | PE_CLK100M_DR3_1-DIFF1 | PAIR | 2 | 6.5 | 5 | 10 | 5 | 12 | 20 | 25 | 12 | 12 | 20 | 12 | 7.5 | 85 Ohms | TOP=L2:L3=L2/L4:L6=L5/L7:BOTTOM=L7 |
| PE_CLK100M_DR3_1_P | PE_CLK100M_DR3_1-DIFF1 | PAIR | 3 | 6.5 | 5 | 10 | 5 | 12 | 20 | 25 | 12 | 12 | 20 | 12 | 7.5 | 85 Ohms | TOP=L2:L3=L2/L4:L6=L5/L7:BOTTOM=L7 |
| PE_CLK100M_DR3_1_P | PE_CLK100M_DR3_1-DIFF1 | PAIR | 4 | 6.5 | 5 | 10 | 5 | 12 | 20 | 25 | 12 | 12 | 20 | 12 | 7.5 | 85 Ohms | TOP=L2:L3=L2/L4:L6=L5/L7:BOTTOM=L7 |
| PE_CLK100M_DR3_1_P | PE_CLK100M_DR3_1-DIFF1 | PAIR | 5 | 6.5 | 5 | 10 | 5 | 12 | 20 | 25 | 12 | 12 | 20 | 12 | 7.5 | 85 Ohms | TOP=L2:L3=L2/L4:L6=L5/L7:BOTTOM=L7 |
| PE_CLK100M_DR3_1_P | PE_CLK100M_DR3_1-DIFF1 | PAIR | 6 | 6.5 | 5 | 10 | 5 | 12 | 20 | 25 | 12 | 12 | 20 | 12 | 7.5 | 85 Ohms | TOP=L2:L3=L2/L4:L6=L5/L7:BOTTOM=L7 |
| PE_CLK100M_DR3_1_P | PE_CLK100M_DR3_1-DIFF1 | PAIR | 7 | 6.5 | 5 | 10 | 5 | 12 | 20 | 25 | 12 | 12 | 20 | 12 | 7.5 | 85 Ohms | TOP=L2:L3=L2/L4:L6=L5/L7:BOTTOM=L7 |
| PE_CLK100M_DR3_1_P | PE_CLK100M_DR3_1-DIFF1 | PAIR | 8 | 6.88 | 5 | 10 | 5 | 12 | 20 | 36 | 12 | 12 | 20 | 12 | 5.13 | 85 Ohms | TOP=L2:L3=L2/L4:L6=L5/L7:BOTTOM=L7 |
| PE_CLK100M_DR3_2_N | PE_CLK100M_DR3_2-DIFF1 | PAIR | 1 | 6.88 | 5 | 10 | 5 | 12 | 20 | 36 | 12 | 12 | 20 | 12 | 5.13 | 85 Ohms | TOP=L2:L3=L2/L4:L6=L5/L7:BOTTOM=L7 |
| PE_CLK100M_DR3_2_N | PE_CLK100M_DR3_2-DIFF1 | PAIR | 2 | 6.5 | 5 | 10 | 5 | 12 | 20 | 25 | 12 | 12 | 20 | 12 | 7.5 | 85 Ohms | TOP=L2:L3=L2/L4:L6=L5/L7:BOTTOM=L7 |
| PE_CLK100M_DR3_2_N | PE_CLK100M_DR3_2-DIFF1 | PAIR | 3 | 6.5 | 5 | 10 | 5 | 12 | 20 | 25 | 12 | 12 | 20 | 12 | 7.5 | 85 Ohms | TOP=L2:L3=L2/L4:L6=L5/L7:BOTTOM=L7 |
| PE_CLK100M_DR3_2_N | PE_CLK100M_DR3_2-DIFF1 | PAIR | 4 | 6.5 | 5 | 10 | 5 | 12 | 20 | 25 | 12 | 12 | 20 | 12 | 7.5 | 85 Ohms | TOP=L2:L3=L2/L4:L6=L5/L7:BOTTOM=L7 |
| PE_CLK100M_DR3_2_N | PE_CLK100M_DR3_2-DIFF1 | PAIR | 5 | 6.5 | 5 | 10 | 5 | 12 | 20 | 25 | 12 | 12 | 20 | 12 | 7.5 | 85 Ohms | TOP=L2:L3=L2/L4:L6=L5/L7:BOTTOM=L7 |
| PE_CLK100M_DR3_2_N | PE_CLK100M_DR3_2-DIFF1 | PAIR | 6 | 6.5 | 5 | 10 | 5 | 12 | 20 | 25 | 12 | 12 | 20 | 12 | 7.5 | 85 Ohms | TOP=L2:L3=L2/L4:L6=L5/L7:BOTTOM=L7 |
| PE_CLK100M_DR3_2_N | PE_CLK100M_DR3_2-DIFF1 | PAIR | 7 | 6.5 | 5 | 10 | 5 | 12 | 20 | 25 | 12 | 12 | 20 | 12 | 7.5 | 85 Ohms | TOP=L2:L3=L2/L4:L6=L5/L7:BOTTOM=L7 |
| PE_CLK100M_DR3_2_N | PE_CLK100M_DR3_2-DIFF1 | PAIR | 8 | 6.88 | 5 | 10 | 5 | 12 | 20 | 36 | 12 | 12 | 20 | 12 | 5.13 | 85 Ohms | TOP=L2:L3=L2/L4:L6=L5/L7:BOTTOM=L7 |
| PE_CLK100M_DR3_2_P | PE_CLK100M_DR3_2-DIFF1 | PAIR | 1 | 6.88 | 5 | 10 | 5 | 12 | 20 | 36 | 12 | 12 | 20 | 12 | 5.13 | 85 Ohms | TOP=L2:L3=L2/L4:L6=L5/L7:BOTTOM=L7 |
| PE_CLK100M_DR3_2_P | PE_CLK100M_DR3_2-DIFF1 | PAIR | 2 | 6.5 | 5 | 10 | 5 | 12 | 20 | 25 | 12 | 12 | 20 | 12 | 7.5 | 85 Ohms | TOP=L2:L3=L2/L4:L6=L5/L7:BOTTOM=L7 |
| PE_CLK100M_DR3_2_P | PE_CLK100M_DR3_2-DIFF1 | PAIR | 3 | 6.5 | 5 | 10 | 5 | 12 | 20 | 25 | 12 | 12 | 20 | 12 | 7.5 | 85 Ohms | TOP=L2:L3=L2/L4:L6=L5/L7:BOTTOM=L7 |
| PE_CLK100M_DR3_2_P | PE_CLK100M_DR3_2-DIFF1 | PAIR | 4 | 6.5 | 5 | 10 | 5 | 12 | 20 | 25 | 12 | 12 | 20 | 12 | 7.5 | 85 Ohms | TOP=L2:L3=L2/L4:L6=L5/L7:BOTTOM=L7 |
| PE_CLK100M_DR3_2_P | PE_CLK100M_DR3_2-DIFF1 | PAIR | 5 | 6.5 | 5 | 10 | 5 | 12 | 20 | 25 | 12 | 12 | 20 | 12 | 7.5 | 85 Ohms | TOP=L2:L3=L2/L4:L6=L5/L7:BOTTOM=L7 |
| PE_CLK100M_DR3_2_P | PE_CLK100M_DR3_2-DIFF1 | PAIR | 6 | 6.5 | 5 | 10 | 5 | 12 | 20 | 25 | 12 | 12 | 20 | 12 | 7.5 | 85 Ohms | TOP=L2:L3=L2/L4:L6=L5/L7:BOTTOM=L7 |
| PE_CLK100M_DR3_2_P | PE_CLK100M_DR3_2-DIFF1 | PAIR | 7 | 6.5 | 5 | 10 | 5 | 12 | 20 | 25 | 12 | 12 | 20 | 12 | 7.5 | 85 Ohms | TOP=L2:L3=L2/L4:L6=L5/L7:BOTTOM=L7 |
| PE_CLK100M_DR3_2_P | PE_CLK100M_DR3_2-DIFF1 | PAIR | 8 | 6.88 | 5 | 10 | 5 | 12 | 20 | 36 | 12 | 12 | 20 | 12 | 5.13 | 85 Ohms | TOP=L2:L3=L2/L4:L6=L5/L7:BOTTOM=L7 |
| PE_CLK100M_DR4_1_N | PE_CLK100M_DR4_1-DIFF1 | PAIR | 1 | 6.88 | 5 | 10 | 5 | 12 | 20 | 36 | 12 | 12 | 20 | 12 | 5.13 | 85 Ohms | TOP=L2:L3=L2/L4:L6=L5/L7:BOTTOM=L7 |
| PE_CLK100M_DR4_1_N | PE_CLK100M_DR4_1-DIFF1 | PAIR | 2 | 6.5 | 5 | 10 | 5 | 12 | 20 | 25 | 12 | 12 | 20 | 12 | 7.5 | 85 Ohms | TOP=L2:L3=L2/L4:L6=L5/L7:BOTTOM=L7 |
| PE_CLK100M_DR4_1_N | PE_CLK100M_DR4_1-DIFF1 | PAIR | 3 | 6.5 | 5 | 10 | 5 | 12 | 20 | 25 | 12 | 12 | 20 | 12 | 7.5 | 85 Ohms | TOP=L2:L3=L2/L4:L6=L5/L7:BOTTOM=L7 |
| PE_CLK100M_DR4_1_N | PE_CLK100M_DR4_1-DIFF1 | PAIR | 4 | 6.5 | 5 | 10 | 5 | 12 | 20 | 25 | 12 | 12 | 20 | 12 | 7.5 | 85 Ohms | TOP=L2:L3=L2/L4:L6=L5/L7:BOTTOM=L7 |
| PE_CLK100M_DR4_1_N | PE_CLK100M_DR4_1-DIFF1 | PAIR | 5 | 6.5 | 5 | 10 | 5 | 12 | 20 | 25 | 12 | 12 | 20 | 12 | 7.5 | 85 Ohms | TOP=L2:L3=L2/L4:L6=L5/L7:BOTTOM=L7 |
| PE_CLK100M_DR4_1_N | PE_CLK100M_DR4_1-DIFF1 | PAIR | 6 | 6.5 | 5 | 10 | 5 | 12 | 20 | 25 | 12 | 12 | 20 | 12 | 7.5 | 85 Ohms | TOP=L2:L3=L2/L4:L6=L5/L7:BOTTOM=L7 |
| PE_CLK100M_DR4_1_N | PE_CLK100M_DR4_1-DIFF1 | PAIR | 7 | 6.5 | 5 | 10 | 5 | 12 | 20 | 25 | 12 | 12 | 20 | 12 | 7.5 | 85 Ohms | TOP=L2:L3=L2/L4:L6=L5/L7:BOTTOM=L7 |
| PE_CLK100M_DR4_1_N | PE_CLK100M_DR4_1-DIFF1 | PAIR | 8 | 6.88 | 5 | 10 | 5 | 12 | 20 | 36 | 12 | 12 | 20 | 12 | 5.13 | 85 Ohms | TOP=L2:L3=L2/L4:L6=L5/L7:BOTTOM=L7 |
| PE_CLK100M_DR4_1_P | PE_CLK100M_DR4_1-DIFF1 | PAIR | 1 | 6.88 | 5 | 10 | 5 | 12 | 20 | 36 | 12 | 12 | 20 | 12 | 5.13 | 85 Ohms | TOP=L2:L3=L2/L4:L6=L5/L7:BOTTOM=L7 |
| PE_CLK100M_DR4_1_P | PE_CLK100M_DR4_1-DIFF1 | PAIR | 2 | 6.5 | 5 | 10 | 5 | 12 | 20 | 25 | 12 | 12 | 20 | 12 | 7.5 | 85 Ohms | TOP=L2:L3=L2/L4:L6=L5/L7:BOTTOM=L7 |
| PE_CLK100M_DR4_1_P | PE_CLK100M_DR4_1-DIFF1 | PAIR | 3 | 6.5 | 5 | 10 | 5 | 12 | 20 | 25 | 12 | 12 | 20 | 12 | 7.5 | 85 Ohms | TOP=L2:L3=L2/L4:L6=L5/L7:BOTTOM=L7 |
| PE_CLK100M_DR4_1_P | PE_CLK100M_DR4_1-DIFF1 | PAIR | 4 | 6.5 | 5 | 10 | 5 | 12 | 20 | 25 | 12 | 12 | 20 | 12 | 7.5 | 85 Ohms | TOP=L2:L3=L2/L4:L6=L5/L7:BOTTOM=L7 |
| PE_CLK100M_DR4_1_P | PE_CLK100M_DR4_1-DIFF1 | PAIR | 5 | 6.5 | 5 | 10 | 5 | 12 | 20 | 25 | 12 | 12 | 20 | 12 | 7.5 | 85 Ohms | TOP=L2:L3=L2/L4:L6=L5/L7:BOTTOM=L7 |
| PE_CLK100M_DR4_1_P | PE_CLK100M_DR4_1-DIFF1 | PAIR | 6 | 6.5 | 5 | 10 | 5 | 12 | 20 | 25 | 12 | 12 | 20 | 12 | 7.5 | 85 Ohms | TOP=L2:L3=L2/L4:L6=L5/L7:BOTTOM=L7 |
| PE_CLK100M_DR4_1_P | PE_CLK100M_DR4_1-DIFF1 | PAIR | 7 | 6.5 | 5 | 10 | 5 | 12 | 20 | 25 | 12 | 12 | 20 | 12 | 7.5 | 85 Ohms | TOP=L2:L3=L2/L4:L6=L5/L7:BOTTOM=L7 |
| PE_CLK100M_DR4_1_P | PE_CLK100M_DR4_1-DIFF1 | PAIR | 8 | 6.88 | 5 | 10 | 5 | 12 | 20 | 36 | 12 | 12 | 20 | 12 | 5.13 | 85 Ohms | TOP=L2:L3=L2/L4:L6=L5/L7:BOTTOM=L7 |
| PE_CLK100M_DR4_2_N | PE_CLK100M_DR4_2-DIFF1 | PAIR | 1 | 6.88 | 5 | 10 | 5 | 12 | 20 | 36 | 12 | 12 | 20 | 12 | 5.13 | 85 Ohms | TOP=L2:L3=L2/L4:L6=L5/L7:BOTTOM=L7 |
| PE_CLK100M_DR4_2_N | PE_CLK100M_DR4_2-DIFF1 | PAIR | 2 | 6.5 | 5 | 10 | 5 | 12 | 20 | 25 | 12 | 12 | 20 | 12 | 7.5 | 85 Ohms | TOP=L2:L3=L2/L4:L6=L5/L7:BOTTOM=L7 |
| PE_CLK100M_DR4_2_N | PE_CLK100M_DR4_2-DIFF1 | PAIR | 3 | 6.5 | 5 | 10 | 5 | 12 | 20 | 25 | 12 | 12 | 20 | 12 | 7.5 | 85 Ohms | TOP=L2:L3=L2/L4:L6=L5/L7:BOTTOM=L7 |
| PE_CLK100M_DR4_2_N | PE_CLK100M_DR4_2-DIFF1 | PAIR | 4 | 6.5 | 5 | 10 | 5 | 12 | 20 | 25 | 12 | 12 | 20 | 12 | 7.5 | 85 Ohms | TOP=L2:L3=L2/L4:L6=L5/L7:BOTTOM=L7 |
| PE_CLK100M_DR4_2_N | PE_CLK100M_DR4_2-DIFF1 | PAIR | 5 | 6.5 | 5 | 10 | 5 | 12 | 20 | 25 | 12 | 12 | 20 | 12 | 7.5 | 85 Ohms | TOP=L2:L3=L2/L4:L6=L5/L7:BOTTOM=L7 |
| PE_CLK100M_DR4_2_N | PE_CLK100M_DR4_2-DIFF1 | PAIR | 6 | 6.5 | 5 | 10 | 5 | 12 | 20 | 25 | 12 | 12 | 20 | 12 | 7.5 | 85 Ohms | TOP=L2:L3=L2/L4:L6=L5/L7:BOTTOM=L7 |
| PE_CLK100M_DR4_2_N | PE_CLK100M_DR4_2-DIFF1 | PAIR | 7 | 6.5 | 5 | 10 | 5 | 12 | 20 | 25 | 12 | 12 | 20 | 12 | 7.5 | 85 Ohms | TOP=L2:L3=L2/L4:L6=L5/L7:BOTTOM=L7 |
| PE_CLK100M_DR4_2_N | PE_CLK100M_DR4_2-DIFF1 | PAIR | 8 | 6.88 | 5 | 10 | 5 | 12 | 20 | 36 | 12 | 12 | 20 | 12 | 5.13 | 85 Ohms | TOP=L2:L3=L2/L4:L6=L5/L7:BOTTOM=L7 |
| PE_CLK100M_DR4_2_P | PE_CLK100M_DR4_2-DIFF1 | PAIR | 1 | 6.88 | 5 | 10 | 5 | 12 | 20 | 36 | 12 | 12 | 20 | 12 | 5.13 | 85 Ohms | TOP=L2:L3=L2/L4:L6=L5/L7:BOTTOM=L7 |
| PE_CLK100M_DR4_2_P | PE_CLK100M_DR4_2-DIFF1 | PAIR | 2 | 6.5 | 5 | 10 | 5 | 12 | 20 | 25 | 12 | 12 | 20 | 12 | 7.5 | 85 Ohms | TOP=L2:L3=L2/L4:L6=L5/L7:BOTTOM=L7 |
| PE_CLK100M_DR4_2_P | PE_CLK100M_DR4_2-DIFF1 | PAIR | 3 | 6.5 | 5 | 10 | 5 | 12 | 20 | 25 | 12 | 12 | 20 | 12 | 7.5 | 85 Ohms | TOP=L2:L3=L2/L4:L6=L5/L7:BOTTOM=L7 |
| PE_CLK100M_DR4_2_P | PE_CLK100M_DR4_2-DIFF1 | PAIR | 4 | 6.5 | 5 | 10 | 5 | 12 | 20 | 25 | 12 | 12 | 20 | 12 | 7.5 | 85 Ohms | TOP=L2:L3=L2/L4:L6=L5/L7:BOTTOM=L7 |
| PE_CLK100M_DR4_2_P | PE_CLK100M_DR4_2-DIFF1 | PAIR | 5 | 6.5 | 5 | 10 | 5 | 12 | 20 | 25 | 12 | 12 | 20 | 12 | 7.5 | 85 Ohms | TOP=L2:L3=L2/L4:L6=L5/L7:BOTTOM=L7 |
| PE_CLK100M_DR4_2_P | PE_CLK100M_DR4_2-DIFF1 | PAIR | 6 | 6.5 | 5 | 10 | 5 | 12 | 20 | 25 | 12 | 12 | 20 | 12 | 7.5 | 85 Ohms | TOP=L2:L3=L2/L4:L6=L5/L7:BOTTOM=L7 |
| PE_CLK100M_DR4_2_P | PE_CLK100M_DR4_2-DIFF1 | PAIR | 7 | 6.5 | 5 | 10 | 5 | 12 | 20 | 25 | 12 | 12 | 20 | 12 | 7.5 | 85 Ohms | TOP=L2:L3=L2/L4:L6=L5/L7:BOTTOM=L7 |
| PE_CLK100M_DR4_2_P | PE_CLK100M_DR4_2-DIFF1 | PAIR | 8 | 6.88 | 5 | 10 | 5 | 12 | 20 | 36 | 12 | 12 | 20 | 12 | 5.13 | 85 Ohms | TOP=L2:L3=L2/L4:L6=L5/L7:BOTTOM=L7 |
| PE_CLK100M_DR5_1_N | PE_CLK100M_DR5_1-DIFF1 | PAIR | 1 | 6.88 | 5 | 10 | 5 | 12 | 20 | 36 | 12 | 12 | 20 | 12 | 5.13 | 85 Ohms | TOP=L2:L3=L2/L4:L6=L5/L7:BOTTOM=L7 |
| PE_CLK100M_DR5_1_N | PE_CLK100M_DR5_1-DIFF1 | PAIR | 2 | 6.5 | 5 | 10 | 5 | 12 | 20 | 25 | 12 | 12 | 20 | 12 | 7.5 | 85 Ohms | TOP=L2:L3=L2/L4:L6=L5/L7:BOTTOM=L7 |
| PE_CLK100M_DR5_1_N | PE_CLK100M_DR5_1-DIFF1 | PAIR | 3 | 6.5 | 5 | 10 | 5 | 12 | 20 | 25 | 12 | 12 | 20 | 12 | 7.5 | 85 Ohms | TOP=L2:L3=L2/L4:L6=L5/L7:BOTTOM=L7 |
| PE_CLK100M_DR5_1_N | PE_CLK100M_DR5_1-DIFF1 | PAIR | 4 | 6.5 | 5 | 10 | 5 | 12 | 20 | 25 | 12 | 12 | 20 | 12 | 7.5 | 85 Ohms | TOP=L2:L3=L2/L4:L6=L5/L7:BOTTOM=L7 |
| PE_CLK100M_DR5_1_N | PE_CLK100M_DR5_1-DIFF1 | PAIR | 5 | 6.5 | 5 | 10 | 5 | 12 | 20 | 25 | 12 | 12 | 20 | 12 | 7.5 | 85 Ohms | TOP=L2:L3=L2/L4:L6=L5/L7:BOTTOM=L7 |
| PE_CLK100M_DR5_1_N | PE_CLK100M_DR5_1-DIFF1 | PAIR | 6 | 6.5 | 5 | 10 | 5 | 12 | 20 | 25 | 12 | 12 | 20 | 12 | 7.5 | 85 Ohms | TOP=L2:L3=L2/L4:L6=L5/L7:BOTTOM=L7 |
| PE_CLK100M_DR5_1_N | PE_CLK100M_DR5_1-DIFF1 | PAIR | 7 | 6.5 | 5 | 10 | 5 | 12 | 20 | 25 | 12 | 12 | 20 | 12 | 7.5 | 85 Ohms | TOP=L2:L3=L2/L4:L6=L5/L7:BOTTOM=L7 |
| PE_CLK100M_DR5_1_N | PE_CLK100M_DR5_1-DIFF1 | PAIR | 8 | 6.88 | 5 | 10 | 5 | 12 | 20 | 36 | 12 | 12 | 20 | 12 | 5.13 | 85 Ohms | TOP=L2:L3=L2/L4:L6=L5/L7:BOTTOM=L7 |
| PE_CLK100M_DR5_1_P | PE_CLK100M_DR5_1-DIFF1 | PAIR | 1 | 6.88 | 5 | 10 | 5 | 12 | 20 | 36 | 12 | 12 | 20 | 12 | 5.13 | 85 Ohms | TOP=L2:L3=L2/L4:L6=L5/L7:BOTTOM=L7 |
| PE_CLK100M_DR5_1_P | PE_CLK100M_DR5_1-DIFF1 | PAIR | 2 | 6.5 | 5 | 10 | 5 | 12 | 20 | 25 | 12 | 12 | 20 | 12 | 7.5 | 85 Ohms | TOP=L2:L3=L2/L4:L6=L5/L7:BOTTOM=L7 |
| PE_CLK100M_DR5_1_P | PE_CLK100M_DR5_1-DIFF1 | PAIR | 3 | 6.5 | 5 | 10 | 5 | 12 | 20 | 25 | 12 | 12 | 20 | 12 | 7.5 | 85 Ohms | TOP=L2:L3=L2/L4:L6=L5/L7:BOTTOM=L7 |
| PE_CLK100M_DR5_1_P | PE_CLK100M_DR5_1-DIFF1 | PAIR | 4 | 6.5 | 5 | 10 | 5 | 12 | 20 | 25 | 12 | 12 | 20 | 12 | 7.5 | 85 Ohms | TOP=L2:L3=L2/L4:L6=L5/L7:BOTTOM=L7 |
| PE_CLK100M_DR5_1_P | PE_CLK100M_DR5_1-DIFF1 | PAIR | 5 | 6.5 | 5 | 10 | 5 | 12 | 20 | 25 | 12 | 12 | 20 | 12 | 7.5 | 85 Ohms | TOP=L2:L3=L2/L4:L6=L5/L7:BOTTOM=L7 |
| PE_CLK100M_DR5_1_P | PE_CLK100M_DR5_1-DIFF1 | PAIR | 6 | 6.5 | 5 | 10 | 5 | 12 | 20 | 25 | 12 | 12 | 20 | 12 | 7.5 | 85 Ohms | TOP=L2:L3=L2/L4:L6=L5/L7:BOTTOM=L7 |
| PE_CLK100M_DR5_1_P | PE_CLK100M_DR5_1-DIFF1 | PAIR | 7 | 6.5 | 5 | 10 | 5 | 12 | 20 | 25 | 12 | 12 | 20 | 12 | 7.5 | 85 Ohms | TOP=L2:L3=L2/L4:L6=L5/L7:BOTTOM=L7 |
| PE_CLK100M_DR5_1_P | PE_CLK100M_DR5_1-DIFF1 | PAIR | 8 | 6.88 | 5 | 10 | 5 | 12 | 20 | 36 | 12 | 12 | 20 | 12 | 5.13 | 85 Ohms | TOP=L2:L3=L2/L4:L6=L5/L7:BOTTOM=L7 |
| PE_CLK100M_DR5_2_N | PE_CLK100M_DR5_2-DIFF1 | PAIR | 1 | 6.88 | 5 | 10 | 5 | 12 | 20 | 36 | 12 | 12 | 20 | 12 | 5.13 | 85 Ohms | TOP=L2:L3=L2/L4:L6=L5/L7:BOTTOM=L7 |
| PE_CLK100M_DR5_2_N | PE_CLK100M_DR5_2-DIFF1 | PAIR | 2 | 6.5 | 5 | 10 | 5 | 12 | 20 | 25 | 12 | 12 | 20 | 12 | 7.5 | 85 Ohms | TOP=L2:L3=L2/L4:L6=L5/L7:BOTTOM=L7 |
| PE_CLK100M_DR5_2_N | PE_CLK100M_DR5_2-DIFF1 | PAIR | 3 | 6.5 | 5 | 10 | 5 | 12 | 20 | 25 | 12 | 12 | 20 | 12 | 7.5 | 85 Ohms | TOP=L2:L3=L2/L4:L6=L5/L7:BOTTOM=L7 |
| PE_CLK100M_DR5_2_N | PE_CLK100M_DR5_2-DIFF1 | PAIR | 4 | 6.5 | 5 | 10 | 5 | 12 | 20 | 25 | 12 | 12 | 20 | 12 | 7.5 | 85 Ohms | TOP=L2:L3=L2/L4:L6=L5/L7:BOTTOM=L7 |
| PE_CLK100M_DR5_2_N | PE_CLK100M_DR5_2-DIFF1 | PAIR | 5 | 6.5 | 5 | 10 | 5 | 12 | 20 | 25 | 12 | 12 | 20 | 12 | 7.5 | 85 Ohms | TOP=L2:L3=L2/L4:L6=L5/L7:BOTTOM=L7 |
| PE_CLK100M_DR5_2_N | PE_CLK100M_DR5_2-DIFF1 | PAIR | 6 | 6.5 | 5 | 10 | 5 | 12 | 20 | 25 | 12 | 12 | 20 | 12 | 7.5 | 85 Ohms | TOP=L2:L3=L2/L4:L6=L5/L7:BOTTOM=L7 |
| PE_CLK100M_DR5_2_N | PE_CLK100M_DR5_2-DIFF1 | PAIR | 7 | 6.5 | 5 | 10 | 5 | 12 | 20 | 25 | 12 | 12 | 20 | 12 | 7.5 | 85 Ohms | TOP=L2:L3=L2/L4:L6=L5/L7:BOTTOM=L7 |
| PE_CLK100M_DR5_2_N | PE_CLK100M_DR5_2-DIFF1 | PAIR | 8 | 6.88 | 5 | 10 | 5 | 12 | 20 | 36 | 12 | 12 | 20 | 12 | 5.13 | 85 Ohms | TOP=L2:L3=L2/L4:L6=L5/L7:BOTTOM=L7 |
| PE_CLK100M_DR5_2_P | PE_CLK100M_DR5_2-DIFF1 | PAIR | 1 | 6.88 | 5 | 10 | 5 | 12 | 20 | 36 | 12 | 12 | 20 | 12 | 5.13 | 85 Ohms | TOP=L2:L3=L2/L4:L6=L5/L7:BOTTOM=L7 |
| PE_CLK100M_DR5_2_P | PE_CLK100M_DR5_2-DIFF1 | PAIR | 2 | 6.5 | 5 | 10 | 5 | 12 | 20 | 25 | 12 | 12 | 20 | 12 | 7.5 | 85 Ohms | TOP=L2:L3=L2/L4:L6=L5/L7:BOTTOM=L7 |
| PE_CLK100M_DR5_2_P | PE_CLK100M_DR5_2-DIFF1 | PAIR | 3 | 6.5 | 5 | 10 | 5 | 12 | 20 | 25 | 12 | 12 | 20 | 12 | 7.5 | 85 Ohms | TOP=L2:L3=L2/L4:L6=L5/L7:BOTTOM=L7 |
| PE_CLK100M_DR5_2_P | PE_CLK100M_DR5_2-DIFF1 | PAIR | 4 | 6.5 | 5 | 10 | 5 | 12 | 20 | 25 | 12 | 12 | 20 | 12 | 7.5 | 85 Ohms | TOP=L2:L3=L2/L4:L6=L5/L7:BOTTOM=L7 |
| PE_CLK100M_DR5_2_P | PE_CLK100M_DR5_2-DIFF1 | PAIR | 5 | 6.5 | 5 | 10 | 5 | 12 | 20 | 25 | 12 | 12 | 20 | 12 | 7.5 | 85 Ohms | TOP=L2:L3=L2/L4:L6=L5/L7:BOTTOM=L7 |
| PE_CLK100M_DR5_2_P | PE_CLK100M_DR5_2-DIFF1 | PAIR | 6 | 6.5 | 5 | 10 | 5 | 12 | 20 | 25 | 12 | 12 | 20 | 12 | 7.5 | 85 Ohms | TOP=L2:L3=L2/L4:L6=L5/L7:BOTTOM=L7 |
| PE_CLK100M_DR5_2_P | PE_CLK100M_DR5_2-DIFF1 | PAIR | 7 | 6.5 | 5 | 10 | 5 | 12 | 20 | 25 | 12 | 12 | 20 | 12 | 7.5 | 85 Ohms | TOP=L2:L3=L2/L4:L6=L5/L7:BOTTOM=L7 |
| PE_CLK100M_DR5_2_P | PE_CLK100M_DR5_2-DIFF1 | PAIR | 8 | 6.88 | 5 | 10 | 5 | 12 | 20 | 36 | 12 | 12 | 20 | 12 | 5.13 | 85 Ohms | TOP=L2:L3=L2/L4:L6=L5/L7:BOTTOM=L7 |
| PE_CLK100M_DR6_1_N | PE_CLK100M_DR6_1-DIFF1 | PAIR | 1 | 6.88 | 5 | 10 | 5 | 12 | 20 | 36 | 12 | 12 | 20 | 12 | 5.13 | 85 Ohms | TOP=L2:L3=L2/L4:L6=L5/L7:BOTTOM=L7 |
| PE_CLK100M_DR6_1_N | PE_CLK100M_DR6_1-DIFF1 | PAIR | 2 | 6.5 | 5 | 10 | 5 | 12 | 20 | 25 | 12 | 12 | 20 | 12 | 7.5 | 85 Ohms | TOP=L2:L3=L2/L4:L6=L5/L7:BOTTOM=L7 |
| PE_CLK100M_DR6_1_N | PE_CLK100M_DR6_1-DIFF1 | PAIR | 3 | 6.5 | 5 | 10 | 5 | 12 | 20 | 25 | 12 | 12 | 20 | 12 | 7.5 | 85 Ohms | TOP=L2:L3=L2/L4:L6=L5/L7:BOTTOM=L7 |
| PE_CLK100M_DR6_1_N | PE_CLK100M_DR6_1-DIFF1 | PAIR | 4 | 6.5 | 5 | 10 | 5 | 12 | 20 | 25 | 12 | 12 | 20 | 12 | 7.5 | 85 Ohms | TOP=L2:L3=L2/L4:L6=L5/L7:BOTTOM=L7 |
| PE_CLK100M_DR6_1_N | PE_CLK100M_DR6_1-DIFF1 | PAIR | 5 | 6.5 | 5 | 10 | 5 | 12 | 20 | 25 | 12 | 12 | 20 | 12 | 7.5 | 85 Ohms | TOP=L2:L3=L2/L4:L6=L5/L7:BOTTOM=L7 |
| PE_CLK100M_DR6_1_N | PE_CLK100M_DR6_1-DIFF1 | PAIR | 6 | 6.5 | 5 | 10 | 5 | 12 | 20 | 25 | 12 | 12 | 20 | 12 | 7.5 | 85 Ohms | TOP=L2:L3=L2/L4:L6=L5/L7:BOTTOM=L7 |
| PE_CLK100M_DR6_1_N | PE_CLK100M_DR6_1-DIFF1 | PAIR | 7 | 6.5 | 5 | 10 | 5 | 12 | 20 | 25 | 12 | 12 | 20 | 12 | 7.5 | 85 Ohms | TOP=L2:L3=L2/L4:L6=L5/L7:BOTTOM=L7 |
| PE_CLK100M_DR6_1_N | PE_CLK100M_DR6_1-DIFF1 | PAIR | 8 | 6.88 | 5 | 10 | 5 | 12 | 20 | 36 | 12 | 12 | 20 | 12 | 5.13 | 85 Ohms | TOP=L2:L3=L2/L4:L6=L5/L7:BOTTOM=L7 |
| PE_CLK100M_DR6_1_P | PE_CLK100M_DR6_1-DIFF1 | PAIR | 1 | 6.88 | 5 | 10 | 5 | 12 | 20 | 36 | 12 | 12 | 20 | 12 | 5.13 | 85 Ohms | TOP=L2:L3=L2/L4:L6=L5/L7:BOTTOM=L7 |
| PE_CLK100M_DR6_1_P | PE_CLK100M_DR6_1-DIFF1 | PAIR | 2 | 6.5 | 5 | 10 | 5 | 12 | 20 | 25 | 12 | 12 | 20 | 12 | 7.5 | 85 Ohms | TOP=L2:L3=L2/L4:L6=L5/L7:BOTTOM=L7 |
| PE_CLK100M_DR6_1_P | PE_CLK100M_DR6_1-DIFF1 | PAIR | 3 | 6.5 | 5 | 10 | 5 | 12 | 20 | 25 | 12 | 12 | 20 | 12 | 7.5 | 85 Ohms | TOP=L2:L3=L2/L4:L6=L5/L7:BOTTOM=L7 |
| PE_CLK100M_DR6_1_P | PE_CLK100M_DR6_1-DIFF1 | PAIR | 4 | 6.5 | 5 | 10 | 5 | 12 | 20 | 25 | 12 | 12 | 20 | 12 | 7.5 | 85 Ohms | TOP=L2:L3=L2/L4:L6=L5/L7:BOTTOM=L7 |
| PE_CLK100M_DR6_1_P | PE_CLK100M_DR6_1-DIFF1 | PAIR | 5 | 6.5 | 5 | 10 | 5 | 12 | 20 | 25 | 12 | 12 | 20 | 12 | 7.5 | 85 Ohms | TOP=L2:L3=L2/L4:L6=L5/L7:BOTTOM=L7 |
| PE_CLK100M_DR6_1_P | PE_CLK100M_DR6_1-DIFF1 | PAIR | 6 | 6.5 | 5 | 10 | 5 | 12 | 20 | 25 | 12 | 12 | 20 | 12 | 7.5 | 85 Ohms | TOP=L2:L3=L2/L4:L6=L5/L7:BOTTOM=L7 |
| PE_CLK100M_DR6_1_P | PE_CLK100M_DR6_1-DIFF1 | PAIR | 7 | 6.5 | 5 | 10 | 5 | 12 | 20 | 25 | 12 | 12 | 20 | 12 | 7.5 | 85 Ohms | TOP=L2:L3=L2/L4:L6=L5/L7:BOTTOM=L7 |
| PE_CLK100M_DR6_1_P | PE_CLK100M_DR6_1-DIFF1 | PAIR | 8 | 6.88 | 5 | 10 | 5 | 12 | 20 | 36 | 12 | 12 | 20 | 12 | 5.13 | 85 Ohms | TOP=L2:L3=L2/L4:L6=L5/L7:BOTTOM=L7 |
| PE_CLK100M_DR6_2_N | PE_CLK100M_DR6_2-DIFF1 | PAIR | 1 | 6.88 | 5 | 10 | 5 | 12 | 20 | 36 | 12 | 12 | 20 | 12 | 5.13 | 85 Ohms | TOP=L2:L3=L2/L4:L6=L5/L7:BOTTOM=L7 |
| PE_CLK100M_DR6_2_N | PE_CLK100M_DR6_2-DIFF1 | PAIR | 2 | 6.5 | 5 | 10 | 5 | 12 | 20 | 25 | 12 | 12 | 20 | 12 | 7.5 | 85 Ohms | TOP=L2:L3=L2/L4:L6=L5/L7:BOTTOM=L7 |
| PE_CLK100M_DR6_2_N | PE_CLK100M_DR6_2-DIFF1 | PAIR | 3 | 6.5 | 5 | 10 | 5 | 12 | 20 | 25 | 12 | 12 | 20 | 12 | 7.5 | 85 Ohms | TOP=L2:L3=L2/L4:L6=L5/L7:BOTTOM=L7 |
| PE_CLK100M_DR6_2_N | PE_CLK100M_DR6_2-DIFF1 | PAIR | 4 | 6.5 | 5 | 10 | 5 | 12 | 20 | 25 | 12 | 12 | 20 | 12 | 7.5 | 85 Ohms | TOP=L2:L3=L2/L4:L6=L5/L7:BOTTOM=L7 |
| PE_CLK100M_DR6_2_N | PE_CLK100M_DR6_2-DIFF1 | PAIR | 5 | 6.5 | 5 | 10 | 5 | 12 | 20 | 25 | 12 | 12 | 20 | 12 | 7.5 | 85 Ohms | TOP=L2:L3=L2/L4:L6=L5/L7:BOTTOM=L7 |
| PE_CLK100M_DR6_2_N | PE_CLK100M_DR6_2-DIFF1 | PAIR | 6 | 6.5 | 5 | 10 | 5 | 12 | 20 | 25 | 12 | 12 | 20 | 12 | 7.5 | 85 Ohms | TOP=L2:L3=L2/L4:L6=L5/L7:BOTTOM=L7 |
| PE_CLK100M_DR6_2_N | PE_CLK100M_DR6_2-DIFF1 | PAIR | 7 | 6.5 | 5 | 10 | 5 | 12 | 20 | 25 | 12 | 12 | 20 | 12 | 7.5 | 85 Ohms | TOP=L2:L3=L2/L4:L6=L5/L7:BOTTOM=L7 |
| PE_CLK100M_DR6_2_N | PE_CLK100M_DR6_2-DIFF1 | PAIR | 8 | 6.88 | 5 | 10 | 5 | 12 | 20 | 36 | 12 | 12 | 20 | 12 | 5.13 | 85 Ohms | TOP=L2:L3=L2/L4:L6=L5/L7:BOTTOM=L7 |
| PE_CLK100M_DR6_2_P | PE_CLK100M_DR6_2-DIFF1 | PAIR | 1 | 6.88 | 5 | 10 | 5 | 12 | 20 | 36 | 12 | 12 | 20 | 12 | 5.13 | 85 Ohms | TOP=L2:L3=L2/L4:L6=L5/L7:BOTTOM=L7 |
| PE_CLK100M_DR6_2_P | PE_CLK100M_DR6_2-DIFF1 | PAIR | 2 | 6.5 | 5 | 10 | 5 | 12 | 20 | 25 | 12 | 12 | 20 | 12 | 7.5 | 85 Ohms | TOP=L2:L3=L2/L4:L6=L5/L7:BOTTOM=L7 |
| PE_CLK100M_DR6_2_P | PE_CLK100M_DR6_2-DIFF1 | PAIR | 3 | 6.5 | 5 | 10 | 5 | 12 | 20 | 25 | 12 | 12 | 20 | 12 | 7.5 | 85 Ohms | TOP=L2:L3=L2/L4:L6=L5/L7:BOTTOM=L7 |
| PE_CLK100M_DR6_2_P | PE_CLK100M_DR6_2-DIFF1 | PAIR | 4 | 6.5 | 5 | 10 | 5 | 12 | 20 | 25 | 12 | 12 | 20 | 12 | 7.5 | 85 Ohms | TOP=L2:L3=L2/L4:L6=L5/L7:BOTTOM=L7 |
| PE_CLK100M_DR6_2_P | PE_CLK100M_DR6_2-DIFF1 | PAIR | 5 | 6.5 | 5 | 10 | 5 | 12 | 20 | 25 | 12 | 12 | 20 | 12 | 7.5 | 85 Ohms | TOP=L2:L3=L2/L4:L6=L5/L7:BOTTOM=L7 |
| PE_CLK100M_DR6_2_P | PE_CLK100M_DR6_2-DIFF1 | PAIR | 6 | 6.5 | 5 | 10 | 5 | 12 | 20 | 25 | 12 | 12 | 20 | 12 | 7.5 | 85 Ohms | TOP=L2:L3=L2/L4:L6=L5/L7:BOTTOM=L7 |
| PE_CLK100M_DR6_2_P | PE_CLK100M_DR6_2-DIFF1 | PAIR | 7 | 6.5 | 5 | 10 | 5 | 12 | 20 | 25 | 12 | 12 | 20 | 12 | 7.5 | 85 Ohms | TOP=L2:L3=L2/L4:L6=L5/L7:BOTTOM=L7 |
| PE_CLK100M_DR6_2_P | PE_CLK100M_DR6_2-DIFF1 | PAIR | 8 | 6.88 | 5 | 10 | 5 | 12 | 20 | 36 | 12 | 12 | 20 | 12 | 5.13 | 85 Ohms | TOP=L2:L3=L2/L4:L6=L5/L7:BOTTOM=L7 |
| PE_CLK100M_DR7_1_N | PE_CLK100M_DR7_1-DIFF1 | PAIR | 1 | 6.88 | 5 | 10 | 5 | 12 | 20 | 36 | 12 | 12 | 20 | 12 | 5.13 | 85 Ohms | TOP=L2:L3=L2/L4:L6=L5/L7:BOTTOM=L7 |
| PE_CLK100M_DR7_1_N | PE_CLK100M_DR7_1-DIFF1 | PAIR | 2 | 6.5 | 5 | 10 | 5 | 12 | 20 | 25 | 12 | 12 | 20 | 12 | 7.5 | 85 Ohms | TOP=L2:L3=L2/L4:L6=L5/L7:BOTTOM=L7 |
| PE_CLK100M_DR7_1_N | PE_CLK100M_DR7_1-DIFF1 | PAIR | 3 | 6.5 | 5 | 10 | 5 | 12 | 20 | 25 | 12 | 12 | 20 | 12 | 7.5 | 85 Ohms | TOP=L2:L3=L2/L4:L6=L5/L7:BOTTOM=L7 |
| PE_CLK100M_DR7_1_N | PE_CLK100M_DR7_1-DIFF1 | PAIR | 4 | 6.5 | 5 | 10 | 5 | 12 | 20 | 25 | 12 | 12 | 20 | 12 | 7.5 | 85 Ohms | TOP=L2:L3=L2/L4:L6=L5/L7:BOTTOM=L7 |
| PE_CLK100M_DR7_1_N | PE_CLK100M_DR7_1-DIFF1 | PAIR | 5 | 6.5 | 5 | 10 | 5 | 12 | 20 | 25 | 12 | 12 | 20 | 12 | 7.5 | 85 Ohms | TOP=L2:L3=L2/L4:L6=L5/L7:BOTTOM=L7 |
| PE_CLK100M_DR7_1_N | PE_CLK100M_DR7_1-DIFF1 | PAIR | 6 | 6.5 | 5 | 10 | 5 | 12 | 20 | 25 | 12 | 12 | 20 | 12 | 7.5 | 85 Ohms | TOP=L2:L3=L2/L4:L6=L5/L7:BOTTOM=L7 |
| PE_CLK100M_DR7_1_N | PE_CLK100M_DR7_1-DIFF1 | PAIR | 7 | 6.5 | 5 | 10 | 5 | 12 | 20 | 25 | 12 | 12 | 20 | 12 | 7.5 | 85 Ohms | TOP=L2:L3=L2/L4:L6=L5/L7:BOTTOM=L7 |
| PE_CLK100M_DR7_1_N | PE_CLK100M_DR7_1-DIFF1 | PAIR | 8 | 6.88 | 5 | 10 | 5 | 12 | 20 | 36 | 12 | 12 | 20 | 12 | 5.13 | 85 Ohms | TOP=L2:L3=L2/L4:L6=L5/L7:BOTTOM=L7 |
| PE_CLK100M_DR7_1_P | PE_CLK100M_DR7_1-DIFF1 | PAIR | 1 | 6.88 | 5 | 10 | 5 | 12 | 20 | 36 | 12 | 12 | 20 | 12 | 5.13 | 85 Ohms | TOP=L2:L3=L2/L4:L6=L5/L7:BOTTOM=L7 |
| PE_CLK100M_DR7_1_P | PE_CLK100M_DR7_1-DIFF1 | PAIR | 2 | 6.5 | 5 | 10 | 5 | 12 | 20 | 25 | 12 | 12 | 20 | 12 | 7.5 | 85 Ohms | TOP=L2:L3=L2/L4:L6=L5/L7:BOTTOM=L7 |
| PE_CLK100M_DR7_1_P | PE_CLK100M_DR7_1-DIFF1 | PAIR | 3 | 6.5 | 5 | 10 | 5 | 12 | 20 | 25 | 12 | 12 | 20 | 12 | 7.5 | 85 Ohms | TOP=L2:L3=L2/L4:L6=L5/L7:BOTTOM=L7 |
| PE_CLK100M_DR7_1_P | PE_CLK100M_DR7_1-DIFF1 | PAIR | 4 | 6.5 | 5 | 10 | 5 | 12 | 20 | 25 | 12 | 12 | 20 | 12 | 7.5 | 85 Ohms | TOP=L2:L3=L2/L4:L6=L5/L7:BOTTOM=L7 |
| PE_CLK100M_DR7_1_P | PE_CLK100M_DR7_1-DIFF1 | PAIR | 5 | 6.5 | 5 | 10 | 5 | 12 | 20 | 25 | 12 | 12 | 20 | 12 | 7.5 | 85 Ohms | TOP=L2:L3=L2/L4:L6=L5/L7:BOTTOM=L7 |
| PE_CLK100M_DR7_1_P | PE_CLK100M_DR7_1-DIFF1 | PAIR | 6 | 6.5 | 5 | 10 | 5 | 12 | 20 | 25 | 12 | 12 | 20 | 12 | 7.5 | 85 Ohms | TOP=L2:L3=L2/L4:L6=L5/L7:BOTTOM=L7 |
| PE_CLK100M_DR7_1_P | PE_CLK100M_DR7_1-DIFF1 | PAIR | 7 | 6.5 | 5 | 10 | 5 | 12 | 20 | 25 | 12 | 12 | 20 | 12 | 7.5 | 85 Ohms | TOP=L2:L3=L2/L4:L6=L5/L7:BOTTOM=L7 |
| PE_CLK100M_DR7_1_P | PE_CLK100M_DR7_1-DIFF1 | PAIR | 8 | 6.88 | 5 | 10 | 5 | 12 | 20 | 36 | 12 | 12 | 20 | 12 | 5.13 | 85 Ohms | TOP=L2:L3=L2/L4:L6=L5/L7:BOTTOM=L7 |
| PE_CLK100M_DR7_2_N | PE_CLK100M_DR7_2-DIFF1 | PAIR | 1 | 6.88 | 5 | 10 | 5 | 12 | 20 | 36 | 12 | 12 | 20 | 12 | 5.13 | 85 Ohms | TOP=L2:L3=L2/L4:L6=L5/L7:BOTTOM=L7 |
| PE_CLK100M_DR7_2_N | PE_CLK100M_DR7_2-DIFF1 | PAIR | 2 | 6.5 | 5 | 10 | 5 | 12 | 20 | 25 | 12 | 12 | 20 | 12 | 7.5 | 85 Ohms | TOP=L2:L3=L2/L4:L6=L5/L7:BOTTOM=L7 |
| PE_CLK100M_DR7_2_N | PE_CLK100M_DR7_2-DIFF1 | PAIR | 3 | 6.5 | 5 | 10 | 5 | 12 | 20 | 25 | 12 | 12 | 20 | 12 | 7.5 | 85 Ohms | TOP=L2:L3=L2/L4:L6=L5/L7:BOTTOM=L7 |
| PE_CLK100M_DR7_2_N | PE_CLK100M_DR7_2-DIFF1 | PAIR | 4 | 6.5 | 5 | 10 | 5 | 12 | 20 | 25 | 12 | 12 | 20 | 12 | 7.5 | 85 Ohms | TOP=L2:L3=L2/L4:L6=L5/L7:BOTTOM=L7 |
| PE_CLK100M_DR7_2_N | PE_CLK100M_DR7_2-DIFF1 | PAIR | 5 | 6.5 | 5 | 10 | 5 | 12 | 20 | 25 | 12 | 12 | 20 | 12 | 7.5 | 85 Ohms | TOP=L2:L3=L2/L4:L6=L5/L7:BOTTOM=L7 |
| PE_CLK100M_DR7_2_N | PE_CLK100M_DR7_2-DIFF1 | PAIR | 6 | 6.5 | 5 | 10 | 5 | 12 | 20 | 25 | 12 | 12 | 20 | 12 | 7.5 | 85 Ohms | TOP=L2:L3=L2/L4:L6=L5/L7:BOTTOM=L7 |
| PE_CLK100M_DR7_2_N | PE_CLK100M_DR7_2-DIFF1 | PAIR | 7 | 6.5 | 5 | 10 | 5 | 12 | 20 | 25 | 12 | 12 | 20 | 12 | 7.5 | 85 Ohms | TOP=L2:L3=L2/L4:L6=L5/L7:BOTTOM=L7 |
| PE_CLK100M_DR7_2_N | PE_CLK100M_DR7_2-DIFF1 | PAIR | 8 | 6.88 | 5 | 10 | 5 | 12 | 20 | 36 | 12 | 12 | 20 | 12 | 5.13 | 85 Ohms | TOP=L2:L3=L2/L4:L6=L5/L7:BOTTOM=L7 |
| PE_CLK100M_DR7_2_P | PE_CLK100M_DR7_2-DIFF1 | PAIR | 1 | 6.88 | 5 | 10 | 5 | 12 | 20 | 36 | 12 | 12 | 20 | 12 | 5.13 | 85 Ohms | TOP=L2:L3=L2/L4:L6=L5/L7:BOTTOM=L7 |
| PE_CLK100M_DR7_2_P | PE_CLK100M_DR7_2-DIFF1 | PAIR | 2 | 6.5 | 5 | 10 | 5 | 12 | 20 | 25 | 12 | 12 | 20 | 12 | 7.5 | 85 Ohms | TOP=L2:L3=L2/L4:L6=L5/L7:BOTTOM=L7 |
| PE_CLK100M_DR7_2_P | PE_CLK100M_DR7_2-DIFF1 | PAIR | 3 | 6.5 | 5 | 10 | 5 | 12 | 20 | 25 | 12 | 12 | 20 | 12 | 7.5 | 85 Ohms | TOP=L2:L3=L2/L4:L6=L5/L7:BOTTOM=L7 |
| PE_CLK100M_DR7_2_P | PE_CLK100M_DR7_2-DIFF1 | PAIR | 4 | 6.5 | 5 | 10 | 5 | 12 | 20 | 25 | 12 | 12 | 20 | 12 | 7.5 | 85 Ohms | TOP=L2:L3=L2/L4:L6=L5/L7:BOTTOM=L7 |
| PE_CLK100M_DR7_2_P | PE_CLK100M_DR7_2-DIFF1 | PAIR | 5 | 6.5 | 5 | 10 | 5 | 12 | 20 | 25 | 12 | 12 | 20 | 12 | 7.5 | 85 Ohms | TOP=L2:L3=L2/L4:L6=L5/L7:BOTTOM=L7 |
| PE_CLK100M_DR7_2_P | PE_CLK100M_DR7_2-DIFF1 | PAIR | 6 | 6.5 | 5 | 10 | 5 | 12 | 20 | 25 | 12 | 12 | 20 | 12 | 7.5 | 85 Ohms | TOP=L2:L3=L2/L4:L6=L5/L7:BOTTOM=L7 |
| PE_CLK100M_DR7_2_P | PE_CLK100M_DR7_2-DIFF1 | PAIR | 7 | 6.5 | 5 | 10 | 5 | 12 | 20 | 25 | 12 | 12 | 20 | 12 | 7.5 | 85 Ohms | TOP=L2:L3=L2/L4:L6=L5/L7:BOTTOM=L7 |
| PE_CLK100M_DR7_2_P | PE_CLK100M_DR7_2-DIFF1 | PAIR | 8 | 6.88 | 5 | 10 | 5 | 12 | 20 | 36 | 12 | 12 | 20 | 12 | 5.13 | 85 Ohms | TOP=L2:L3=L2/L4:L6=L5/L7:BOTTOM=L7 |
| PE_CLK100M_DR8_1_N | PE_CLK100M_DR8_1-DIFF1 | PAIR | 1 | 6.88 | 5 | 10 | 5 | 12 | 20 | 36 | 12 | 12 | 20 | 12 | 5.13 | 85 Ohms | TOP=L2:L3=L2/L4:L6=L5/L7:BOTTOM=L7 |
| PE_CLK100M_DR8_1_N | PE_CLK100M_DR8_1-DIFF1 | PAIR | 2 | 6.5 | 5 | 10 | 5 | 12 | 20 | 25 | 12 | 12 | 20 | 12 | 7.5 | 85 Ohms | TOP=L2:L3=L2/L4:L6=L5/L7:BOTTOM=L7 |
| PE_CLK100M_DR8_1_N | PE_CLK100M_DR8_1-DIFF1 | PAIR | 3 | 6.5 | 5 | 10 | 5 | 12 | 20 | 25 | 12 | 12 | 20 | 12 | 7.5 | 85 Ohms | TOP=L2:L3=L2/L4:L6=L5/L7:BOTTOM=L7 |
| PE_CLK100M_DR8_1_N | PE_CLK100M_DR8_1-DIFF1 | PAIR | 4 | 6.5 | 5 | 10 | 5 | 12 | 20 | 25 | 12 | 12 | 20 | 12 | 7.5 | 85 Ohms | TOP=L2:L3=L2/L4:L6=L5/L7:BOTTOM=L7 |
| PE_CLK100M_DR8_1_N | PE_CLK100M_DR8_1-DIFF1 | PAIR | 5 | 6.5 | 5 | 10 | 5 | 12 | 20 | 25 | 12 | 12 | 20 | 12 | 7.5 | 85 Ohms | TOP=L2:L3=L2/L4:L6=L5/L7:BOTTOM=L7 |
| PE_CLK100M_DR8_1_N | PE_CLK100M_DR8_1-DIFF1 | PAIR | 6 | 6.5 | 5 | 10 | 5 | 12 | 20 | 25 | 12 | 12 | 20 | 12 | 7.5 | 85 Ohms | TOP=L2:L3=L2/L4:L6=L5/L7:BOTTOM=L7 |
| PE_CLK100M_DR8_1_N | PE_CLK100M_DR8_1-DIFF1 | PAIR | 7 | 6.5 | 5 | 10 | 5 | 12 | 20 | 25 | 12 | 12 | 20 | 12 | 7.5 | 85 Ohms | TOP=L2:L3=L2/L4:L6=L5/L7:BOTTOM=L7 |
| PE_CLK100M_DR8_1_N | PE_CLK100M_DR8_1-DIFF1 | PAIR | 8 | 6.88 | 5 | 10 | 5 | 12 | 20 | 36 | 12 | 12 | 20 | 12 | 5.13 | 85 Ohms | TOP=L2:L3=L2/L4:L6=L5/L7:BOTTOM=L7 |
| PE_CLK100M_DR8_1_P | PE_CLK100M_DR8_1-DIFF1 | PAIR | 1 | 6.88 | 5 | 10 | 5 | 12 | 20 | 36 | 12 | 12 | 20 | 12 | 5.13 | 85 Ohms | TOP=L2:L3=L2/L4:L6=L5/L7:BOTTOM=L7 |
| PE_CLK100M_DR8_1_P | PE_CLK100M_DR8_1-DIFF1 | PAIR | 2 | 6.5 | 5 | 10 | 5 | 12 | 20 | 25 | 12 | 12 | 20 | 12 | 7.5 | 85 Ohms | TOP=L2:L3=L2/L4:L6=L5/L7:BOTTOM=L7 |
| PE_CLK100M_DR8_1_P | PE_CLK100M_DR8_1-DIFF1 | PAIR | 3 | 6.5 | 5 | 10 | 5 | 12 | 20 | 25 | 12 | 12 | 20 | 12 | 7.5 | 85 Ohms | TOP=L2:L3=L2/L4:L6=L5/L7:BOTTOM=L7 |
| PE_CLK100M_DR8_1_P | PE_CLK100M_DR8_1-DIFF1 | PAIR | 4 | 6.5 | 5 | 10 | 5 | 12 | 20 | 25 | 12 | 12 | 20 | 12 | 7.5 | 85 Ohms | TOP=L2:L3=L2/L4:L6=L5/L7:BOTTOM=L7 |
| PE_CLK100M_DR8_1_P | PE_CLK100M_DR8_1-DIFF1 | PAIR | 5 | 6.5 | 5 | 10 | 5 | 12 | 20 | 25 | 12 | 12 | 20 | 12 | 7.5 | 85 Ohms | TOP=L2:L3=L2/L4:L6=L5/L7:BOTTOM=L7 |
| PE_CLK100M_DR8_1_P | PE_CLK100M_DR8_1-DIFF1 | PAIR | 6 | 6.5 | 5 | 10 | 5 | 12 | 20 | 25 | 12 | 12 | 20 | 12 | 7.5 | 85 Ohms | TOP=L2:L3=L2/L4:L6=L5/L7:BOTTOM=L7 |
| PE_CLK100M_DR8_1_P | PE_CLK100M_DR8_1-DIFF1 | PAIR | 7 | 6.5 | 5 | 10 | 5 | 12 | 20 | 25 | 12 | 12 | 20 | 12 | 7.5 | 85 Ohms | TOP=L2:L3=L2/L4:L6=L5/L7:BOTTOM=L7 |
| PE_CLK100M_DR8_1_P | PE_CLK100M_DR8_1-DIFF1 | PAIR | 8 | 6.88 | 5 | 10 | 5 | 12 | 20 | 36 | 12 | 12 | 20 | 12 | 5.13 | 85 Ohms | TOP=L2:L3=L2/L4:L6=L5/L7:BOTTOM=L7 |
| PE_CLK100M_DR8_2_N | PE_CLK100M_DR8_2-DIFF1 | PAIR | 1 | 6.88 | 5 | 10 | 5 | 12 | 20 | 36 | 12 | 12 | 20 | 12 | 5.13 | 85 Ohms | TOP=L2:L3=L2/L4:L6=L5/L7:BOTTOM=L7 |
| PE_CLK100M_DR8_2_N | PE_CLK100M_DR8_2-DIFF1 | PAIR | 2 | 6.5 | 5 | 10 | 5 | 12 | 20 | 25 | 12 | 12 | 20 | 12 | 7.5 | 85 Ohms | TOP=L2:L3=L2/L4:L6=L5/L7:BOTTOM=L7 |
| PE_CLK100M_DR8_2_N | PE_CLK100M_DR8_2-DIFF1 | PAIR | 3 | 6.5 | 5 | 10 | 5 | 12 | 20 | 25 | 12 | 12 | 20 | 12 | 7.5 | 85 Ohms | TOP=L2:L3=L2/L4:L6=L5/L7:BOTTOM=L7 |
| PE_CLK100M_DR8_2_N | PE_CLK100M_DR8_2-DIFF1 | PAIR | 4 | 6.5 | 5 | 10 | 5 | 12 | 20 | 25 | 12 | 12 | 20 | 12 | 7.5 | 85 Ohms | TOP=L2:L3=L2/L4:L6=L5/L7:BOTTOM=L7 |
| PE_CLK100M_DR8_2_N | PE_CLK100M_DR8_2-DIFF1 | PAIR | 5 | 6.5 | 5 | 10 | 5 | 12 | 20 | 25 | 12 | 12 | 20 | 12 | 7.5 | 85 Ohms | TOP=L2:L3=L2/L4:L6=L5/L7:BOTTOM=L7 |
| PE_CLK100M_DR8_2_N | PE_CLK100M_DR8_2-DIFF1 | PAIR | 6 | 6.5 | 5 | 10 | 5 | 12 | 20 | 25 | 12 | 12 | 20 | 12 | 7.5 | 85 Ohms | TOP=L2:L3=L2/L4:L6=L5/L7:BOTTOM=L7 |
| PE_CLK100M_DR8_2_N | PE_CLK100M_DR8_2-DIFF1 | PAIR | 7 | 6.5 | 5 | 10 | 5 | 12 | 20 | 25 | 12 | 12 | 20 | 12 | 7.5 | 85 Ohms | TOP=L2:L3=L2/L4:L6=L5/L7:BOTTOM=L7 |
| PE_CLK100M_DR8_2_N | PE_CLK100M_DR8_2-DIFF1 | PAIR | 8 | 6.88 | 5 | 10 | 5 | 12 | 20 | 36 | 12 | 12 | 20 | 12 | 5.13 | 85 Ohms | TOP=L2:L3=L2/L4:L6=L5/L7:BOTTOM=L7 |
| PE_CLK100M_DR8_2_P | PE_CLK100M_DR8_2-DIFF1 | PAIR | 1 | 6.88 | 5 | 10 | 5 | 12 | 20 | 36 | 12 | 12 | 20 | 12 | 5.13 | 85 Ohms | TOP=L2:L3=L2/L4:L6=L5/L7:BOTTOM=L7 |
| PE_CLK100M_DR8_2_P | PE_CLK100M_DR8_2-DIFF1 | PAIR | 2 | 6.5 | 5 | 10 | 5 | 12 | 20 | 25 | 12 | 12 | 20 | 12 | 7.5 | 85 Ohms | TOP=L2:L3=L2/L4:L6=L5/L7:BOTTOM=L7 |
| PE_CLK100M_DR8_2_P | PE_CLK100M_DR8_2-DIFF1 | PAIR | 3 | 6.5 | 5 | 10 | 5 | 12 | 20 | 25 | 12 | 12 | 20 | 12 | 7.5 | 85 Ohms | TOP=L2:L3=L2/L4:L6=L5/L7:BOTTOM=L7 |
| PE_CLK100M_DR8_2_P | PE_CLK100M_DR8_2-DIFF1 | PAIR | 4 | 6.5 | 5 | 10 | 5 | 12 | 20 | 25 | 12 | 12 | 20 | 12 | 7.5 | 85 Ohms | TOP=L2:L3=L2/L4:L6=L5/L7:BOTTOM=L7 |
| PE_CLK100M_DR8_2_P | PE_CLK100M_DR8_2-DIFF1 | PAIR | 5 | 6.5 | 5 | 10 | 5 | 12 | 20 | 25 | 12 | 12 | 20 | 12 | 7.5 | 85 Ohms | TOP=L2:L3=L2/L4:L6=L5/L7:BOTTOM=L7 |
| PE_CLK100M_DR8_2_P | PE_CLK100M_DR8_2-DIFF1 | PAIR | 6 | 6.5 | 5 | 10 | 5 | 12 | 20 | 25 | 12 | 12 | 20 | 12 | 7.5 | 85 Ohms | TOP=L2:L3=L2/L4:L6=L5/L7:BOTTOM=L7 |
| PE_CLK100M_DR8_2_P | PE_CLK100M_DR8_2-DIFF1 | PAIR | 7 | 6.5 | 5 | 10 | 5 | 12 | 20 | 25 | 12 | 12 | 20 | 12 | 7.5 | 85 Ohms | TOP=L2:L3=L2/L4:L6=L5/L7:BOTTOM=L7 |
| PE_CLK100M_DR8_2_P | PE_CLK100M_DR8_2-DIFF1 | PAIR | 8 | 6.88 | 5 | 10 | 5 | 12 | 20 | 36 | 12 | 12 | 20 | 12 | 5.13 | 85 Ohms | TOP=L2:L3=L2/L4:L6=L5/L7:BOTTOM=L7 |
| PE_CLK100M_DR9_1_N | PE_CLK100M_DR9_1-DIFF1 | PAIR | 1 | 6.88 | 5 | 10 | 5 | 12 | 20 | 36 | 12 | 12 | 20 | 12 | 5.13 | 85 Ohms | TOP=L2:L3=L2/L4:L6=L5/L7:BOTTOM=L7 |
| PE_CLK100M_DR9_1_N | PE_CLK100M_DR9_1-DIFF1 | PAIR | 2 | 6.5 | 5 | 10 | 5 | 12 | 20 | 25 | 12 | 12 | 20 | 12 | 7.5 | 85 Ohms | TOP=L2:L3=L2/L4:L6=L5/L7:BOTTOM=L7 |
| PE_CLK100M_DR9_1_N | PE_CLK100M_DR9_1-DIFF1 | PAIR | 3 | 6.5 | 5 | 10 | 5 | 12 | 20 | 25 | 12 | 12 | 20 | 12 | 7.5 | 85 Ohms | TOP=L2:L3=L2/L4:L6=L5/L7:BOTTOM=L7 |
| PE_CLK100M_DR9_1_N | PE_CLK100M_DR9_1-DIFF1 | PAIR | 4 | 6.5 | 5 | 10 | 5 | 12 | 20 | 25 | 12 | 12 | 20 | 12 | 7.5 | 85 Ohms | TOP=L2:L3=L2/L4:L6=L5/L7:BOTTOM=L7 |
| PE_CLK100M_DR9_1_N | PE_CLK100M_DR9_1-DIFF1 | PAIR | 5 | 6.5 | 5 | 10 | 5 | 12 | 20 | 25 | 12 | 12 | 20 | 12 | 7.5 | 85 Ohms | TOP=L2:L3=L2/L4:L6=L5/L7:BOTTOM=L7 |
| PE_CLK100M_DR9_1_N | PE_CLK100M_DR9_1-DIFF1 | PAIR | 6 | 6.5 | 5 | 10 | 5 | 12 | 20 | 25 | 12 | 12 | 20 | 12 | 7.5 | 85 Ohms | TOP=L2:L3=L2/L4:L6=L5/L7:BOTTOM=L7 |
| PE_CLK100M_DR9_1_N | PE_CLK100M_DR9_1-DIFF1 | PAIR | 7 | 6.5 | 5 | 10 | 5 | 12 | 20 | 25 | 12 | 12 | 20 | 12 | 7.5 | 85 Ohms | TOP=L2:L3=L2/L4:L6=L5/L7:BOTTOM=L7 |
| PE_CLK100M_DR9_1_N | PE_CLK100M_DR9_1-DIFF1 | PAIR | 8 | 6.88 | 5 | 10 | 5 | 12 | 20 | 36 | 12 | 12 | 20 | 12 | 5.13 | 85 Ohms | TOP=L2:L3=L2/L4:L6=L5/L7:BOTTOM=L7 |
| PE_CLK100M_DR9_1_P | PE_CLK100M_DR9_1-DIFF1 | PAIR | 1 | 6.88 | 5 | 10 | 5 | 12 | 20 | 36 | 12 | 12 | 20 | 12 | 5.13 | 85 Ohms | TOP=L2:L3=L2/L4:L6=L5/L7:BOTTOM=L7 |
| PE_CLK100M_DR9_1_P | PE_CLK100M_DR9_1-DIFF1 | PAIR | 2 | 6.5 | 5 | 10 | 5 | 12 | 20 | 25 | 12 | 12 | 20 | 12 | 7.5 | 85 Ohms | TOP=L2:L3=L2/L4:L6=L5/L7:BOTTOM=L7 |
| PE_CLK100M_DR9_1_P | PE_CLK100M_DR9_1-DIFF1 | PAIR | 3 | 6.5 | 5 | 10 | 5 | 12 | 20 | 25 | 12 | 12 | 20 | 12 | 7.5 | 85 Ohms | TOP=L2:L3=L2/L4:L6=L5/L7:BOTTOM=L7 |
| PE_CLK100M_DR9_1_P | PE_CLK100M_DR9_1-DIFF1 | PAIR | 4 | 6.5 | 5 | 10 | 5 | 12 | 20 | 25 | 12 | 12 | 20 | 12 | 7.5 | 85 Ohms | TOP=L2:L3=L2/L4:L6=L5/L7:BOTTOM=L7 |
| PE_CLK100M_DR9_1_P | PE_CLK100M_DR9_1-DIFF1 | PAIR | 5 | 6.5 | 5 | 10 | 5 | 12 | 20 | 25 | 12 | 12 | 20 | 12 | 7.5 | 85 Ohms | TOP=L2:L3=L2/L4:L6=L5/L7:BOTTOM=L7 |
| PE_CLK100M_DR9_1_P | PE_CLK100M_DR9_1-DIFF1 | PAIR | 6 | 6.5 | 5 | 10 | 5 | 12 | 20 | 25 | 12 | 12 | 20 | 12 | 7.5 | 85 Ohms | TOP=L2:L3=L2/L4:L6=L5/L7:BOTTOM=L7 |
| PE_CLK100M_DR9_1_P | PE_CLK100M_DR9_1-DIFF1 | PAIR | 7 | 6.5 | 5 | 10 | 5 | 12 | 20 | 25 | 12 | 12 | 20 | 12 | 7.5 | 85 Ohms | TOP=L2:L3=L2/L4:L6=L5/L7:BOTTOM=L7 |
| PE_CLK100M_DR9_1_P | PE_CLK100M_DR9_1-DIFF1 | PAIR | 8 | 6.88 | 5 | 10 | 5 | 12 | 20 | 36 | 12 | 12 | 20 | 12 | 5.13 | 85 Ohms | TOP=L2:L3=L2/L4:L6=L5/L7:BOTTOM=L7 |
| PE_CLK100M_DR9_2_N | PE_CLK100M_DR9_2-DIFF1 | PAIR | 1 | 6.88 | 5 | 10 | 5 | 12 | 20 | 36 | 12 | 12 | 20 | 12 | 5.13 | 85 Ohms | TOP=L2:L3=L2/L4:L6=L5/L7:BOTTOM=L7 |
| PE_CLK100M_DR9_2_N | PE_CLK100M_DR9_2-DIFF1 | PAIR | 2 | 6.5 | 5 | 10 | 5 | 12 | 20 | 25 | 12 | 12 | 20 | 12 | 7.5 | 85 Ohms | TOP=L2:L3=L2/L4:L6=L5/L7:BOTTOM=L7 |
| PE_CLK100M_DR9_2_N | PE_CLK100M_DR9_2-DIFF1 | PAIR | 3 | 6.5 | 5 | 10 | 5 | 12 | 20 | 25 | 12 | 12 | 20 | 12 | 7.5 | 85 Ohms | TOP=L2:L3=L2/L4:L6=L5/L7:BOTTOM=L7 |
| PE_CLK100M_DR9_2_N | PE_CLK100M_DR9_2-DIFF1 | PAIR | 4 | 6.5 | 5 | 10 | 5 | 12 | 20 | 25 | 12 | 12 | 20 | 12 | 7.5 | 85 Ohms | TOP=L2:L3=L2/L4:L6=L5/L7:BOTTOM=L7 |
| PE_CLK100M_DR9_2_N | PE_CLK100M_DR9_2-DIFF1 | PAIR | 5 | 6.5 | 5 | 10 | 5 | 12 | 20 | 25 | 12 | 12 | 20 | 12 | 7.5 | 85 Ohms | TOP=L2:L3=L2/L4:L6=L5/L7:BOTTOM=L7 |
| PE_CLK100M_DR9_2_N | PE_CLK100M_DR9_2-DIFF1 | PAIR | 6 | 6.5 | 5 | 10 | 5 | 12 | 20 | 25 | 12 | 12 | 20 | 12 | 7.5 | 85 Ohms | TOP=L2:L3=L2/L4:L6=L5/L7:BOTTOM=L7 |
| PE_CLK100M_DR9_2_N | PE_CLK100M_DR9_2-DIFF1 | PAIR | 7 | 6.5 | 5 | 10 | 5 | 12 | 20 | 25 | 12 | 12 | 20 | 12 | 7.5 | 85 Ohms | TOP=L2:L3=L2/L4:L6=L5/L7:BOTTOM=L7 |
| PE_CLK100M_DR9_2_N | PE_CLK100M_DR9_2-DIFF1 | PAIR | 8 | 6.88 | 5 | 10 | 5 | 12 | 20 | 36 | 12 | 12 | 20 | 12 | 5.13 | 85 Ohms | TOP=L2:L3=L2/L4:L6=L5/L7:BOTTOM=L7 |
| PE_CLK100M_DR9_2_P | PE_CLK100M_DR9_2-DIFF1 | PAIR | 1 | 6.88 | 5 | 10 | 5 | 12 | 20 | 36 | 12 | 12 | 20 | 12 | 5.13 | 85 Ohms | TOP=L2:L3=L2/L4:L6=L5/L7:BOTTOM=L7 |
| PE_CLK100M_DR9_2_P | PE_CLK100M_DR9_2-DIFF1 | PAIR | 2 | 6.5 | 5 | 10 | 5 | 12 | 20 | 25 | 12 | 12 | 20 | 12 | 7.5 | 85 Ohms | TOP=L2:L3=L2/L4:L6=L5/L7:BOTTOM=L7 |
| PE_CLK100M_DR9_2_P | PE_CLK100M_DR9_2-DIFF1 | PAIR | 3 | 6.5 | 5 | 10 | 5 | 12 | 20 | 25 | 12 | 12 | 20 | 12 | 7.5 | 85 Ohms | TOP=L2:L3=L2/L4:L6=L5/L7:BOTTOM=L7 |
| PE_CLK100M_DR9_2_P | PE_CLK100M_DR9_2-DIFF1 | PAIR | 4 | 6.5 | 5 | 10 | 5 | 12 | 20 | 25 | 12 | 12 | 20 | 12 | 7.5 | 85 Ohms | TOP=L2:L3=L2/L4:L6=L5/L7:BOTTOM=L7 |
| PE_CLK100M_DR9_2_P | PE_CLK100M_DR9_2-DIFF1 | PAIR | 5 | 6.5 | 5 | 10 | 5 | 12 | 20 | 25 | 12 | 12 | 20 | 12 | 7.5 | 85 Ohms | TOP=L2:L3=L2/L4:L6=L5/L7:BOTTOM=L7 |
| PE_CLK100M_DR9_2_P | PE_CLK100M_DR9_2-DIFF1 | PAIR | 6 | 6.5 | 5 | 10 | 5 | 12 | 20 | 25 | 12 | 12 | 20 | 12 | 7.5 | 85 Ohms | TOP=L2:L3=L2/L4:L6=L5/L7:BOTTOM=L7 |
| PE_CLK100M_DR9_2_P | PE_CLK100M_DR9_2-DIFF1 | PAIR | 7 | 6.5 | 5 | 10 | 5 | 12 | 20 | 25 | 12 | 12 | 20 | 12 | 7.5 | 85 Ohms | TOP=L2:L3=L2/L4:L6=L5/L7:BOTTOM=L7 |
| PE_CLK100M_DR9_2_P | PE_CLK100M_DR9_2-DIFF1 | PAIR | 8 | 6.88 | 5 | 10 | 5 | 12 | 20 | 36 | 12 | 12 | 20 | 12 | 5.13 | 85 Ohms | TOP=L2:L3=L2/L4:L6=L5/L7:BOTTOM=L7 |
| PE_RX1_DR0_N | PE_RX1_DR0-DIFF1 | PAIR | 1 | 6.88 | 5 | 10 | 5 | 50 | 20 | 36 | 12 | 12 | 20 | 12 | 5.13 | 85 Ohms | TOP=L2:L3=L2/L4:L6=L5/L7:BOTTOM=L7 |
| PE_RX1_DR0_N | PE_RX1_DR0-DIFF1 | PAIR | 2 | 6.5 | 5 | 10 | 5 | 50 | 20 | 25 | 12 | 12 | 20 | 12 | 7.5 | 85 Ohms | TOP=L2:L3=L2/L4:L6=L5/L7:BOTTOM=L7 |
| PE_RX1_DR0_N | PE_RX1_DR0-DIFF1 | PAIR | 3 | 6.5 | 5 | 10 | 5 | 50 | 20 | 25 | 12 | 12 | 20 | 12 | 7.5 | 85 Ohms | TOP=L2:L3=L2/L4:L6=L5/L7:BOTTOM=L7 |
| PE_RX1_DR0_N | PE_RX1_DR0-DIFF1 | PAIR | 4 | 6.5 | 5 | 10 | 5 | 50 | 20 | 25 | 12 | 12 | 20 | 12 | 7.5 | 85 Ohms | TOP=L2:L3=L2/L4:L6=L5/L7:BOTTOM=L7 |
| PE_RX1_DR0_N | PE_RX1_DR0-DIFF1 | PAIR | 5 | 6.5 | 5 | 10 | 5 | 50 | 20 | 25 | 12 | 12 | 20 | 12 | 7.5 | 85 Ohms | TOP=L2:L3=L2/L4:L6=L5/L7:BOTTOM=L7 |
| PE_RX1_DR0_N | PE_RX1_DR0-DIFF1 | PAIR | 6 | 6.5 | 5 | 10 | 5 | 50 | 20 | 25 | 12 | 12 | 20 | 12 | 7.5 | 85 Ohms | TOP=L2:L3=L2/L4:L6=L5/L7:BOTTOM=L7 |
| PE_RX1_DR0_N | PE_RX1_DR0-DIFF1 | PAIR | 7 | 6.5 | 5 | 10 | 5 | 50 | 20 | 25 | 12 | 12 | 20 | 12 | 7.5 | 85 Ohms | TOP=L2:L3=L2/L4:L6=L5/L7:BOTTOM=L7 |
| PE_RX1_DR0_N | PE_RX1_DR0-DIFF1 | PAIR | 8 | 6.88 | 5 | 10 | 5 | 50 | 20 | 36 | 12 | 12 | 20 | 12 | 5.13 | 85 Ohms | TOP=L2:L3=L2/L4:L6=L5/L7:BOTTOM=L7 |
| PE_RX1_DR0_P | PE_RX1_DR0-DIFF1 | PAIR | 1 | 6.88 | 5 | 10 | 5 | 50 | 20 | 36 | 12 | 12 | 20 | 12 | 5.13 | 85 Ohms | TOP=L2:L3=L2/L4:L6=L5/L7:BOTTOM=L7 |
| PE_RX1_DR0_P | PE_RX1_DR0-DIFF1 | PAIR | 2 | 6.5 | 5 | 10 | 5 | 50 | 20 | 25 | 12 | 12 | 20 | 12 | 7.5 | 85 Ohms | TOP=L2:L3=L2/L4:L6=L5/L7:BOTTOM=L7 |
| PE_RX1_DR0_P | PE_RX1_DR0-DIFF1 | PAIR | 3 | 6.5 | 5 | 10 | 5 | 50 | 20 | 25 | 12 | 12 | 20 | 12 | 7.5 | 85 Ohms | TOP=L2:L3=L2/L4:L6=L5/L7:BOTTOM=L7 |
| PE_RX1_DR0_P | PE_RX1_DR0-DIFF1 | PAIR | 4 | 6.5 | 5 | 10 | 5 | 50 | 20 | 25 | 12 | 12 | 20 | 12 | 7.5 | 85 Ohms | TOP=L2:L3=L2/L4:L6=L5/L7:BOTTOM=L7 |
| PE_RX1_DR0_P | PE_RX1_DR0-DIFF1 | PAIR | 5 | 6.5 | 5 | 10 | 5 | 50 | 20 | 25 | 12 | 12 | 20 | 12 | 7.5 | 85 Ohms | TOP=L2:L3=L2/L4:L6=L5/L7:BOTTOM=L7 |
| PE_RX1_DR0_P | PE_RX1_DR0-DIFF1 | PAIR | 6 | 6.5 | 5 | 10 | 5 | 50 | 20 | 25 | 12 | 12 | 20 | 12 | 7.5 | 85 Ohms | TOP=L2:L3=L2/L4:L6=L5/L7:BOTTOM=L7 |
| PE_RX1_DR0_P | PE_RX1_DR0-DIFF1 | PAIR | 7 | 6.5 | 5 | 10 | 5 | 50 | 20 | 25 | 12 | 12 | 20 | 12 | 7.5 | 85 Ohms | TOP=L2:L3=L2/L4:L6=L5/L7:BOTTOM=L7 |
| PE_RX1_DR0_P | PE_RX1_DR0-DIFF1 | PAIR | 8 | 6.88 | 5 | 10 | 5 | 50 | 20 | 36 | 12 | 12 | 20 | 12 | 5.13 | 85 Ohms | TOP=L2:L3=L2/L4:L6=L5/L7:BOTTOM=L7 |
| PE_RX1_DR10_N | PE_RX1_DR10-DIFF1 | PAIR | 1 | 6.88 | 5 | 10 | 5 | 50 | 20 | 36 | 12 | 12 | 20 | 12 | 5.13 | 85 Ohms | TOP=L2:L3=L2/L4:L6=L5/L7:BOTTOM=L7 |
| PE_RX1_DR10_N | PE_RX1_DR10-DIFF1 | PAIR | 2 | 6.5 | 5 | 10 | 5 | 50 | 20 | 25 | 12 | 12 | 20 | 12 | 7.5 | 85 Ohms | TOP=L2:L3=L2/L4:L6=L5/L7:BOTTOM=L7 |
| PE_RX1_DR10_N | PE_RX1_DR10-DIFF1 | PAIR | 3 | 6.5 | 5 | 10 | 5 | 50 | 20 | 25 | 12 | 12 | 20 | 12 | 7.5 | 85 Ohms | TOP=L2:L3=L2/L4:L6=L5/L7:BOTTOM=L7 |
| PE_RX1_DR10_N | PE_RX1_DR10-DIFF1 | PAIR | 4 | 6.5 | 5 | 10 | 5 | 50 | 20 | 25 | 12 | 12 | 20 | 12 | 7.5 | 85 Ohms | TOP=L2:L3=L2/L4:L6=L5/L7:BOTTOM=L7 |
| PE_RX1_DR10_N | PE_RX1_DR10-DIFF1 | PAIR | 5 | 6.5 | 5 | 10 | 5 | 50 | 20 | 25 | 12 | 12 | 20 | 12 | 7.5 | 85 Ohms | TOP=L2:L3=L2/L4:L6=L5/L7:BOTTOM=L7 |
| PE_RX1_DR10_N | PE_RX1_DR10-DIFF1 | PAIR | 6 | 6.5 | 5 | 10 | 5 | 50 | 20 | 25 | 12 | 12 | 20 | 12 | 7.5 | 85 Ohms | TOP=L2:L3=L2/L4:L6=L5/L7:BOTTOM=L7 |
| PE_RX1_DR10_N | PE_RX1_DR10-DIFF1 | PAIR | 7 | 6.5 | 5 | 10 | 5 | 50 | 20 | 25 | 12 | 12 | 20 | 12 | 7.5 | 85 Ohms | TOP=L2:L3=L2/L4:L6=L5/L7:BOTTOM=L7 |
| PE_RX1_DR10_N | PE_RX1_DR10-DIFF1 | PAIR | 8 | 6.88 | 5 | 10 | 5 | 50 | 20 | 36 | 12 | 12 | 20 | 12 | 5.13 | 85 Ohms | TOP=L2:L3=L2/L4:L6=L5/L7:BOTTOM=L7 |
| PE_RX1_DR10_P | PE_RX1_DR10-DIFF1 | PAIR | 1 | 6.88 | 5 | 10 | 5 | 50 | 20 | 36 | 12 | 12 | 20 | 12 | 5.13 | 85 Ohms | TOP=L2:L3=L2/L4:L6=L5/L7:BOTTOM=L7 |
| PE_RX1_DR10_P | PE_RX1_DR10-DIFF1 | PAIR | 2 | 6.5 | 5 | 10 | 5 | 50 | 20 | 25 | 12 | 12 | 20 | 12 | 7.5 | 85 Ohms | TOP=L2:L3=L2/L4:L6=L5/L7:BOTTOM=L7 |
| PE_RX1_DR10_P | PE_RX1_DR10-DIFF1 | PAIR | 3 | 6.5 | 5 | 10 | 5 | 50 | 20 | 25 | 12 | 12 | 20 | 12 | 7.5 | 85 Ohms | TOP=L2:L3=L2/L4:L6=L5/L7:BOTTOM=L7 |
| PE_RX1_DR10_P | PE_RX1_DR10-DIFF1 | PAIR | 4 | 6.5 | 5 | 10 | 5 | 50 | 20 | 25 | 12 | 12 | 20 | 12 | 7.5 | 85 Ohms | TOP=L2:L3=L2/L4:L6=L5/L7:BOTTOM=L7 |
| PE_RX1_DR10_P | PE_RX1_DR10-DIFF1 | PAIR | 5 | 6.5 | 5 | 10 | 5 | 50 | 20 | 25 | 12 | 12 | 20 | 12 | 7.5 | 85 Ohms | TOP=L2:L3=L2/L4:L6=L5/L7:BOTTOM=L7 |
| PE_RX1_DR10_P | PE_RX1_DR10-DIFF1 | PAIR | 6 | 6.5 | 5 | 10 | 5 | 50 | 20 | 25 | 12 | 12 | 20 | 12 | 7.5 | 85 Ohms | TOP=L2:L3=L2/L4:L6=L5/L7:BOTTOM=L7 |
| PE_RX1_DR10_P | PE_RX1_DR10-DIFF1 | PAIR | 7 | 6.5 | 5 | 10 | 5 | 50 | 20 | 25 | 12 | 12 | 20 | 12 | 7.5 | 85 Ohms | TOP=L2:L3=L2/L4:L6=L5/L7:BOTTOM=L7 |
| PE_RX1_DR10_P | PE_RX1_DR10-DIFF1 | PAIR | 8 | 6.88 | 5 | 10 | 5 | 50 | 20 | 36 | 12 | 12 | 20 | 12 | 5.13 | 85 Ohms | TOP=L2:L3=L2/L4:L6=L5/L7:BOTTOM=L7 |
| PE_RX1_DR11_N | PE_RX1_DR11-DIFF1 | PAIR | 1 | 6.88 | 5 | 10 | 5 | 50 | 20 | 36 | 12 | 12 | 20 | 12 | 5.13 | 85 Ohms | TOP=L2:L3=L2/L4:L6=L5/L7:BOTTOM=L7 |
| PE_RX1_DR11_N | PE_RX1_DR11-DIFF1 | PAIR | 2 | 6.5 | 5 | 10 | 5 | 50 | 20 | 25 | 12 | 12 | 20 | 12 | 7.5 | 85 Ohms | TOP=L2:L3=L2/L4:L6=L5/L7:BOTTOM=L7 |
| PE_RX1_DR11_N | PE_RX1_DR11-DIFF1 | PAIR | 3 | 6.5 | 5 | 10 | 5 | 50 | 20 | 25 | 12 | 12 | 20 | 12 | 7.5 | 85 Ohms | TOP=L2:L3=L2/L4:L6=L5/L7:BOTTOM=L7 |
| PE_RX1_DR11_N | PE_RX1_DR11-DIFF1 | PAIR | 4 | 6.5 | 5 | 10 | 5 | 50 | 20 | 25 | 12 | 12 | 20 | 12 | 7.5 | 85 Ohms | TOP=L2:L3=L2/L4:L6=L5/L7:BOTTOM=L7 |
| PE_RX1_DR11_N | PE_RX1_DR11-DIFF1 | PAIR | 5 | 6.5 | 5 | 10 | 5 | 50 | 20 | 25 | 12 | 12 | 20 | 12 | 7.5 | 85 Ohms | TOP=L2:L3=L2/L4:L6=L5/L7:BOTTOM=L7 |
| PE_RX1_DR11_N | PE_RX1_DR11-DIFF1 | PAIR | 6 | 6.5 | 5 | 10 | 5 | 50 | 20 | 25 | 12 | 12 | 20 | 12 | 7.5 | 85 Ohms | TOP=L2:L3=L2/L4:L6=L5/L7:BOTTOM=L7 |
| PE_RX1_DR11_N | PE_RX1_DR11-DIFF1 | PAIR | 7 | 6.5 | 5 | 10 | 5 | 50 | 20 | 25 | 12 | 12 | 20 | 12 | 7.5 | 85 Ohms | TOP=L2:L3=L2/L4:L6=L5/L7:BOTTOM=L7 |
| PE_RX1_DR11_N | PE_RX1_DR11-DIFF1 | PAIR | 8 | 6.88 | 5 | 10 | 5 | 50 | 20 | 36 | 12 | 12 | 20 | 12 | 5.13 | 85 Ohms | TOP=L2:L3=L2/L4:L6=L5/L7:BOTTOM=L7 |
| PE_RX1_DR11_P | PE_RX1_DR11-DIFF1 | PAIR | 1 | 6.88 | 5 | 10 | 5 | 50 | 20 | 36 | 12 | 12 | 20 | 12 | 5.13 | 85 Ohms | TOP=L2:L3=L2/L4:L6=L5/L7:BOTTOM=L7 |
| PE_RX1_DR11_P | PE_RX1_DR11-DIFF1 | PAIR | 2 | 6.5 | 5 | 10 | 5 | 50 | 20 | 25 | 12 | 12 | 20 | 12 | 7.5 | 85 Ohms | TOP=L2:L3=L2/L4:L6=L5/L7:BOTTOM=L7 |
| PE_RX1_DR11_P | PE_RX1_DR11-DIFF1 | PAIR | 3 | 6.5 | 5 | 10 | 5 | 50 | 20 | 25 | 12 | 12 | 20 | 12 | 7.5 | 85 Ohms | TOP=L2:L3=L2/L4:L6=L5/L7:BOTTOM=L7 |
| PE_RX1_DR11_P | PE_RX1_DR11-DIFF1 | PAIR | 4 | 6.5 | 5 | 10 | 5 | 50 | 20 | 25 | 12 | 12 | 20 | 12 | 7.5 | 85 Ohms | TOP=L2:L3=L2/L4:L6=L5/L7:BOTTOM=L7 |
| PE_RX1_DR11_P | PE_RX1_DR11-DIFF1 | PAIR | 5 | 6.5 | 5 | 10 | 5 | 50 | 20 | 25 | 12 | 12 | 20 | 12 | 7.5 | 85 Ohms | TOP=L2:L3=L2/L4:L6=L5/L7:BOTTOM=L7 |
| PE_RX1_DR11_P | PE_RX1_DR11-DIFF1 | PAIR | 6 | 6.5 | 5 | 10 | 5 | 50 | 20 | 25 | 12 | 12 | 20 | 12 | 7.5 | 85 Ohms | TOP=L2:L3=L2/L4:L6=L5/L7:BOTTOM=L7 |
| PE_RX1_DR11_P | PE_RX1_DR11-DIFF1 | PAIR | 7 | 6.5 | 5 | 10 | 5 | 50 | 20 | 25 | 12 | 12 | 20 | 12 | 7.5 | 85 Ohms | TOP=L2:L3=L2/L4:L6=L5/L7:BOTTOM=L7 |
| PE_RX1_DR11_P | PE_RX1_DR11-DIFF1 | PAIR | 8 | 6.88 | 5 | 10 | 5 | 50 | 20 | 36 | 12 | 12 | 20 | 12 | 5.13 | 85 Ohms | TOP=L2:L3=L2/L4:L6=L5/L7:BOTTOM=L7 |
| PE_RX1_DR12_N | PE_RX1_DR12-DIFF1 | PAIR | 1 | 6.88 | 5 | 10 | 5 | 50 | 20 | 36 | 12 | 12 | 20 | 12 | 5.13 | 85 Ohms | TOP=L2:L3=L2/L4:L6=L5/L7:BOTTOM=L7 |
| PE_RX1_DR12_N | PE_RX1_DR12-DIFF1 | PAIR | 2 | 6.5 | 5 | 10 | 5 | 50 | 20 | 25 | 12 | 12 | 20 | 12 | 7.5 | 85 Ohms | TOP=L2:L3=L2/L4:L6=L5/L7:BOTTOM=L7 |
| PE_RX1_DR12_N | PE_RX1_DR12-DIFF1 | PAIR | 3 | 6.5 | 5 | 10 | 5 | 50 | 20 | 25 | 12 | 12 | 20 | 12 | 7.5 | 85 Ohms | TOP=L2:L3=L2/L4:L6=L5/L7:BOTTOM=L7 |
| PE_RX1_DR12_N | PE_RX1_DR12-DIFF1 | PAIR | 4 | 6.5 | 5 | 10 | 5 | 50 | 20 | 25 | 12 | 12 | 20 | 12 | 7.5 | 85 Ohms | TOP=L2:L3=L2/L4:L6=L5/L7:BOTTOM=L7 |
| PE_RX1_DR12_N | PE_RX1_DR12-DIFF1 | PAIR | 5 | 6.5 | 5 | 10 | 5 | 50 | 20 | 25 | 12 | 12 | 20 | 12 | 7.5 | 85 Ohms | TOP=L2:L3=L2/L4:L6=L5/L7:BOTTOM=L7 |
| PE_RX1_DR12_N | PE_RX1_DR12-DIFF1 | PAIR | 6 | 6.5 | 5 | 10 | 5 | 50 | 20 | 25 | 12 | 12 | 20 | 12 | 7.5 | 85 Ohms | TOP=L2:L3=L2/L4:L6=L5/L7:BOTTOM=L7 |
| PE_RX1_DR12_N | PE_RX1_DR12-DIFF1 | PAIR | 7 | 6.5 | 5 | 10 | 5 | 50 | 20 | 25 | 12 | 12 | 20 | 12 | 7.5 | 85 Ohms | TOP=L2:L3=L2/L4:L6=L5/L7:BOTTOM=L7 |
| PE_RX1_DR12_N | PE_RX1_DR12-DIFF1 | PAIR | 8 | 6.88 | 5 | 10 | 5 | 50 | 20 | 36 | 12 | 12 | 20 | 12 | 5.13 | 85 Ohms | TOP=L2:L3=L2/L4:L6=L5/L7:BOTTOM=L7 |
| PE_RX1_DR12_P | PE_RX1_DR12-DIFF1 | PAIR | 1 | 6.88 | 5 | 10 | 5 | 50 | 20 | 36 | 12 | 12 | 20 | 12 | 5.13 | 85 Ohms | TOP=L2:L3=L2/L4:L6=L5/L7:BOTTOM=L7 |
| PE_RX1_DR12_P | PE_RX1_DR12-DIFF1 | PAIR | 2 | 6.5 | 5 | 10 | 5 | 50 | 20 | 25 | 12 | 12 | 20 | 12 | 7.5 | 85 Ohms | TOP=L2:L3=L2/L4:L6=L5/L7:BOTTOM=L7 |
| PE_RX1_DR12_P | PE_RX1_DR12-DIFF1 | PAIR | 3 | 6.5 | 5 | 10 | 5 | 50 | 20 | 25 | 12 | 12 | 20 | 12 | 7.5 | 85 Ohms | TOP=L2:L3=L2/L4:L6=L5/L7:BOTTOM=L7 |
| PE_RX1_DR12_P | PE_RX1_DR12-DIFF1 | PAIR | 4 | 6.5 | 5 | 10 | 5 | 50 | 20 | 25 | 12 | 12 | 20 | 12 | 7.5 | 85 Ohms | TOP=L2:L3=L2/L4:L6=L5/L7:BOTTOM=L7 |
| PE_RX1_DR12_P | PE_RX1_DR12-DIFF1 | PAIR | 5 | 6.5 | 5 | 10 | 5 | 50 | 20 | 25 | 12 | 12 | 20 | 12 | 7.5 | 85 Ohms | TOP=L2:L3=L2/L4:L6=L5/L7:BOTTOM=L7 |
| PE_RX1_DR12_P | PE_RX1_DR12-DIFF1 | PAIR | 6 | 6.5 | 5 | 10 | 5 | 50 | 20 | 25 | 12 | 12 | 20 | 12 | 7.5 | 85 Ohms | TOP=L2:L3=L2/L4:L6=L5/L7:BOTTOM=L7 |
| PE_RX1_DR12_P | PE_RX1_DR12-DIFF1 | PAIR | 7 | 6.5 | 5 | 10 | 5 | 50 | 20 | 25 | 12 | 12 | 20 | 12 | 7.5 | 85 Ohms | TOP=L2:L3=L2/L4:L6=L5/L7:BOTTOM=L7 |
| PE_RX1_DR12_P | PE_RX1_DR12-DIFF1 | PAIR | 8 | 6.88 | 5 | 10 | 5 | 50 | 20 | 36 | 12 | 12 | 20 | 12 | 5.13 | 85 Ohms | TOP=L2:L3=L2/L4:L6=L5/L7:BOTTOM=L7 |
| PE_RX1_DR13_N | PE_RX1_DR13-DIFF1 | PAIR | 1 | 6.88 | 5 | 10 | 5 | 50 | 20 | 36 | 12 | 12 | 20 | 12 | 5.13 | 85 Ohms | TOP=L2:L3=L2/L4:L6=L5/L7:BOTTOM=L7 |
| PE_RX1_DR13_N | PE_RX1_DR13-DIFF1 | PAIR | 2 | 6.5 | 5 | 10 | 5 | 50 | 20 | 25 | 12 | 12 | 20 | 12 | 7.5 | 85 Ohms | TOP=L2:L3=L2/L4:L6=L5/L7:BOTTOM=L7 |
| PE_RX1_DR13_N | PE_RX1_DR13-DIFF1 | PAIR | 3 | 6.5 | 5 | 10 | 5 | 50 | 20 | 25 | 12 | 12 | 20 | 12 | 7.5 | 85 Ohms | TOP=L2:L3=L2/L4:L6=L5/L7:BOTTOM=L7 |
| PE_RX1_DR13_N | PE_RX1_DR13-DIFF1 | PAIR | 4 | 6.5 | 5 | 10 | 5 | 50 | 20 | 25 | 12 | 12 | 20 | 12 | 7.5 | 85 Ohms | TOP=L2:L3=L2/L4:L6=L5/L7:BOTTOM=L7 |
| PE_RX1_DR13_N | PE_RX1_DR13-DIFF1 | PAIR | 5 | 6.5 | 5 | 10 | 5 | 50 | 20 | 25 | 12 | 12 | 20 | 12 | 7.5 | 85 Ohms | TOP=L2:L3=L2/L4:L6=L5/L7:BOTTOM=L7 |
| PE_RX1_DR13_N | PE_RX1_DR13-DIFF1 | PAIR | 6 | 6.5 | 5 | 10 | 5 | 50 | 20 | 25 | 12 | 12 | 20 | 12 | 7.5 | 85 Ohms | TOP=L2:L3=L2/L4:L6=L5/L7:BOTTOM=L7 |
| PE_RX1_DR13_N | PE_RX1_DR13-DIFF1 | PAIR | 7 | 6.5 | 5 | 10 | 5 | 50 | 20 | 25 | 12 | 12 | 20 | 12 | 7.5 | 85 Ohms | TOP=L2:L3=L2/L4:L6=L5/L7:BOTTOM=L7 |
| PE_RX1_DR13_N | PE_RX1_DR13-DIFF1 | PAIR | 8 | 6.88 | 5 | 10 | 5 | 50 | 20 | 36 | 12 | 12 | 20 | 12 | 5.13 | 85 Ohms | TOP=L2:L3=L2/L4:L6=L5/L7:BOTTOM=L7 |
| PE_RX1_DR13_P | PE_RX1_DR13-DIFF1 | PAIR | 1 | 6.88 | 5 | 10 | 5 | 50 | 20 | 36 | 12 | 12 | 20 | 12 | 5.13 | 85 Ohms | TOP=L2:L3=L2/L4:L6=L5/L7:BOTTOM=L7 |
| PE_RX1_DR13_P | PE_RX1_DR13-DIFF1 | PAIR | 2 | 6.5 | 5 | 10 | 5 | 50 | 20 | 25 | 12 | 12 | 20 | 12 | 7.5 | 85 Ohms | TOP=L2:L3=L2/L4:L6=L5/L7:BOTTOM=L7 |
| PE_RX1_DR13_P | PE_RX1_DR13-DIFF1 | PAIR | 3 | 6.5 | 5 | 10 | 5 | 50 | 20 | 25 | 12 | 12 | 20 | 12 | 7.5 | 85 Ohms | TOP=L2:L3=L2/L4:L6=L5/L7:BOTTOM=L7 |
| PE_RX1_DR13_P | PE_RX1_DR13-DIFF1 | PAIR | 4 | 6.5 | 5 | 10 | 5 | 50 | 20 | 25 | 12 | 12 | 20 | 12 | 7.5 | 85 Ohms | TOP=L2:L3=L2/L4:L6=L5/L7:BOTTOM=L7 |
| PE_RX1_DR13_P | PE_RX1_DR13-DIFF1 | PAIR | 5 | 6.5 | 5 | 10 | 5 | 50 | 20 | 25 | 12 | 12 | 20 | 12 | 7.5 | 85 Ohms | TOP=L2:L3=L2/L4:L6=L5/L7:BOTTOM=L7 |
| PE_RX1_DR13_P | PE_RX1_DR13-DIFF1 | PAIR | 6 | 6.5 | 5 | 10 | 5 | 50 | 20 | 25 | 12 | 12 | 20 | 12 | 7.5 | 85 Ohms | TOP=L2:L3=L2/L4:L6=L5/L7:BOTTOM=L7 |
| PE_RX1_DR13_P | PE_RX1_DR13-DIFF1 | PAIR | 7 | 6.5 | 5 | 10 | 5 | 50 | 20 | 25 | 12 | 12 | 20 | 12 | 7.5 | 85 Ohms | TOP=L2:L3=L2/L4:L6=L5/L7:BOTTOM=L7 |
| PE_RX1_DR13_P | PE_RX1_DR13-DIFF1 | PAIR | 8 | 6.88 | 5 | 10 | 5 | 50 | 20 | 36 | 12 | 12 | 20 | 12 | 5.13 | 85 Ohms | TOP=L2:L3=L2/L4:L6=L5/L7:BOTTOM=L7 |
| PE_RX1_DR14_N | PE_RX1_DR14-DIFF1 | PAIR | 1 | 6.88 | 5 | 10 | 5 | 50 | 20 | 36 | 12 | 12 | 20 | 12 | 5.13 | 85 Ohms | TOP=L2:L3=L2/L4:L6=L5/L7:BOTTOM=L7 |
| PE_RX1_DR14_N | PE_RX1_DR14-DIFF1 | PAIR | 2 | 6.5 | 5 | 10 | 5 | 50 | 20 | 25 | 12 | 12 | 20 | 12 | 7.5 | 85 Ohms | TOP=L2:L3=L2/L4:L6=L5/L7:BOTTOM=L7 |
| PE_RX1_DR14_N | PE_RX1_DR14-DIFF1 | PAIR | 3 | 6.5 | 5 | 10 | 5 | 50 | 20 | 25 | 12 | 12 | 20 | 12 | 7.5 | 85 Ohms | TOP=L2:L3=L2/L4:L6=L5/L7:BOTTOM=L7 |
| PE_RX1_DR14_N | PE_RX1_DR14-DIFF1 | PAIR | 4 | 6.5 | 5 | 10 | 5 | 50 | 20 | 25 | 12 | 12 | 20 | 12 | 7.5 | 85 Ohms | TOP=L2:L3=L2/L4:L6=L5/L7:BOTTOM=L7 |
| PE_RX1_DR14_N | PE_RX1_DR14-DIFF1 | PAIR | 5 | 6.5 | 5 | 10 | 5 | 50 | 20 | 25 | 12 | 12 | 20 | 12 | 7.5 | 85 Ohms | TOP=L2:L3=L2/L4:L6=L5/L7:BOTTOM=L7 |
| PE_RX1_DR14_N | PE_RX1_DR14-DIFF1 | PAIR | 6 | 6.5 | 5 | 10 | 5 | 50 | 20 | 25 | 12 | 12 | 20 | 12 | 7.5 | 85 Ohms | TOP=L2:L3=L2/L4:L6=L5/L7:BOTTOM=L7 |
| PE_RX1_DR14_N | PE_RX1_DR14-DIFF1 | PAIR | 7 | 6.5 | 5 | 10 | 5 | 50 | 20 | 25 | 12 | 12 | 20 | 12 | 7.5 | 85 Ohms | TOP=L2:L3=L2/L4:L6=L5/L7:BOTTOM=L7 |
| PE_RX1_DR14_N | PE_RX1_DR14-DIFF1 | PAIR | 8 | 6.88 | 5 | 10 | 5 | 50 | 20 | 36 | 12 | 12 | 20 | 12 | 5.13 | 85 Ohms | TOP=L2:L3=L2/L4:L6=L5/L7:BOTTOM=L7 |
| PE_RX1_DR14_P | PE_RX1_DR14-DIFF1 | PAIR | 1 | 6.88 | 5 | 10 | 5 | 50 | 20 | 36 | 12 | 12 | 20 | 12 | 5.13 | 85 Ohms | TOP=L2:L3=L2/L4:L6=L5/L7:BOTTOM=L7 |
| PE_RX1_DR14_P | PE_RX1_DR14-DIFF1 | PAIR | 2 | 6.5 | 5 | 10 | 5 | 50 | 20 | 25 | 12 | 12 | 20 | 12 | 7.5 | 85 Ohms | TOP=L2:L3=L2/L4:L6=L5/L7:BOTTOM=L7 |
| PE_RX1_DR14_P | PE_RX1_DR14-DIFF1 | PAIR | 3 | 6.5 | 5 | 10 | 5 | 50 | 20 | 25 | 12 | 12 | 20 | 12 | 7.5 | 85 Ohms | TOP=L2:L3=L2/L4:L6=L5/L7:BOTTOM=L7 |
| PE_RX1_DR14_P | PE_RX1_DR14-DIFF1 | PAIR | 4 | 6.5 | 5 | 10 | 5 | 50 | 20 | 25 | 12 | 12 | 20 | 12 | 7.5 | 85 Ohms | TOP=L2:L3=L2/L4:L6=L5/L7:BOTTOM=L7 |
| PE_RX1_DR14_P | PE_RX1_DR14-DIFF1 | PAIR | 5 | 6.5 | 5 | 10 | 5 | 50 | 20 | 25 | 12 | 12 | 20 | 12 | 7.5 | 85 Ohms | TOP=L2:L3=L2/L4:L6=L5/L7:BOTTOM=L7 |
| PE_RX1_DR14_P | PE_RX1_DR14-DIFF1 | PAIR | 6 | 6.5 | 5 | 10 | 5 | 50 | 20 | 25 | 12 | 12 | 20 | 12 | 7.5 | 85 Ohms | TOP=L2:L3=L2/L4:L6=L5/L7:BOTTOM=L7 |
| PE_RX1_DR14_P | PE_RX1_DR14-DIFF1 | PAIR | 7 | 6.5 | 5 | 10 | 5 | 50 | 20 | 25 | 12 | 12 | 20 | 12 | 7.5 | 85 Ohms | TOP=L2:L3=L2/L4:L6=L5/L7:BOTTOM=L7 |
| PE_RX1_DR14_P | PE_RX1_DR14-DIFF1 | PAIR | 8 | 6.88 | 5 | 10 | 5 | 50 | 20 | 36 | 12 | 12 | 20 | 12 | 5.13 | 85 Ohms | TOP=L2:L3=L2/L4:L6=L5/L7:BOTTOM=L7 |
| PE_RX1_DR1_N | PE_RX1_DR1-DIFF1 | PAIR | 1 | 6.88 | 5 | 10 | 5 | 50 | 20 | 36 | 12 | 12 | 20 | 12 | 5.13 | 85 Ohms | TOP=L2:L3=L2/L4:L6=L5/L7:BOTTOM=L7 |
| PE_RX1_DR1_N | PE_RX1_DR1-DIFF1 | PAIR | 2 | 6.5 | 5 | 10 | 5 | 50 | 20 | 25 | 12 | 12 | 20 | 12 | 7.5 | 85 Ohms | TOP=L2:L3=L2/L4:L6=L5/L7:BOTTOM=L7 |
| PE_RX1_DR1_N | PE_RX1_DR1-DIFF1 | PAIR | 3 | 6.5 | 5 | 10 | 5 | 50 | 20 | 25 | 12 | 12 | 20 | 12 | 7.5 | 85 Ohms | TOP=L2:L3=L2/L4:L6=L5/L7:BOTTOM=L7 |
| PE_RX1_DR1_N | PE_RX1_DR1-DIFF1 | PAIR | 4 | 6.5 | 5 | 10 | 5 | 50 | 20 | 25 | 12 | 12 | 20 | 12 | 7.5 | 85 Ohms | TOP=L2:L3=L2/L4:L6=L5/L7:BOTTOM=L7 |
| PE_RX1_DR1_N | PE_RX1_DR1-DIFF1 | PAIR | 5 | 6.5 | 5 | 10 | 5 | 50 | 20 | 25 | 12 | 12 | 20 | 12 | 7.5 | 85 Ohms | TOP=L2:L3=L2/L4:L6=L5/L7:BOTTOM=L7 |
| PE_RX1_DR1_N | PE_RX1_DR1-DIFF1 | PAIR | 6 | 6.5 | 5 | 10 | 5 | 50 | 20 | 25 | 12 | 12 | 20 | 12 | 7.5 | 85 Ohms | TOP=L2:L3=L2/L4:L6=L5/L7:BOTTOM=L7 |
| PE_RX1_DR1_N | PE_RX1_DR1-DIFF1 | PAIR | 7 | 6.5 | 5 | 10 | 5 | 50 | 20 | 25 | 12 | 12 | 20 | 12 | 7.5 | 85 Ohms | TOP=L2:L3=L2/L4:L6=L5/L7:BOTTOM=L7 |
| PE_RX1_DR1_N | PE_RX1_DR1-DIFF1 | PAIR | 8 | 6.88 | 5 | 10 | 5 | 50 | 20 | 36 | 12 | 12 | 20 | 12 | 5.13 | 85 Ohms | TOP=L2:L3=L2/L4:L6=L5/L7:BOTTOM=L7 |
| PE_RX1_DR1_P | PE_RX1_DR1-DIFF1 | PAIR | 1 | 6.88 | 5 | 10 | 5 | 50 | 20 | 36 | 12 | 12 | 20 | 12 | 5.13 | 85 Ohms | TOP=L2:L3=L2/L4:L6=L5/L7:BOTTOM=L7 |
| PE_RX1_DR1_P | PE_RX1_DR1-DIFF1 | PAIR | 2 | 6.5 | 5 | 10 | 5 | 50 | 20 | 25 | 12 | 12 | 20 | 12 | 7.5 | 85 Ohms | TOP=L2:L3=L2/L4:L6=L5/L7:BOTTOM=L7 |
| PE_RX1_DR1_P | PE_RX1_DR1-DIFF1 | PAIR | 3 | 6.5 | 5 | 10 | 5 | 50 | 20 | 25 | 12 | 12 | 20 | 12 | 7.5 | 85 Ohms | TOP=L2:L3=L2/L4:L6=L5/L7:BOTTOM=L7 |
| PE_RX1_DR1_P | PE_RX1_DR1-DIFF1 | PAIR | 4 | 6.5 | 5 | 10 | 5 | 50 | 20 | 25 | 12 | 12 | 20 | 12 | 7.5 | 85 Ohms | TOP=L2:L3=L2/L4:L6=L5/L7:BOTTOM=L7 |
| PE_RX1_DR1_P | PE_RX1_DR1-DIFF1 | PAIR | 5 | 6.5 | 5 | 10 | 5 | 50 | 20 | 25 | 12 | 12 | 20 | 12 | 7.5 | 85 Ohms | TOP=L2:L3=L2/L4:L6=L5/L7:BOTTOM=L7 |
| PE_RX1_DR1_P | PE_RX1_DR1-DIFF1 | PAIR | 6 | 6.5 | 5 | 10 | 5 | 50 | 20 | 25 | 12 | 12 | 20 | 12 | 7.5 | 85 Ohms | TOP=L2:L3=L2/L4:L6=L5/L7:BOTTOM=L7 |
| PE_RX1_DR1_P | PE_RX1_DR1-DIFF1 | PAIR | 7 | 6.5 | 5 | 10 | 5 | 50 | 20 | 25 | 12 | 12 | 20 | 12 | 7.5 | 85 Ohms | TOP=L2:L3=L2/L4:L6=L5/L7:BOTTOM=L7 |
| PE_RX1_DR1_P | PE_RX1_DR1-DIFF1 | PAIR | 8 | 6.88 | 5 | 10 | 5 | 50 | 20 | 36 | 12 | 12 | 20 | 12 | 5.13 | 85 Ohms | TOP=L2:L3=L2/L4:L6=L5/L7:BOTTOM=L7 |
| PE_RX1_DR2_N | PE_RX1_DR2-DIFF1 | PAIR | 1 | 6.88 | 5 | 10 | 5 | 50 | 20 | 36 | 12 | 12 | 20 | 12 | 5.13 | 85 Ohms | TOP=L2:L3=L2/L4:L6=L5/L7:BOTTOM=L7 |
| PE_RX1_DR2_N | PE_RX1_DR2-DIFF1 | PAIR | 2 | 6.5 | 5 | 10 | 5 | 50 | 20 | 25 | 12 | 12 | 20 | 12 | 7.5 | 85 Ohms | TOP=L2:L3=L2/L4:L6=L5/L7:BOTTOM=L7 |
| PE_RX1_DR2_N | PE_RX1_DR2-DIFF1 | PAIR | 3 | 6.5 | 5 | 10 | 5 | 50 | 20 | 25 | 12 | 12 | 20 | 12 | 7.5 | 85 Ohms | TOP=L2:L3=L2/L4:L6=L5/L7:BOTTOM=L7 |
| PE_RX1_DR2_N | PE_RX1_DR2-DIFF1 | PAIR | 4 | 6.5 | 5 | 10 | 5 | 50 | 20 | 25 | 12 | 12 | 20 | 12 | 7.5 | 85 Ohms | TOP=L2:L3=L2/L4:L6=L5/L7:BOTTOM=L7 |
| PE_RX1_DR2_N | PE_RX1_DR2-DIFF1 | PAIR | 5 | 6.5 | 5 | 10 | 5 | 50 | 20 | 25 | 12 | 12 | 20 | 12 | 7.5 | 85 Ohms | TOP=L2:L3=L2/L4:L6=L5/L7:BOTTOM=L7 |
| PE_RX1_DR2_N | PE_RX1_DR2-DIFF1 | PAIR | 6 | 6.5 | 5 | 10 | 5 | 50 | 20 | 25 | 12 | 12 | 20 | 12 | 7.5 | 85 Ohms | TOP=L2:L3=L2/L4:L6=L5/L7:BOTTOM=L7 |
| PE_RX1_DR2_N | PE_RX1_DR2-DIFF1 | PAIR | 7 | 6.5 | 5 | 10 | 5 | 50 | 20 | 25 | 12 | 12 | 20 | 12 | 7.5 | 85 Ohms | TOP=L2:L3=L2/L4:L6=L5/L7:BOTTOM=L7 |
| PE_RX1_DR2_N | PE_RX1_DR2-DIFF1 | PAIR | 8 | 6.88 | 5 | 10 | 5 | 50 | 20 | 36 | 12 | 12 | 20 | 12 | 5.13 | 85 Ohms | TOP=L2:L3=L2/L4:L6=L5/L7:BOTTOM=L7 |
| PE_RX1_DR2_P | PE_RX1_DR2-DIFF1 | PAIR | 1 | 6.88 | 5 | 10 | 5 | 50 | 20 | 36 | 12 | 12 | 20 | 12 | 5.13 | 85 Ohms | TOP=L2:L3=L2/L4:L6=L5/L7:BOTTOM=L7 |
| PE_RX1_DR2_P | PE_RX1_DR2-DIFF1 | PAIR | 2 | 6.5 | 5 | 10 | 5 | 50 | 20 | 25 | 12 | 12 | 20 | 12 | 7.5 | 85 Ohms | TOP=L2:L3=L2/L4:L6=L5/L7:BOTTOM=L7 |
| PE_RX1_DR2_P | PE_RX1_DR2-DIFF1 | PAIR | 3 | 6.5 | 5 | 10 | 5 | 50 | 20 | 25 | 12 | 12 | 20 | 12 | 7.5 | 85 Ohms | TOP=L2:L3=L2/L4:L6=L5/L7:BOTTOM=L7 |
| PE_RX1_DR2_P | PE_RX1_DR2-DIFF1 | PAIR | 4 | 6.5 | 5 | 10 | 5 | 50 | 20 | 25 | 12 | 12 | 20 | 12 | 7.5 | 85 Ohms | TOP=L2:L3=L2/L4:L6=L5/L7:BOTTOM=L7 |
| PE_RX1_DR2_P | PE_RX1_DR2-DIFF1 | PAIR | 5 | 6.5 | 5 | 10 | 5 | 50 | 20 | 25 | 12 | 12 | 20 | 12 | 7.5 | 85 Ohms | TOP=L2:L3=L2/L4:L6=L5/L7:BOTTOM=L7 |
| PE_RX1_DR2_P | PE_RX1_DR2-DIFF1 | PAIR | 6 | 6.5 | 5 | 10 | 5 | 50 | 20 | 25 | 12 | 12 | 20 | 12 | 7.5 | 85 Ohms | TOP=L2:L3=L2/L4:L6=L5/L7:BOTTOM=L7 |
| PE_RX1_DR2_P | PE_RX1_DR2-DIFF1 | PAIR | 7 | 6.5 | 5 | 10 | 5 | 50 | 20 | 25 | 12 | 12 | 20 | 12 | 7.5 | 85 Ohms | TOP=L2:L3=L2/L4:L6=L5/L7:BOTTOM=L7 |
| PE_RX1_DR2_P | PE_RX1_DR2-DIFF1 | PAIR | 8 | 6.88 | 5 | 10 | 5 | 50 | 20 | 36 | 12 | 12 | 20 | 12 | 5.13 | 85 Ohms | TOP=L2:L3=L2/L4:L6=L5/L7:BOTTOM=L7 |
| PE_RX1_DR3_N | PE_RX1_DR3-DIFF1 | PAIR | 1 | 6.88 | 5 | 10 | 5 | 50 | 20 | 36 | 12 | 12 | 20 | 12 | 5.13 | 85 Ohms | TOP=L2:L3=L2/L4:L6=L5/L7:BOTTOM=L7 |
| PE_RX1_DR3_N | PE_RX1_DR3-DIFF1 | PAIR | 2 | 6.5 | 5 | 10 | 5 | 50 | 20 | 25 | 12 | 12 | 20 | 12 | 7.5 | 85 Ohms | TOP=L2:L3=L2/L4:L6=L5/L7:BOTTOM=L7 |
| PE_RX1_DR3_N | PE_RX1_DR3-DIFF1 | PAIR | 3 | 6.5 | 5 | 10 | 5 | 50 | 20 | 25 | 12 | 12 | 20 | 12 | 7.5 | 85 Ohms | TOP=L2:L3=L2/L4:L6=L5/L7:BOTTOM=L7 |
| PE_RX1_DR3_N | PE_RX1_DR3-DIFF1 | PAIR | 4 | 6.5 | 5 | 10 | 5 | 50 | 20 | 25 | 12 | 12 | 20 | 12 | 7.5 | 85 Ohms | TOP=L2:L3=L2/L4:L6=L5/L7:BOTTOM=L7 |
| PE_RX1_DR3_N | PE_RX1_DR3-DIFF1 | PAIR | 5 | 6.5 | 5 | 10 | 5 | 50 | 20 | 25 | 12 | 12 | 20 | 12 | 7.5 | 85 Ohms | TOP=L2:L3=L2/L4:L6=L5/L7:BOTTOM=L7 |
| PE_RX1_DR3_N | PE_RX1_DR3-DIFF1 | PAIR | 6 | 6.5 | 5 | 10 | 5 | 50 | 20 | 25 | 12 | 12 | 20 | 12 | 7.5 | 85 Ohms | TOP=L2:L3=L2/L4:L6=L5/L7:BOTTOM=L7 |
| PE_RX1_DR3_N | PE_RX1_DR3-DIFF1 | PAIR | 7 | 6.5 | 5 | 10 | 5 | 50 | 20 | 25 | 12 | 12 | 20 | 12 | 7.5 | 85 Ohms | TOP=L2:L3=L2/L4:L6=L5/L7:BOTTOM=L7 |
| PE_RX1_DR3_N | PE_RX1_DR3-DIFF1 | PAIR | 8 | 6.88 | 5 | 10 | 5 | 50 | 20 | 36 | 12 | 12 | 20 | 12 | 5.13 | 85 Ohms | TOP=L2:L3=L2/L4:L6=L5/L7:BOTTOM=L7 |
| PE_RX1_DR3_P | PE_RX1_DR3-DIFF1 | PAIR | 1 | 6.88 | 5 | 10 | 5 | 50 | 20 | 36 | 12 | 12 | 20 | 12 | 5.13 | 85 Ohms | TOP=L2:L3=L2/L4:L6=L5/L7:BOTTOM=L7 |
| PE_RX1_DR3_P | PE_RX1_DR3-DIFF1 | PAIR | 2 | 6.5 | 5 | 10 | 5 | 50 | 20 | 25 | 12 | 12 | 20 | 12 | 7.5 | 85 Ohms | TOP=L2:L3=L2/L4:L6=L5/L7:BOTTOM=L7 |
| PE_RX1_DR3_P | PE_RX1_DR3-DIFF1 | PAIR | 3 | 6.5 | 5 | 10 | 5 | 50 | 20 | 25 | 12 | 12 | 20 | 12 | 7.5 | 85 Ohms | TOP=L2:L3=L2/L4:L6=L5/L7:BOTTOM=L7 |
| PE_RX1_DR3_P | PE_RX1_DR3-DIFF1 | PAIR | 4 | 6.5 | 5 | 10 | 5 | 50 | 20 | 25 | 12 | 12 | 20 | 12 | 7.5 | 85 Ohms | TOP=L2:L3=L2/L4:L6=L5/L7:BOTTOM=L7 |
| PE_RX1_DR3_P | PE_RX1_DR3-DIFF1 | PAIR | 5 | 6.5 | 5 | 10 | 5 | 50 | 20 | 25 | 12 | 12 | 20 | 12 | 7.5 | 85 Ohms | TOP=L2:L3=L2/L4:L6=L5/L7:BOTTOM=L7 |
| PE_RX1_DR3_P | PE_RX1_DR3-DIFF1 | PAIR | 6 | 6.5 | 5 | 10 | 5 | 50 | 20 | 25 | 12 | 12 | 20 | 12 | 7.5 | 85 Ohms | TOP=L2:L3=L2/L4:L6=L5/L7:BOTTOM=L7 |
| PE_RX1_DR3_P | PE_RX1_DR3-DIFF1 | PAIR | 7 | 6.5 | 5 | 10 | 5 | 50 | 20 | 25 | 12 | 12 | 20 | 12 | 7.5 | 85 Ohms | TOP=L2:L3=L2/L4:L6=L5/L7:BOTTOM=L7 |
| PE_RX1_DR3_P | PE_RX1_DR3-DIFF1 | PAIR | 8 | 6.88 | 5 | 10 | 5 | 50 | 20 | 36 | 12 | 12 | 20 | 12 | 5.13 | 85 Ohms | TOP=L2:L3=L2/L4:L6=L5/L7:BOTTOM=L7 |
| PE_RX1_DR4_N | PE_RX1_DR4-DIFF1 | PAIR | 1 | 6.88 | 5 | 10 | 5 | 50 | 20 | 36 | 12 | 12 | 20 | 12 | 5.13 | 85 Ohms | TOP=L2:L3=L2/L4:L6=L5/L7:BOTTOM=L7 |
| PE_RX1_DR4_N | PE_RX1_DR4-DIFF1 | PAIR | 2 | 6.5 | 5 | 10 | 5 | 50 | 20 | 25 | 12 | 12 | 20 | 12 | 7.5 | 85 Ohms | TOP=L2:L3=L2/L4:L6=L5/L7:BOTTOM=L7 |
| PE_RX1_DR4_N | PE_RX1_DR4-DIFF1 | PAIR | 3 | 6.5 | 5 | 10 | 5 | 50 | 20 | 25 | 12 | 12 | 20 | 12 | 7.5 | 85 Ohms | TOP=L2:L3=L2/L4:L6=L5/L7:BOTTOM=L7 |
| PE_RX1_DR4_N | PE_RX1_DR4-DIFF1 | PAIR | 4 | 6.5 | 5 | 10 | 5 | 50 | 20 | 25 | 12 | 12 | 20 | 12 | 7.5 | 85 Ohms | TOP=L2:L3=L2/L4:L6=L5/L7:BOTTOM=L7 |
| PE_RX1_DR4_N | PE_RX1_DR4-DIFF1 | PAIR | 5 | 6.5 | 5 | 10 | 5 | 50 | 20 | 25 | 12 | 12 | 20 | 12 | 7.5 | 85 Ohms | TOP=L2:L3=L2/L4:L6=L5/L7:BOTTOM=L7 |
| PE_RX1_DR4_N | PE_RX1_DR4-DIFF1 | PAIR | 6 | 6.5 | 5 | 10 | 5 | 50 | 20 | 25 | 12 | 12 | 20 | 12 | 7.5 | 85 Ohms | TOP=L2:L3=L2/L4:L6=L5/L7:BOTTOM=L7 |
| PE_RX1_DR4_N | PE_RX1_DR4-DIFF1 | PAIR | 7 | 6.5 | 5 | 10 | 5 | 50 | 20 | 25 | 12 | 12 | 20 | 12 | 7.5 | 85 Ohms | TOP=L2:L3=L2/L4:L6=L5/L7:BOTTOM=L7 |
| PE_RX1_DR4_N | PE_RX1_DR4-DIFF1 | PAIR | 8 | 6.88 | 5 | 10 | 5 | 50 | 20 | 36 | 12 | 12 | 20 | 12 | 5.13 | 85 Ohms | TOP=L2:L3=L2/L4:L6=L5/L7:BOTTOM=L7 |
| PE_RX1_DR4_P | PE_RX1_DR4-DIFF1 | PAIR | 1 | 6.88 | 5 | 10 | 5 | 50 | 20 | 36 | 12 | 12 | 20 | 12 | 5.13 | 85 Ohms | TOP=L2:L3=L2/L4:L6=L5/L7:BOTTOM=L7 |
| PE_RX1_DR4_P | PE_RX1_DR4-DIFF1 | PAIR | 2 | 6.5 | 5 | 10 | 5 | 50 | 20 | 25 | 12 | 12 | 20 | 12 | 7.5 | 85 Ohms | TOP=L2:L3=L2/L4:L6=L5/L7:BOTTOM=L7 |
| PE_RX1_DR4_P | PE_RX1_DR4-DIFF1 | PAIR | 3 | 6.5 | 5 | 10 | 5 | 50 | 20 | 25 | 12 | 12 | 20 | 12 | 7.5 | 85 Ohms | TOP=L2:L3=L2/L4:L6=L5/L7:BOTTOM=L7 |
| PE_RX1_DR4_P | PE_RX1_DR4-DIFF1 | PAIR | 4 | 6.5 | 5 | 10 | 5 | 50 | 20 | 25 | 12 | 12 | 20 | 12 | 7.5 | 85 Ohms | TOP=L2:L3=L2/L4:L6=L5/L7:BOTTOM=L7 |
| PE_RX1_DR4_P | PE_RX1_DR4-DIFF1 | PAIR | 5 | 6.5 | 5 | 10 | 5 | 50 | 20 | 25 | 12 | 12 | 20 | 12 | 7.5 | 85 Ohms | TOP=L2:L3=L2/L4:L6=L5/L7:BOTTOM=L7 |
| PE_RX1_DR4_P | PE_RX1_DR4-DIFF1 | PAIR | 6 | 6.5 | 5 | 10 | 5 | 50 | 20 | 25 | 12 | 12 | 20 | 12 | 7.5 | 85 Ohms | TOP=L2:L3=L2/L4:L6=L5/L7:BOTTOM=L7 |
| PE_RX1_DR4_P | PE_RX1_DR4-DIFF1 | PAIR | 7 | 6.5 | 5 | 10 | 5 | 50 | 20 | 25 | 12 | 12 | 20 | 12 | 7.5 | 85 Ohms | TOP=L2:L3=L2/L4:L6=L5/L7:BOTTOM=L7 |
| PE_RX1_DR4_P | PE_RX1_DR4-DIFF1 | PAIR | 8 | 6.88 | 5 | 10 | 5 | 50 | 20 | 36 | 12 | 12 | 20 | 12 | 5.13 | 85 Ohms | TOP=L2:L3=L2/L4:L6=L5/L7:BOTTOM=L7 |
| PE_RX1_DR5_N | PE_RX1_DR5-DIFF1 | PAIR | 1 | 6.88 | 5 | 10 | 5 | 50 | 20 | 36 | 12 | 12 | 20 | 12 | 5.13 | 85 Ohms | TOP=L2:L3=L2/L4:L6=L5/L7:BOTTOM=L7 |
| PE_RX1_DR5_N | PE_RX1_DR5-DIFF1 | PAIR | 2 | 6.5 | 5 | 10 | 5 | 50 | 20 | 25 | 12 | 12 | 20 | 12 | 7.5 | 85 Ohms | TOP=L2:L3=L2/L4:L6=L5/L7:BOTTOM=L7 |
| PE_RX1_DR5_N | PE_RX1_DR5-DIFF1 | PAIR | 3 | 6.5 | 5 | 10 | 5 | 50 | 20 | 25 | 12 | 12 | 20 | 12 | 7.5 | 85 Ohms | TOP=L2:L3=L2/L4:L6=L5/L7:BOTTOM=L7 |
| PE_RX1_DR5_N | PE_RX1_DR5-DIFF1 | PAIR | 4 | 6.5 | 5 | 10 | 5 | 50 | 20 | 25 | 12 | 12 | 20 | 12 | 7.5 | 85 Ohms | TOP=L2:L3=L2/L4:L6=L5/L7:BOTTOM=L7 |
| PE_RX1_DR5_N | PE_RX1_DR5-DIFF1 | PAIR | 5 | 6.5 | 5 | 10 | 5 | 50 | 20 | 25 | 12 | 12 | 20 | 12 | 7.5 | 85 Ohms | TOP=L2:L3=L2/L4:L6=L5/L7:BOTTOM=L7 |
| PE_RX1_DR5_N | PE_RX1_DR5-DIFF1 | PAIR | 6 | 6.5 | 5 | 10 | 5 | 50 | 20 | 25 | 12 | 12 | 20 | 12 | 7.5 | 85 Ohms | TOP=L2:L3=L2/L4:L6=L5/L7:BOTTOM=L7 |
| PE_RX1_DR5_N | PE_RX1_DR5-DIFF1 | PAIR | 7 | 6.5 | 5 | 10 | 5 | 50 | 20 | 25 | 12 | 12 | 20 | 12 | 7.5 | 85 Ohms | TOP=L2:L3=L2/L4:L6=L5/L7:BOTTOM=L7 |
| PE_RX1_DR5_N | PE_RX1_DR5-DIFF1 | PAIR | 8 | 6.88 | 5 | 10 | 5 | 50 | 20 | 36 | 12 | 12 | 20 | 12 | 5.13 | 85 Ohms | TOP=L2:L3=L2/L4:L6=L5/L7:BOTTOM=L7 |
| PE_RX1_DR5_P | PE_RX1_DR5-DIFF1 | PAIR | 1 | 6.88 | 5 | 10 | 5 | 50 | 20 | 36 | 12 | 12 | 20 | 12 | 5.13 | 85 Ohms | TOP=L2:L3=L2/L4:L6=L5/L7:BOTTOM=L7 |
| PE_RX1_DR5_P | PE_RX1_DR5-DIFF1 | PAIR | 2 | 6.5 | 5 | 10 | 5 | 50 | 20 | 25 | 12 | 12 | 20 | 12 | 7.5 | 85 Ohms | TOP=L2:L3=L2/L4:L6=L5/L7:BOTTOM=L7 |
| PE_RX1_DR5_P | PE_RX1_DR5-DIFF1 | PAIR | 3 | 6.5 | 5 | 10 | 5 | 50 | 20 | 25 | 12 | 12 | 20 | 12 | 7.5 | 85 Ohms | TOP=L2:L3=L2/L4:L6=L5/L7:BOTTOM=L7 |
| PE_RX1_DR5_P | PE_RX1_DR5-DIFF1 | PAIR | 4 | 6.5 | 5 | 10 | 5 | 50 | 20 | 25 | 12 | 12 | 20 | 12 | 7.5 | 85 Ohms | TOP=L2:L3=L2/L4:L6=L5/L7:BOTTOM=L7 |
| PE_RX1_DR5_P | PE_RX1_DR5-DIFF1 | PAIR | 5 | 6.5 | 5 | 10 | 5 | 50 | 20 | 25 | 12 | 12 | 20 | 12 | 7.5 | 85 Ohms | TOP=L2:L3=L2/L4:L6=L5/L7:BOTTOM=L7 |
| PE_RX1_DR5_P | PE_RX1_DR5-DIFF1 | PAIR | 6 | 6.5 | 5 | 10 | 5 | 50 | 20 | 25 | 12 | 12 | 20 | 12 | 7.5 | 85 Ohms | TOP=L2:L3=L2/L4:L6=L5/L7:BOTTOM=L7 |
| PE_RX1_DR5_P | PE_RX1_DR5-DIFF1 | PAIR | 7 | 6.5 | 5 | 10 | 5 | 50 | 20 | 25 | 12 | 12 | 20 | 12 | 7.5 | 85 Ohms | TOP=L2:L3=L2/L4:L6=L5/L7:BOTTOM=L7 |
| PE_RX1_DR5_P | PE_RX1_DR5-DIFF1 | PAIR | 8 | 6.88 | 5 | 10 | 5 | 50 | 20 | 36 | 12 | 12 | 20 | 12 | 5.13 | 85 Ohms | TOP=L2:L3=L2/L4:L6=L5/L7:BOTTOM=L7 |
| PE_RX1_DR6_N | PE_RX1_DR6-DIFF1 | PAIR | 1 | 6.88 | 5 | 10 | 5 | 50 | 20 | 36 | 12 | 12 | 20 | 12 | 5.13 | 85 Ohms | TOP=L2:L3=L2/L4:L6=L5/L7:BOTTOM=L7 |
| PE_RX1_DR6_N | PE_RX1_DR6-DIFF1 | PAIR | 2 | 6.5 | 5 | 10 | 5 | 50 | 20 | 25 | 12 | 12 | 20 | 12 | 7.5 | 85 Ohms | TOP=L2:L3=L2/L4:L6=L5/L7:BOTTOM=L7 |
| PE_RX1_DR6_N | PE_RX1_DR6-DIFF1 | PAIR | 3 | 6.5 | 5 | 10 | 5 | 50 | 20 | 25 | 12 | 12 | 20 | 12 | 7.5 | 85 Ohms | TOP=L2:L3=L2/L4:L6=L5/L7:BOTTOM=L7 |
| PE_RX1_DR6_N | PE_RX1_DR6-DIFF1 | PAIR | 4 | 6.5 | 5 | 10 | 5 | 50 | 20 | 25 | 12 | 12 | 20 | 12 | 7.5 | 85 Ohms | TOP=L2:L3=L2/L4:L6=L5/L7:BOTTOM=L7 |
| PE_RX1_DR6_N | PE_RX1_DR6-DIFF1 | PAIR | 5 | 6.5 | 5 | 10 | 5 | 50 | 20 | 25 | 12 | 12 | 20 | 12 | 7.5 | 85 Ohms | TOP=L2:L3=L2/L4:L6=L5/L7:BOTTOM=L7 |
| PE_RX1_DR6_N | PE_RX1_DR6-DIFF1 | PAIR | 6 | 6.5 | 5 | 10 | 5 | 50 | 20 | 25 | 12 | 12 | 20 | 12 | 7.5 | 85 Ohms | TOP=L2:L3=L2/L4:L6=L5/L7:BOTTOM=L7 |
| PE_RX1_DR6_N | PE_RX1_DR6-DIFF1 | PAIR | 7 | 6.5 | 5 | 10 | 5 | 50 | 20 | 25 | 12 | 12 | 20 | 12 | 7.5 | 85 Ohms | TOP=L2:L3=L2/L4:L6=L5/L7:BOTTOM=L7 |
| PE_RX1_DR6_N | PE_RX1_DR6-DIFF1 | PAIR | 8 | 6.88 | 5 | 10 | 5 | 50 | 20 | 36 | 12 | 12 | 20 | 12 | 5.13 | 85 Ohms | TOP=L2:L3=L2/L4:L6=L5/L7:BOTTOM=L7 |
| PE_RX1_DR6_P | PE_RX1_DR6-DIFF1 | PAIR | 1 | 6.88 | 5 | 10 | 5 | 50 | 20 | 36 | 12 | 12 | 20 | 12 | 5.13 | 85 Ohms | TOP=L2:L3=L2/L4:L6=L5/L7:BOTTOM=L7 |
| PE_RX1_DR6_P | PE_RX1_DR6-DIFF1 | PAIR | 2 | 6.5 | 5 | 10 | 5 | 50 | 20 | 25 | 12 | 12 | 20 | 12 | 7.5 | 85 Ohms | TOP=L2:L3=L2/L4:L6=L5/L7:BOTTOM=L7 |
| PE_RX1_DR6_P | PE_RX1_DR6-DIFF1 | PAIR | 3 | 6.5 | 5 | 10 | 5 | 50 | 20 | 25 | 12 | 12 | 20 | 12 | 7.5 | 85 Ohms | TOP=L2:L3=L2/L4:L6=L5/L7:BOTTOM=L7 |
| PE_RX1_DR6_P | PE_RX1_DR6-DIFF1 | PAIR | 4 | 6.5 | 5 | 10 | 5 | 50 | 20 | 25 | 12 | 12 | 20 | 12 | 7.5 | 85 Ohms | TOP=L2:L3=L2/L4:L6=L5/L7:BOTTOM=L7 |
| PE_RX1_DR6_P | PE_RX1_DR6-DIFF1 | PAIR | 5 | 6.5 | 5 | 10 | 5 | 50 | 20 | 25 | 12 | 12 | 20 | 12 | 7.5 | 85 Ohms | TOP=L2:L3=L2/L4:L6=L5/L7:BOTTOM=L7 |
| PE_RX1_DR6_P | PE_RX1_DR6-DIFF1 | PAIR | 6 | 6.5 | 5 | 10 | 5 | 50 | 20 | 25 | 12 | 12 | 20 | 12 | 7.5 | 85 Ohms | TOP=L2:L3=L2/L4:L6=L5/L7:BOTTOM=L7 |
| PE_RX1_DR6_P | PE_RX1_DR6-DIFF1 | PAIR | 7 | 6.5 | 5 | 10 | 5 | 50 | 20 | 25 | 12 | 12 | 20 | 12 | 7.5 | 85 Ohms | TOP=L2:L3=L2/L4:L6=L5/L7:BOTTOM=L7 |
| PE_RX1_DR6_P | PE_RX1_DR6-DIFF1 | PAIR | 8 | 6.88 | 5 | 10 | 5 | 50 | 20 | 36 | 12 | 12 | 20 | 12 | 5.13 | 85 Ohms | TOP=L2:L3=L2/L4:L6=L5/L7:BOTTOM=L7 |
| PE_RX1_DR7_N | PE_RX1_DR7-DIFF1 | PAIR | 1 | 6.88 | 5 | 10 | 5 | 50 | 20 | 36 | 12 | 12 | 20 | 12 | 5.13 | 85 Ohms | TOP=L2:L3=L2/L4:L6=L5/L7:BOTTOM=L7 |
| PE_RX1_DR7_N | PE_RX1_DR7-DIFF1 | PAIR | 2 | 6.5 | 5 | 10 | 5 | 50 | 20 | 25 | 12 | 12 | 20 | 12 | 7.5 | 85 Ohms | TOP=L2:L3=L2/L4:L6=L5/L7:BOTTOM=L7 |
| PE_RX1_DR7_N | PE_RX1_DR7-DIFF1 | PAIR | 3 | 6.5 | 5 | 10 | 5 | 50 | 20 | 25 | 12 | 12 | 20 | 12 | 7.5 | 85 Ohms | TOP=L2:L3=L2/L4:L6=L5/L7:BOTTOM=L7 |
| PE_RX1_DR7_N | PE_RX1_DR7-DIFF1 | PAIR | 4 | 6.5 | 5 | 10 | 5 | 50 | 20 | 25 | 12 | 12 | 20 | 12 | 7.5 | 85 Ohms | TOP=L2:L3=L2/L4:L6=L5/L7:BOTTOM=L7 |
| PE_RX1_DR7_N | PE_RX1_DR7-DIFF1 | PAIR | 5 | 6.5 | 5 | 10 | 5 | 50 | 20 | 25 | 12 | 12 | 20 | 12 | 7.5 | 85 Ohms | TOP=L2:L3=L2/L4:L6=L5/L7:BOTTOM=L7 |
| PE_RX1_DR7_N | PE_RX1_DR7-DIFF1 | PAIR | 6 | 6.5 | 5 | 10 | 5 | 50 | 20 | 25 | 12 | 12 | 20 | 12 | 7.5 | 85 Ohms | TOP=L2:L3=L2/L4:L6=L5/L7:BOTTOM=L7 |
| PE_RX1_DR7_N | PE_RX1_DR7-DIFF1 | PAIR | 7 | 6.5 | 5 | 10 | 5 | 50 | 20 | 25 | 12 | 12 | 20 | 12 | 7.5 | 85 Ohms | TOP=L2:L3=L2/L4:L6=L5/L7:BOTTOM=L7 |
| PE_RX1_DR7_N | PE_RX1_DR7-DIFF1 | PAIR | 8 | 6.88 | 5 | 10 | 5 | 50 | 20 | 36 | 12 | 12 | 20 | 12 | 5.13 | 85 Ohms | TOP=L2:L3=L2/L4:L6=L5/L7:BOTTOM=L7 |
| PE_RX1_DR7_P | PE_RX1_DR7-DIFF1 | PAIR | 1 | 6.88 | 5 | 10 | 5 | 50 | 20 | 36 | 12 | 12 | 20 | 12 | 5.13 | 85 Ohms | TOP=L2:L3=L2/L4:L6=L5/L7:BOTTOM=L7 |
| PE_RX1_DR7_P | PE_RX1_DR7-DIFF1 | PAIR | 2 | 6.5 | 5 | 10 | 5 | 50 | 20 | 25 | 12 | 12 | 20 | 12 | 7.5 | 85 Ohms | TOP=L2:L3=L2/L4:L6=L5/L7:BOTTOM=L7 |
| PE_RX1_DR7_P | PE_RX1_DR7-DIFF1 | PAIR | 3 | 6.5 | 5 | 10 | 5 | 50 | 20 | 25 | 12 | 12 | 20 | 12 | 7.5 | 85 Ohms | TOP=L2:L3=L2/L4:L6=L5/L7:BOTTOM=L7 |
| PE_RX1_DR7_P | PE_RX1_DR7-DIFF1 | PAIR | 4 | 6.5 | 5 | 10 | 5 | 50 | 20 | 25 | 12 | 12 | 20 | 12 | 7.5 | 85 Ohms | TOP=L2:L3=L2/L4:L6=L5/L7:BOTTOM=L7 |
| PE_RX1_DR7_P | PE_RX1_DR7-DIFF1 | PAIR | 5 | 6.5 | 5 | 10 | 5 | 50 | 20 | 25 | 12 | 12 | 20 | 12 | 7.5 | 85 Ohms | TOP=L2:L3=L2/L4:L6=L5/L7:BOTTOM=L7 |
| PE_RX1_DR7_P | PE_RX1_DR7-DIFF1 | PAIR | 6 | 6.5 | 5 | 10 | 5 | 50 | 20 | 25 | 12 | 12 | 20 | 12 | 7.5 | 85 Ohms | TOP=L2:L3=L2/L4:L6=L5/L7:BOTTOM=L7 |
| PE_RX1_DR7_P | PE_RX1_DR7-DIFF1 | PAIR | 7 | 6.5 | 5 | 10 | 5 | 50 | 20 | 25 | 12 | 12 | 20 | 12 | 7.5 | 85 Ohms | TOP=L2:L3=L2/L4:L6=L5/L7:BOTTOM=L7 |
| PE_RX1_DR7_P | PE_RX1_DR7-DIFF1 | PAIR | 8 | 6.88 | 5 | 10 | 5 | 50 | 20 | 36 | 12 | 12 | 20 | 12 | 5.13 | 85 Ohms | TOP=L2:L3=L2/L4:L6=L5/L7:BOTTOM=L7 |
| PE_RX1_DR8_N | PE_RX1_DR8-DIFF1 | PAIR | 1 | 6.88 | 5 | 10 | 5 | 50 | 20 | 36 | 12 | 12 | 20 | 12 | 5.13 | 85 Ohms | TOP=L2:L3=L2/L4:L6=L5/L7:BOTTOM=L7 |
| PE_RX1_DR8_N | PE_RX1_DR8-DIFF1 | PAIR | 2 | 6.5 | 5 | 10 | 5 | 50 | 20 | 25 | 12 | 12 | 20 | 12 | 7.5 | 85 Ohms | TOP=L2:L3=L2/L4:L6=L5/L7:BOTTOM=L7 |
| PE_RX1_DR8_N | PE_RX1_DR8-DIFF1 | PAIR | 3 | 6.5 | 5 | 10 | 5 | 50 | 20 | 25 | 12 | 12 | 20 | 12 | 7.5 | 85 Ohms | TOP=L2:L3=L2/L4:L6=L5/L7:BOTTOM=L7 |
| PE_RX1_DR8_N | PE_RX1_DR8-DIFF1 | PAIR | 4 | 6.5 | 5 | 10 | 5 | 50 | 20 | 25 | 12 | 12 | 20 | 12 | 7.5 | 85 Ohms | TOP=L2:L3=L2/L4:L6=L5/L7:BOTTOM=L7 |
| PE_RX1_DR8_N | PE_RX1_DR8-DIFF1 | PAIR | 5 | 6.5 | 5 | 10 | 5 | 50 | 20 | 25 | 12 | 12 | 20 | 12 | 7.5 | 85 Ohms | TOP=L2:L3=L2/L4:L6=L5/L7:BOTTOM=L7 |
| PE_RX1_DR8_N | PE_RX1_DR8-DIFF1 | PAIR | 6 | 6.5 | 5 | 10 | 5 | 50 | 20 | 25 | 12 | 12 | 20 | 12 | 7.5 | 85 Ohms | TOP=L2:L3=L2/L4:L6=L5/L7:BOTTOM=L7 |
| PE_RX1_DR8_N | PE_RX1_DR8-DIFF1 | PAIR | 7 | 6.5 | 5 | 10 | 5 | 50 | 20 | 25 | 12 | 12 | 20 | 12 | 7.5 | 85 Ohms | TOP=L2:L3=L2/L4:L6=L5/L7:BOTTOM=L7 |
| PE_RX1_DR8_N | PE_RX1_DR8-DIFF1 | PAIR | 8 | 6.88 | 5 | 10 | 5 | 50 | 20 | 36 | 12 | 12 | 20 | 12 | 5.13 | 85 Ohms | TOP=L2:L3=L2/L4:L6=L5/L7:BOTTOM=L7 |
| PE_RX1_DR8_P | PE_RX1_DR8-DIFF1 | PAIR | 1 | 6.88 | 5 | 10 | 5 | 50 | 20 | 36 | 12 | 12 | 20 | 12 | 5.13 | 85 Ohms | TOP=L2:L3=L2/L4:L6=L5/L7:BOTTOM=L7 |
| PE_RX1_DR8_P | PE_RX1_DR8-DIFF1 | PAIR | 2 | 6.5 | 5 | 10 | 5 | 50 | 20 | 25 | 12 | 12 | 20 | 12 | 7.5 | 85 Ohms | TOP=L2:L3=L2/L4:L6=L5/L7:BOTTOM=L7 |
| PE_RX1_DR8_P | PE_RX1_DR8-DIFF1 | PAIR | 3 | 6.5 | 5 | 10 | 5 | 50 | 20 | 25 | 12 | 12 | 20 | 12 | 7.5 | 85 Ohms | TOP=L2:L3=L2/L4:L6=L5/L7:BOTTOM=L7 |
| PE_RX1_DR8_P | PE_RX1_DR8-DIFF1 | PAIR | 4 | 6.5 | 5 | 10 | 5 | 50 | 20 | 25 | 12 | 12 | 20 | 12 | 7.5 | 85 Ohms | TOP=L2:L3=L2/L4:L6=L5/L7:BOTTOM=L7 |
| PE_RX1_DR8_P | PE_RX1_DR8-DIFF1 | PAIR | 5 | 6.5 | 5 | 10 | 5 | 50 | 20 | 25 | 12 | 12 | 20 | 12 | 7.5 | 85 Ohms | TOP=L2:L3=L2/L4:L6=L5/L7:BOTTOM=L7 |
| PE_RX1_DR8_P | PE_RX1_DR8-DIFF1 | PAIR | 6 | 6.5 | 5 | 10 | 5 | 50 | 20 | 25 | 12 | 12 | 20 | 12 | 7.5 | 85 Ohms | TOP=L2:L3=L2/L4:L6=L5/L7:BOTTOM=L7 |
| PE_RX1_DR8_P | PE_RX1_DR8-DIFF1 | PAIR | 7 | 6.5 | 5 | 10 | 5 | 50 | 20 | 25 | 12 | 12 | 20 | 12 | 7.5 | 85 Ohms | TOP=L2:L3=L2/L4:L6=L5/L7:BOTTOM=L7 |
| PE_RX1_DR8_P | PE_RX1_DR8-DIFF1 | PAIR | 8 | 6.88 | 5 | 10 | 5 | 50 | 20 | 36 | 12 | 12 | 20 | 12 | 5.13 | 85 Ohms | TOP=L2:L3=L2/L4:L6=L5/L7:BOTTOM=L7 |
| PE_RX1_DR9_N | PE_RX1_DR9-DIFF1 | PAIR | 1 | 6.88 | 5 | 10 | 5 | 50 | 20 | 36 | 12 | 12 | 20 | 12 | 5.13 | 85 Ohms | TOP=L2:L3=L2/L4:L6=L5/L7:BOTTOM=L7 |
| PE_RX1_DR9_N | PE_RX1_DR9-DIFF1 | PAIR | 2 | 6.5 | 5 | 10 | 5 | 50 | 20 | 25 | 12 | 12 | 20 | 12 | 7.5 | 85 Ohms | TOP=L2:L3=L2/L4:L6=L5/L7:BOTTOM=L7 |
| PE_RX1_DR9_N | PE_RX1_DR9-DIFF1 | PAIR | 3 | 6.5 | 5 | 10 | 5 | 50 | 20 | 25 | 12 | 12 | 20 | 12 | 7.5 | 85 Ohms | TOP=L2:L3=L2/L4:L6=L5/L7:BOTTOM=L7 |
| PE_RX1_DR9_N | PE_RX1_DR9-DIFF1 | PAIR | 4 | 6.5 | 5 | 10 | 5 | 50 | 20 | 25 | 12 | 12 | 20 | 12 | 7.5 | 85 Ohms | TOP=L2:L3=L2/L4:L6=L5/L7:BOTTOM=L7 |
| PE_RX1_DR9_N | PE_RX1_DR9-DIFF1 | PAIR | 5 | 6.5 | 5 | 10 | 5 | 50 | 20 | 25 | 12 | 12 | 20 | 12 | 7.5 | 85 Ohms | TOP=L2:L3=L2/L4:L6=L5/L7:BOTTOM=L7 |
| PE_RX1_DR9_N | PE_RX1_DR9-DIFF1 | PAIR | 6 | 6.5 | 5 | 10 | 5 | 50 | 20 | 25 | 12 | 12 | 20 | 12 | 7.5 | 85 Ohms | TOP=L2:L3=L2/L4:L6=L5/L7:BOTTOM=L7 |
| PE_RX1_DR9_N | PE_RX1_DR9-DIFF1 | PAIR | 7 | 6.5 | 5 | 10 | 5 | 50 | 20 | 25 | 12 | 12 | 20 | 12 | 7.5 | 85 Ohms | TOP=L2:L3=L2/L4:L6=L5/L7:BOTTOM=L7 |
| PE_RX1_DR9_N | PE_RX1_DR9-DIFF1 | PAIR | 8 | 6.88 | 5 | 10 | 5 | 50 | 20 | 36 | 12 | 12 | 20 | 12 | 5.13 | 85 Ohms | TOP=L2:L3=L2/L4:L6=L5/L7:BOTTOM=L7 |
| PE_RX1_DR9_P | PE_RX1_DR9-DIFF1 | PAIR | 1 | 6.88 | 5 | 10 | 5 | 50 | 20 | 36 | 12 | 12 | 20 | 12 | 5.13 | 85 Ohms | TOP=L2:L3=L2/L4:L6=L5/L7:BOTTOM=L7 |
| PE_RX1_DR9_P | PE_RX1_DR9-DIFF1 | PAIR | 2 | 6.5 | 5 | 10 | 5 | 50 | 20 | 25 | 12 | 12 | 20 | 12 | 7.5 | 85 Ohms | TOP=L2:L3=L2/L4:L6=L5/L7:BOTTOM=L7 |
| PE_RX1_DR9_P | PE_RX1_DR9-DIFF1 | PAIR | 3 | 6.5 | 5 | 10 | 5 | 50 | 20 | 25 | 12 | 12 | 20 | 12 | 7.5 | 85 Ohms | TOP=L2:L3=L2/L4:L6=L5/L7:BOTTOM=L7 |
| PE_RX1_DR9_P | PE_RX1_DR9-DIFF1 | PAIR | 4 | 6.5 | 5 | 10 | 5 | 50 | 20 | 25 | 12 | 12 | 20 | 12 | 7.5 | 85 Ohms | TOP=L2:L3=L2/L4:L6=L5/L7:BOTTOM=L7 |
| PE_RX1_DR9_P | PE_RX1_DR9-DIFF1 | PAIR | 5 | 6.5 | 5 | 10 | 5 | 50 | 20 | 25 | 12 | 12 | 20 | 12 | 7.5 | 85 Ohms | TOP=L2:L3=L2/L4:L6=L5/L7:BOTTOM=L7 |
| PE_RX1_DR9_P | PE_RX1_DR9-DIFF1 | PAIR | 6 | 6.5 | 5 | 10 | 5 | 50 | 20 | 25 | 12 | 12 | 20 | 12 | 7.5 | 85 Ohms | TOP=L2:L3=L2/L4:L6=L5/L7:BOTTOM=L7 |
| PE_RX1_DR9_P | PE_RX1_DR9-DIFF1 | PAIR | 7 | 6.5 | 5 | 10 | 5 | 50 | 20 | 25 | 12 | 12 | 20 | 12 | 7.5 | 85 Ohms | TOP=L2:L3=L2/L4:L6=L5/L7:BOTTOM=L7 |
| PE_RX1_DR9_P | PE_RX1_DR9-DIFF1 | PAIR | 8 | 6.88 | 5 | 10 | 5 | 50 | 20 | 36 | 12 | 12 | 20 | 12 | 5.13 | 85 Ohms | TOP=L2:L3=L2/L4:L6=L5/L7:BOTTOM=L7 |
| PE_RX2_DR0_N | PE_RX2_DR0-DIFF1 | PAIR | 1 | 6.88 | 5 | 10 | 5 | 50 | 20 | 36 | 12 | 12 | 20 | 12 | 5.13 | 85 Ohms | TOP=L2:L3=L2/L4:L6=L5/L7:BOTTOM=L7 |
| PE_RX2_DR0_N | PE_RX2_DR0-DIFF1 | PAIR | 2 | 6.5 | 5 | 10 | 5 | 50 | 20 | 25 | 12 | 12 | 20 | 12 | 7.5 | 85 Ohms | TOP=L2:L3=L2/L4:L6=L5/L7:BOTTOM=L7 |
| PE_RX2_DR0_N | PE_RX2_DR0-DIFF1 | PAIR | 3 | 6.5 | 5 | 10 | 5 | 50 | 20 | 25 | 12 | 12 | 20 | 12 | 7.5 | 85 Ohms | TOP=L2:L3=L2/L4:L6=L5/L7:BOTTOM=L7 |
| PE_RX2_DR0_N | PE_RX2_DR0-DIFF1 | PAIR | 4 | 6.5 | 5 | 10 | 5 | 50 | 20 | 25 | 12 | 12 | 20 | 12 | 7.5 | 85 Ohms | TOP=L2:L3=L2/L4:L6=L5/L7:BOTTOM=L7 |
| PE_RX2_DR0_N | PE_RX2_DR0-DIFF1 | PAIR | 5 | 6.5 | 5 | 10 | 5 | 50 | 20 | 25 | 12 | 12 | 20 | 12 | 7.5 | 85 Ohms | TOP=L2:L3=L2/L4:L6=L5/L7:BOTTOM=L7 |
| PE_RX2_DR0_N | PE_RX2_DR0-DIFF1 | PAIR | 6 | 6.5 | 5 | 10 | 5 | 50 | 20 | 25 | 12 | 12 | 20 | 12 | 7.5 | 85 Ohms | TOP=L2:L3=L2/L4:L6=L5/L7:BOTTOM=L7 |
| PE_RX2_DR0_N | PE_RX2_DR0-DIFF1 | PAIR | 7 | 6.5 | 5 | 10 | 5 | 50 | 20 | 25 | 12 | 12 | 20 | 12 | 7.5 | 85 Ohms | TOP=L2:L3=L2/L4:L6=L5/L7:BOTTOM=L7 |
| PE_RX2_DR0_N | PE_RX2_DR0-DIFF1 | PAIR | 8 | 6.88 | 5 | 10 | 5 | 50 | 20 | 36 | 12 | 12 | 20 | 12 | 5.13 | 85 Ohms | TOP=L2:L3=L2/L4:L6=L5/L7:BOTTOM=L7 |
| PE_RX2_DR0_P | PE_RX2_DR0-DIFF1 | PAIR | 1 | 6.88 | 5 | 10 | 5 | 50 | 20 | 36 | 12 | 12 | 20 | 12 | 5.13 | 85 Ohms | TOP=L2:L3=L2/L4:L6=L5/L7:BOTTOM=L7 |
| PE_RX2_DR0_P | PE_RX2_DR0-DIFF1 | PAIR | 2 | 6.5 | 5 | 10 | 5 | 50 | 20 | 25 | 12 | 12 | 20 | 12 | 7.5 | 85 Ohms | TOP=L2:L3=L2/L4:L6=L5/L7:BOTTOM=L7 |
| PE_RX2_DR0_P | PE_RX2_DR0-DIFF1 | PAIR | 3 | 6.5 | 5 | 10 | 5 | 50 | 20 | 25 | 12 | 12 | 20 | 12 | 7.5 | 85 Ohms | TOP=L2:L3=L2/L4:L6=L5/L7:BOTTOM=L7 |
| PE_RX2_DR0_P | PE_RX2_DR0-DIFF1 | PAIR | 4 | 6.5 | 5 | 10 | 5 | 50 | 20 | 25 | 12 | 12 | 20 | 12 | 7.5 | 85 Ohms | TOP=L2:L3=L2/L4:L6=L5/L7:BOTTOM=L7 |
| PE_RX2_DR0_P | PE_RX2_DR0-DIFF1 | PAIR | 5 | 6.5 | 5 | 10 | 5 | 50 | 20 | 25 | 12 | 12 | 20 | 12 | 7.5 | 85 Ohms | TOP=L2:L3=L2/L4:L6=L5/L7:BOTTOM=L7 |
| PE_RX2_DR0_P | PE_RX2_DR0-DIFF1 | PAIR | 6 | 6.5 | 5 | 10 | 5 | 50 | 20 | 25 | 12 | 12 | 20 | 12 | 7.5 | 85 Ohms | TOP=L2:L3=L2/L4:L6=L5/L7:BOTTOM=L7 |
| PE_RX2_DR0_P | PE_RX2_DR0-DIFF1 | PAIR | 7 | 6.5 | 5 | 10 | 5 | 50 | 20 | 25 | 12 | 12 | 20 | 12 | 7.5 | 85 Ohms | TOP=L2:L3=L2/L4:L6=L5/L7:BOTTOM=L7 |
| PE_RX2_DR0_P | PE_RX2_DR0-DIFF1 | PAIR | 8 | 6.88 | 5 | 10 | 5 | 50 | 20 | 36 | 12 | 12 | 20 | 12 | 5.13 | 85 Ohms | TOP=L2:L3=L2/L4:L6=L5/L7:BOTTOM=L7 |
| PE_RX2_DR10_N | PE_RX2_DR10-DIFF1 | PAIR | 1 | 6.88 | 5 | 10 | 5 | 50 | 20 | 36 | 12 | 12 | 20 | 12 | 5.13 | 85 Ohms | TOP=L2:L3=L2/L4:L6=L5/L7:BOTTOM=L7 |
| PE_RX2_DR10_N | PE_RX2_DR10-DIFF1 | PAIR | 2 | 6.5 | 5 | 10 | 5 | 50 | 20 | 25 | 12 | 12 | 20 | 12 | 7.5 | 85 Ohms | TOP=L2:L3=L2/L4:L6=L5/L7:BOTTOM=L7 |
| PE_RX2_DR10_N | PE_RX2_DR10-DIFF1 | PAIR | 3 | 6.5 | 5 | 10 | 5 | 50 | 20 | 25 | 12 | 12 | 20 | 12 | 7.5 | 85 Ohms | TOP=L2:L3=L2/L4:L6=L5/L7:BOTTOM=L7 |
| PE_RX2_DR10_N | PE_RX2_DR10-DIFF1 | PAIR | 4 | 6.5 | 5 | 10 | 5 | 50 | 20 | 25 | 12 | 12 | 20 | 12 | 7.5 | 85 Ohms | TOP=L2:L3=L2/L4:L6=L5/L7:BOTTOM=L7 |
| PE_RX2_DR10_N | PE_RX2_DR10-DIFF1 | PAIR | 5 | 6.5 | 5 | 10 | 5 | 50 | 20 | 25 | 12 | 12 | 20 | 12 | 7.5 | 85 Ohms | TOP=L2:L3=L2/L4:L6=L5/L7:BOTTOM=L7 |
| PE_RX2_DR10_N | PE_RX2_DR10-DIFF1 | PAIR | 6 | 6.5 | 5 | 10 | 5 | 50 | 20 | 25 | 12 | 12 | 20 | 12 | 7.5 | 85 Ohms | TOP=L2:L3=L2/L4:L6=L5/L7:BOTTOM=L7 |
| PE_RX2_DR10_N | PE_RX2_DR10-DIFF1 | PAIR | 7 | 6.5 | 5 | 10 | 5 | 50 | 20 | 25 | 12 | 12 | 20 | 12 | 7.5 | 85 Ohms | TOP=L2:L3=L2/L4:L6=L5/L7:BOTTOM=L7 |
| PE_RX2_DR10_N | PE_RX2_DR10-DIFF1 | PAIR | 8 | 6.88 | 5 | 10 | 5 | 50 | 20 | 36 | 12 | 12 | 20 | 12 | 5.13 | 85 Ohms | TOP=L2:L3=L2/L4:L6=L5/L7:BOTTOM=L7 |
| PE_RX2_DR10_P | PE_RX2_DR10-DIFF1 | PAIR | 1 | 6.88 | 5 | 10 | 5 | 50 | 20 | 36 | 12 | 12 | 20 | 12 | 5.13 | 85 Ohms | TOP=L2:L3=L2/L4:L6=L5/L7:BOTTOM=L7 |
| PE_RX2_DR10_P | PE_RX2_DR10-DIFF1 | PAIR | 2 | 6.5 | 5 | 10 | 5 | 50 | 20 | 25 | 12 | 12 | 20 | 12 | 7.5 | 85 Ohms | TOP=L2:L3=L2/L4:L6=L5/L7:BOTTOM=L7 |
| PE_RX2_DR10_P | PE_RX2_DR10-DIFF1 | PAIR | 3 | 6.5 | 5 | 10 | 5 | 50 | 20 | 25 | 12 | 12 | 20 | 12 | 7.5 | 85 Ohms | TOP=L2:L3=L2/L4:L6=L5/L7:BOTTOM=L7 |
| PE_RX2_DR10_P | PE_RX2_DR10-DIFF1 | PAIR | 4 | 6.5 | 5 | 10 | 5 | 50 | 20 | 25 | 12 | 12 | 20 | 12 | 7.5 | 85 Ohms | TOP=L2:L3=L2/L4:L6=L5/L7:BOTTOM=L7 |
| PE_RX2_DR10_P | PE_RX2_DR10-DIFF1 | PAIR | 5 | 6.5 | 5 | 10 | 5 | 50 | 20 | 25 | 12 | 12 | 20 | 12 | 7.5 | 85 Ohms | TOP=L2:L3=L2/L4:L6=L5/L7:BOTTOM=L7 |
| PE_RX2_DR10_P | PE_RX2_DR10-DIFF1 | PAIR | 6 | 6.5 | 5 | 10 | 5 | 50 | 20 | 25 | 12 | 12 | 20 | 12 | 7.5 | 85 Ohms | TOP=L2:L3=L2/L4:L6=L5/L7:BOTTOM=L7 |
| PE_RX2_DR10_P | PE_RX2_DR10-DIFF1 | PAIR | 7 | 6.5 | 5 | 10 | 5 | 50 | 20 | 25 | 12 | 12 | 20 | 12 | 7.5 | 85 Ohms | TOP=L2:L3=L2/L4:L6=L5/L7:BOTTOM=L7 |
| PE_RX2_DR10_P | PE_RX2_DR10-DIFF1 | PAIR | 8 | 6.88 | 5 | 10 | 5 | 50 | 20 | 36 | 12 | 12 | 20 | 12 | 5.13 | 85 Ohms | TOP=L2:L3=L2/L4:L6=L5/L7:BOTTOM=L7 |
| PE_RX2_DR11_N | PE_RX2_DR11-DIFF1 | PAIR | 1 | 6.88 | 5 | 10 | 5 | 50 | 20 | 36 | 12 | 12 | 20 | 12 | 5.13 | 85 Ohms | TOP=L2:L3=L2/L4:L6=L5/L7:BOTTOM=L7 |
| PE_RX2_DR11_N | PE_RX2_DR11-DIFF1 | PAIR | 2 | 6.5 | 5 | 10 | 5 | 50 | 20 | 25 | 12 | 12 | 20 | 12 | 7.5 | 85 Ohms | TOP=L2:L3=L2/L4:L6=L5/L7:BOTTOM=L7 |
| PE_RX2_DR11_N | PE_RX2_DR11-DIFF1 | PAIR | 3 | 6.5 | 5 | 10 | 5 | 50 | 20 | 25 | 12 | 12 | 20 | 12 | 7.5 | 85 Ohms | TOP=L2:L3=L2/L4:L6=L5/L7:BOTTOM=L7 |
| PE_RX2_DR11_N | PE_RX2_DR11-DIFF1 | PAIR | 4 | 6.5 | 5 | 10 | 5 | 50 | 20 | 25 | 12 | 12 | 20 | 12 | 7.5 | 85 Ohms | TOP=L2:L3=L2/L4:L6=L5/L7:BOTTOM=L7 |
| PE_RX2_DR11_N | PE_RX2_DR11-DIFF1 | PAIR | 5 | 6.5 | 5 | 10 | 5 | 50 | 20 | 25 | 12 | 12 | 20 | 12 | 7.5 | 85 Ohms | TOP=L2:L3=L2/L4:L6=L5/L7:BOTTOM=L7 |
| PE_RX2_DR11_N | PE_RX2_DR11-DIFF1 | PAIR | 6 | 6.5 | 5 | 10 | 5 | 50 | 20 | 25 | 12 | 12 | 20 | 12 | 7.5 | 85 Ohms | TOP=L2:L3=L2/L4:L6=L5/L7:BOTTOM=L7 |
| PE_RX2_DR11_N | PE_RX2_DR11-DIFF1 | PAIR | 7 | 6.5 | 5 | 10 | 5 | 50 | 20 | 25 | 12 | 12 | 20 | 12 | 7.5 | 85 Ohms | TOP=L2:L3=L2/L4:L6=L5/L7:BOTTOM=L7 |
| PE_RX2_DR11_N | PE_RX2_DR11-DIFF1 | PAIR | 8 | 6.88 | 5 | 10 | 5 | 50 | 20 | 36 | 12 | 12 | 20 | 12 | 5.13 | 85 Ohms | TOP=L2:L3=L2/L4:L6=L5/L7:BOTTOM=L7 |
| PE_RX2_DR11_P | PE_RX2_DR11-DIFF1 | PAIR | 1 | 6.88 | 5 | 10 | 5 | 50 | 20 | 36 | 12 | 12 | 20 | 12 | 5.13 | 85 Ohms | TOP=L2:L3=L2/L4:L6=L5/L7:BOTTOM=L7 |
| PE_RX2_DR11_P | PE_RX2_DR11-DIFF1 | PAIR | 2 | 6.5 | 5 | 10 | 5 | 50 | 20 | 25 | 12 | 12 | 20 | 12 | 7.5 | 85 Ohms | TOP=L2:L3=L2/L4:L6=L5/L7:BOTTOM=L7 |
| PE_RX2_DR11_P | PE_RX2_DR11-DIFF1 | PAIR | 3 | 6.5 | 5 | 10 | 5 | 50 | 20 | 25 | 12 | 12 | 20 | 12 | 7.5 | 85 Ohms | TOP=L2:L3=L2/L4:L6=L5/L7:BOTTOM=L7 |
| PE_RX2_DR11_P | PE_RX2_DR11-DIFF1 | PAIR | 4 | 6.5 | 5 | 10 | 5 | 50 | 20 | 25 | 12 | 12 | 20 | 12 | 7.5 | 85 Ohms | TOP=L2:L3=L2/L4:L6=L5/L7:BOTTOM=L7 |
| PE_RX2_DR11_P | PE_RX2_DR11-DIFF1 | PAIR | 5 | 6.5 | 5 | 10 | 5 | 50 | 20 | 25 | 12 | 12 | 20 | 12 | 7.5 | 85 Ohms | TOP=L2:L3=L2/L4:L6=L5/L7:BOTTOM=L7 |
| PE_RX2_DR11_P | PE_RX2_DR11-DIFF1 | PAIR | 6 | 6.5 | 5 | 10 | 5 | 50 | 20 | 25 | 12 | 12 | 20 | 12 | 7.5 | 85 Ohms | TOP=L2:L3=L2/L4:L6=L5/L7:BOTTOM=L7 |
| PE_RX2_DR11_P | PE_RX2_DR11-DIFF1 | PAIR | 7 | 6.5 | 5 | 10 | 5 | 50 | 20 | 25 | 12 | 12 | 20 | 12 | 7.5 | 85 Ohms | TOP=L2:L3=L2/L4:L6=L5/L7:BOTTOM=L7 |
| PE_RX2_DR11_P | PE_RX2_DR11-DIFF1 | PAIR | 8 | 6.88 | 5 | 10 | 5 | 50 | 20 | 36 | 12 | 12 | 20 | 12 | 5.13 | 85 Ohms | TOP=L2:L3=L2/L4:L6=L5/L7:BOTTOM=L7 |
| PE_RX2_DR12_N | PE_RX2_DR12-DIFF1 | PAIR | 1 | 6.88 | 5 | 10 | 5 | 50 | 20 | 36 | 12 | 12 | 20 | 12 | 5.13 | 85 Ohms | TOP=L2:L3=L2/L4:L6=L5/L7:BOTTOM=L7 |
| PE_RX2_DR12_N | PE_RX2_DR12-DIFF1 | PAIR | 2 | 6.5 | 5 | 10 | 5 | 50 | 20 | 25 | 12 | 12 | 20 | 12 | 7.5 | 85 Ohms | TOP=L2:L3=L2/L4:L6=L5/L7:BOTTOM=L7 |
| PE_RX2_DR12_N | PE_RX2_DR12-DIFF1 | PAIR | 3 | 6.5 | 5 | 10 | 5 | 50 | 20 | 25 | 12 | 12 | 20 | 12 | 7.5 | 85 Ohms | TOP=L2:L3=L2/L4:L6=L5/L7:BOTTOM=L7 |
| PE_RX2_DR12_N | PE_RX2_DR12-DIFF1 | PAIR | 4 | 6.5 | 5 | 10 | 5 | 50 | 20 | 25 | 12 | 12 | 20 | 12 | 7.5 | 85 Ohms | TOP=L2:L3=L2/L4:L6=L5/L7:BOTTOM=L7 |
| PE_RX2_DR12_N | PE_RX2_DR12-DIFF1 | PAIR | 5 | 6.5 | 5 | 10 | 5 | 50 | 20 | 25 | 12 | 12 | 20 | 12 | 7.5 | 85 Ohms | TOP=L2:L3=L2/L4:L6=L5/L7:BOTTOM=L7 |
| PE_RX2_DR12_N | PE_RX2_DR12-DIFF1 | PAIR | 6 | 6.5 | 5 | 10 | 5 | 50 | 20 | 25 | 12 | 12 | 20 | 12 | 7.5 | 85 Ohms | TOP=L2:L3=L2/L4:L6=L5/L7:BOTTOM=L7 |
| PE_RX2_DR12_N | PE_RX2_DR12-DIFF1 | PAIR | 7 | 6.5 | 5 | 10 | 5 | 50 | 20 | 25 | 12 | 12 | 20 | 12 | 7.5 | 85 Ohms | TOP=L2:L3=L2/L4:L6=L5/L7:BOTTOM=L7 |
| PE_RX2_DR12_N | PE_RX2_DR12-DIFF1 | PAIR | 8 | 6.88 | 5 | 10 | 5 | 50 | 20 | 36 | 12 | 12 | 20 | 12 | 5.13 | 85 Ohms | TOP=L2:L3=L2/L4:L6=L5/L7:BOTTOM=L7 |
| PE_RX2_DR12_P | PE_RX2_DR12-DIFF1 | PAIR | 1 | 6.88 | 5 | 10 | 5 | 50 | 20 | 36 | 12 | 12 | 20 | 12 | 5.13 | 85 Ohms | TOP=L2:L3=L2/L4:L6=L5/L7:BOTTOM=L7 |
| PE_RX2_DR12_P | PE_RX2_DR12-DIFF1 | PAIR | 2 | 6.5 | 5 | 10 | 5 | 50 | 20 | 25 | 12 | 12 | 20 | 12 | 7.5 | 85 Ohms | TOP=L2:L3=L2/L4:L6=L5/L7:BOTTOM=L7 |
| PE_RX2_DR12_P | PE_RX2_DR12-DIFF1 | PAIR | 3 | 6.5 | 5 | 10 | 5 | 50 | 20 | 25 | 12 | 12 | 20 | 12 | 7.5 | 85 Ohms | TOP=L2:L3=L2/L4:L6=L5/L7:BOTTOM=L7 |
| PE_RX2_DR12_P | PE_RX2_DR12-DIFF1 | PAIR | 4 | 6.5 | 5 | 10 | 5 | 50 | 20 | 25 | 12 | 12 | 20 | 12 | 7.5 | 85 Ohms | TOP=L2:L3=L2/L4:L6=L5/L7:BOTTOM=L7 |
| PE_RX2_DR12_P | PE_RX2_DR12-DIFF1 | PAIR | 5 | 6.5 | 5 | 10 | 5 | 50 | 20 | 25 | 12 | 12 | 20 | 12 | 7.5 | 85 Ohms | TOP=L2:L3=L2/L4:L6=L5/L7:BOTTOM=L7 |
| PE_RX2_DR12_P | PE_RX2_DR12-DIFF1 | PAIR | 6 | 6.5 | 5 | 10 | 5 | 50 | 20 | 25 | 12 | 12 | 20 | 12 | 7.5 | 85 Ohms | TOP=L2:L3=L2/L4:L6=L5/L7:BOTTOM=L7 |
| PE_RX2_DR12_P | PE_RX2_DR12-DIFF1 | PAIR | 7 | 6.5 | 5 | 10 | 5 | 50 | 20 | 25 | 12 | 12 | 20 | 12 | 7.5 | 85 Ohms | TOP=L2:L3=L2/L4:L6=L5/L7:BOTTOM=L7 |
| PE_RX2_DR12_P | PE_RX2_DR12-DIFF1 | PAIR | 8 | 6.88 | 5 | 10 | 5 | 50 | 20 | 36 | 12 | 12 | 20 | 12 | 5.13 | 85 Ohms | TOP=L2:L3=L2/L4:L6=L5/L7:BOTTOM=L7 |
| PE_RX2_DR13_N | PE_RX2_DR13-DIFF1 | PAIR | 1 | 6.88 | 5 | 10 | 5 | 50 | 20 | 36 | 12 | 12 | 20 | 12 | 5.13 | 85 Ohms | TOP=L2:L3=L2/L4:L6=L5/L7:BOTTOM=L7 |
| PE_RX2_DR13_N | PE_RX2_DR13-DIFF1 | PAIR | 2 | 6.5 | 5 | 10 | 5 | 50 | 20 | 25 | 12 | 12 | 20 | 12 | 7.5 | 85 Ohms | TOP=L2:L3=L2/L4:L6=L5/L7:BOTTOM=L7 |
| PE_RX2_DR13_N | PE_RX2_DR13-DIFF1 | PAIR | 3 | 6.5 | 5 | 10 | 5 | 50 | 20 | 25 | 12 | 12 | 20 | 12 | 7.5 | 85 Ohms | TOP=L2:L3=L2/L4:L6=L5/L7:BOTTOM=L7 |
| PE_RX2_DR13_N | PE_RX2_DR13-DIFF1 | PAIR | 4 | 6.5 | 5 | 10 | 5 | 50 | 20 | 25 | 12 | 12 | 20 | 12 | 7.5 | 85 Ohms | TOP=L2:L3=L2/L4:L6=L5/L7:BOTTOM=L7 |
| PE_RX2_DR13_N | PE_RX2_DR13-DIFF1 | PAIR | 5 | 6.5 | 5 | 10 | 5 | 50 | 20 | 25 | 12 | 12 | 20 | 12 | 7.5 | 85 Ohms | TOP=L2:L3=L2/L4:L6=L5/L7:BOTTOM=L7 |
| PE_RX2_DR13_N | PE_RX2_DR13-DIFF1 | PAIR | 6 | 6.5 | 5 | 10 | 5 | 50 | 20 | 25 | 12 | 12 | 20 | 12 | 7.5 | 85 Ohms | TOP=L2:L3=L2/L4:L6=L5/L7:BOTTOM=L7 |
| PE_RX2_DR13_N | PE_RX2_DR13-DIFF1 | PAIR | 7 | 6.5 | 5 | 10 | 5 | 50 | 20 | 25 | 12 | 12 | 20 | 12 | 7.5 | 85 Ohms | TOP=L2:L3=L2/L4:L6=L5/L7:BOTTOM=L7 |
| PE_RX2_DR13_N | PE_RX2_DR13-DIFF1 | PAIR | 8 | 6.88 | 5 | 10 | 5 | 50 | 20 | 36 | 12 | 12 | 20 | 12 | 5.13 | 85 Ohms | TOP=L2:L3=L2/L4:L6=L5/L7:BOTTOM=L7 |
| PE_RX2_DR13_P | PE_RX2_DR13-DIFF1 | PAIR | 1 | 6.88 | 5 | 10 | 5 | 50 | 20 | 36 | 12 | 12 | 20 | 12 | 5.13 | 85 Ohms | TOP=L2:L3=L2/L4:L6=L5/L7:BOTTOM=L7 |
| PE_RX2_DR13_P | PE_RX2_DR13-DIFF1 | PAIR | 2 | 6.5 | 5 | 10 | 5 | 50 | 20 | 25 | 12 | 12 | 20 | 12 | 7.5 | 85 Ohms | TOP=L2:L3=L2/L4:L6=L5/L7:BOTTOM=L7 |
| PE_RX2_DR13_P | PE_RX2_DR13-DIFF1 | PAIR | 3 | 6.5 | 5 | 10 | 5 | 50 | 20 | 25 | 12 | 12 | 20 | 12 | 7.5 | 85 Ohms | TOP=L2:L3=L2/L4:L6=L5/L7:BOTTOM=L7 |
| PE_RX2_DR13_P | PE_RX2_DR13-DIFF1 | PAIR | 4 | 6.5 | 5 | 10 | 5 | 50 | 20 | 25 | 12 | 12 | 20 | 12 | 7.5 | 85 Ohms | TOP=L2:L3=L2/L4:L6=L5/L7:BOTTOM=L7 |
| PE_RX2_DR13_P | PE_RX2_DR13-DIFF1 | PAIR | 5 | 6.5 | 5 | 10 | 5 | 50 | 20 | 25 | 12 | 12 | 20 | 12 | 7.5 | 85 Ohms | TOP=L2:L3=L2/L4:L6=L5/L7:BOTTOM=L7 |
| PE_RX2_DR13_P | PE_RX2_DR13-DIFF1 | PAIR | 6 | 6.5 | 5 | 10 | 5 | 50 | 20 | 25 | 12 | 12 | 20 | 12 | 7.5 | 85 Ohms | TOP=L2:L3=L2/L4:L6=L5/L7:BOTTOM=L7 |
| PE_RX2_DR13_P | PE_RX2_DR13-DIFF1 | PAIR | 7 | 6.5 | 5 | 10 | 5 | 50 | 20 | 25 | 12 | 12 | 20 | 12 | 7.5 | 85 Ohms | TOP=L2:L3=L2/L4:L6=L5/L7:BOTTOM=L7 |
| PE_RX2_DR13_P | PE_RX2_DR13-DIFF1 | PAIR | 8 | 6.88 | 5 | 10 | 5 | 50 | 20 | 36 | 12 | 12 | 20 | 12 | 5.13 | 85 Ohms | TOP=L2:L3=L2/L4:L6=L5/L7:BOTTOM=L7 |
| PE_RX2_DR14_N | PE_RX2_DR14-DIFF1 | PAIR | 1 | 6.88 | 5 | 10 | 5 | 50 | 20 | 36 | 12 | 12 | 20 | 12 | 5.13 | 85 Ohms | TOP=L2:L3=L2/L4:L6=L5/L7:BOTTOM=L7 |
| PE_RX2_DR14_N | PE_RX2_DR14-DIFF1 | PAIR | 2 | 6.5 | 5 | 10 | 5 | 50 | 20 | 25 | 12 | 12 | 20 | 12 | 7.5 | 85 Ohms | TOP=L2:L3=L2/L4:L6=L5/L7:BOTTOM=L7 |
| PE_RX2_DR14_N | PE_RX2_DR14-DIFF1 | PAIR | 3 | 6.5 | 5 | 10 | 5 | 50 | 20 | 25 | 12 | 12 | 20 | 12 | 7.5 | 85 Ohms | TOP=L2:L3=L2/L4:L6=L5/L7:BOTTOM=L7 |
| PE_RX2_DR14_N | PE_RX2_DR14-DIFF1 | PAIR | 4 | 6.5 | 5 | 10 | 5 | 50 | 20 | 25 | 12 | 12 | 20 | 12 | 7.5 | 85 Ohms | TOP=L2:L3=L2/L4:L6=L5/L7:BOTTOM=L7 |
| PE_RX2_DR14_N | PE_RX2_DR14-DIFF1 | PAIR | 5 | 6.5 | 5 | 10 | 5 | 50 | 20 | 25 | 12 | 12 | 20 | 12 | 7.5 | 85 Ohms | TOP=L2:L3=L2/L4:L6=L5/L7:BOTTOM=L7 |
| PE_RX2_DR14_N | PE_RX2_DR14-DIFF1 | PAIR | 6 | 6.5 | 5 | 10 | 5 | 50 | 20 | 25 | 12 | 12 | 20 | 12 | 7.5 | 85 Ohms | TOP=L2:L3=L2/L4:L6=L5/L7:BOTTOM=L7 |
| PE_RX2_DR14_N | PE_RX2_DR14-DIFF1 | PAIR | 7 | 6.5 | 5 | 10 | 5 | 50 | 20 | 25 | 12 | 12 | 20 | 12 | 7.5 | 85 Ohms | TOP=L2:L3=L2/L4:L6=L5/L7:BOTTOM=L7 |
| PE_RX2_DR14_N | PE_RX2_DR14-DIFF1 | PAIR | 8 | 6.88 | 5 | 10 | 5 | 50 | 20 | 36 | 12 | 12 | 20 | 12 | 5.13 | 85 Ohms | TOP=L2:L3=L2/L4:L6=L5/L7:BOTTOM=L7 |
| PE_RX2_DR14_P | PE_RX2_DR14-DIFF1 | PAIR | 1 | 6.88 | 5 | 10 | 5 | 50 | 20 | 36 | 12 | 12 | 20 | 12 | 5.13 | 85 Ohms | TOP=L2:L3=L2/L4:L6=L5/L7:BOTTOM=L7 |
| PE_RX2_DR14_P | PE_RX2_DR14-DIFF1 | PAIR | 2 | 6.5 | 5 | 10 | 5 | 50 | 20 | 25 | 12 | 12 | 20 | 12 | 7.5 | 85 Ohms | TOP=L2:L3=L2/L4:L6=L5/L7:BOTTOM=L7 |
| PE_RX2_DR14_P | PE_RX2_DR14-DIFF1 | PAIR | 3 | 6.5 | 5 | 10 | 5 | 50 | 20 | 25 | 12 | 12 | 20 | 12 | 7.5 | 85 Ohms | TOP=L2:L3=L2/L4:L6=L5/L7:BOTTOM=L7 |
| PE_RX2_DR14_P | PE_RX2_DR14-DIFF1 | PAIR | 4 | 6.5 | 5 | 10 | 5 | 50 | 20 | 25 | 12 | 12 | 20 | 12 | 7.5 | 85 Ohms | TOP=L2:L3=L2/L4:L6=L5/L7:BOTTOM=L7 |
| PE_RX2_DR14_P | PE_RX2_DR14-DIFF1 | PAIR | 5 | 6.5 | 5 | 10 | 5 | 50 | 20 | 25 | 12 | 12 | 20 | 12 | 7.5 | 85 Ohms | TOP=L2:L3=L2/L4:L6=L5/L7:BOTTOM=L7 |
| PE_RX2_DR14_P | PE_RX2_DR14-DIFF1 | PAIR | 6 | 6.5 | 5 | 10 | 5 | 50 | 20 | 25 | 12 | 12 | 20 | 12 | 7.5 | 85 Ohms | TOP=L2:L3=L2/L4:L6=L5/L7:BOTTOM=L7 |
| PE_RX2_DR14_P | PE_RX2_DR14-DIFF1 | PAIR | 7 | 6.5 | 5 | 10 | 5 | 50 | 20 | 25 | 12 | 12 | 20 | 12 | 7.5 | 85 Ohms | TOP=L2:L3=L2/L4:L6=L5/L7:BOTTOM=L7 |
| PE_RX2_DR14_P | PE_RX2_DR14-DIFF1 | PAIR | 8 | 6.88 | 5 | 10 | 5 | 50 | 20 | 36 | 12 | 12 | 20 | 12 | 5.13 | 85 Ohms | TOP=L2:L3=L2/L4:L6=L5/L7:BOTTOM=L7 |
| PE_RX2_DR1_N | PE_RX2_DR1-DIFF1 | PAIR | 1 | 6.88 | 5 | 10 | 5 | 50 | 20 | 36 | 12 | 12 | 20 | 12 | 5.13 | 85 Ohms | TOP=L2:L3=L2/L4:L6=L5/L7:BOTTOM=L7 |
| PE_RX2_DR1_N | PE_RX2_DR1-DIFF1 | PAIR | 2 | 6.5 | 5 | 10 | 5 | 50 | 20 | 25 | 12 | 12 | 20 | 12 | 7.5 | 85 Ohms | TOP=L2:L3=L2/L4:L6=L5/L7:BOTTOM=L7 |
| PE_RX2_DR1_N | PE_RX2_DR1-DIFF1 | PAIR | 3 | 6.5 | 5 | 10 | 5 | 50 | 20 | 25 | 12 | 12 | 20 | 12 | 7.5 | 85 Ohms | TOP=L2:L3=L2/L4:L6=L5/L7:BOTTOM=L7 |
| PE_RX2_DR1_N | PE_RX2_DR1-DIFF1 | PAIR | 4 | 6.5 | 5 | 10 | 5 | 50 | 20 | 25 | 12 | 12 | 20 | 12 | 7.5 | 85 Ohms | TOP=L2:L3=L2/L4:L6=L5/L7:BOTTOM=L7 |
| PE_RX2_DR1_N | PE_RX2_DR1-DIFF1 | PAIR | 5 | 6.5 | 5 | 10 | 5 | 50 | 20 | 25 | 12 | 12 | 20 | 12 | 7.5 | 85 Ohms | TOP=L2:L3=L2/L4:L6=L5/L7:BOTTOM=L7 |
| PE_RX2_DR1_N | PE_RX2_DR1-DIFF1 | PAIR | 6 | 6.5 | 5 | 10 | 5 | 50 | 20 | 25 | 12 | 12 | 20 | 12 | 7.5 | 85 Ohms | TOP=L2:L3=L2/L4:L6=L5/L7:BOTTOM=L7 |
| PE_RX2_DR1_N | PE_RX2_DR1-DIFF1 | PAIR | 7 | 6.5 | 5 | 10 | 5 | 50 | 20 | 25 | 12 | 12 | 20 | 12 | 7.5 | 85 Ohms | TOP=L2:L3=L2/L4:L6=L5/L7:BOTTOM=L7 |
| PE_RX2_DR1_N | PE_RX2_DR1-DIFF1 | PAIR | 8 | 6.88 | 5 | 10 | 5 | 50 | 20 | 36 | 12 | 12 | 20 | 12 | 5.13 | 85 Ohms | TOP=L2:L3=L2/L4:L6=L5/L7:BOTTOM=L7 |
| PE_RX2_DR1_P | PE_RX2_DR1-DIFF1 | PAIR | 1 | 6.88 | 5 | 10 | 5 | 50 | 20 | 36 | 12 | 12 | 20 | 12 | 5.13 | 85 Ohms | TOP=L2:L3=L2/L4:L6=L5/L7:BOTTOM=L7 |
| PE_RX2_DR1_P | PE_RX2_DR1-DIFF1 | PAIR | 2 | 6.5 | 5 | 10 | 5 | 50 | 20 | 25 | 12 | 12 | 20 | 12 | 7.5 | 85 Ohms | TOP=L2:L3=L2/L4:L6=L5/L7:BOTTOM=L7 |
| PE_RX2_DR1_P | PE_RX2_DR1-DIFF1 | PAIR | 3 | 6.5 | 5 | 10 | 5 | 50 | 20 | 25 | 12 | 12 | 20 | 12 | 7.5 | 85 Ohms | TOP=L2:L3=L2/L4:L6=L5/L7:BOTTOM=L7 |
| PE_RX2_DR1_P | PE_RX2_DR1-DIFF1 | PAIR | 4 | 6.5 | 5 | 10 | 5 | 50 | 20 | 25 | 12 | 12 | 20 | 12 | 7.5 | 85 Ohms | TOP=L2:L3=L2/L4:L6=L5/L7:BOTTOM=L7 |
| PE_RX2_DR1_P | PE_RX2_DR1-DIFF1 | PAIR | 5 | 6.5 | 5 | 10 | 5 | 50 | 20 | 25 | 12 | 12 | 20 | 12 | 7.5 | 85 Ohms | TOP=L2:L3=L2/L4:L6=L5/L7:BOTTOM=L7 |
| PE_RX2_DR1_P | PE_RX2_DR1-DIFF1 | PAIR | 6 | 6.5 | 5 | 10 | 5 | 50 | 20 | 25 | 12 | 12 | 20 | 12 | 7.5 | 85 Ohms | TOP=L2:L3=L2/L4:L6=L5/L7:BOTTOM=L7 |
| PE_RX2_DR1_P | PE_RX2_DR1-DIFF1 | PAIR | 7 | 6.5 | 5 | 10 | 5 | 50 | 20 | 25 | 12 | 12 | 20 | 12 | 7.5 | 85 Ohms | TOP=L2:L3=L2/L4:L6=L5/L7:BOTTOM=L7 |
| PE_RX2_DR1_P | PE_RX2_DR1-DIFF1 | PAIR | 8 | 6.88 | 5 | 10 | 5 | 50 | 20 | 36 | 12 | 12 | 20 | 12 | 5.13 | 85 Ohms | TOP=L2:L3=L2/L4:L6=L5/L7:BOTTOM=L7 |
| PE_RX2_DR2_N | PE_RX2_DR2-DIFF1 | PAIR | 1 | 6.88 | 5 | 10 | 5 | 50 | 20 | 36 | 12 | 12 | 20 | 12 | 5.13 | 85 Ohms | TOP=L2:L3=L2/L4:L6=L5/L7:BOTTOM=L7 |
| PE_RX2_DR2_N | PE_RX2_DR2-DIFF1 | PAIR | 2 | 6.5 | 5 | 10 | 5 | 50 | 20 | 25 | 12 | 12 | 20 | 12 | 7.5 | 85 Ohms | TOP=L2:L3=L2/L4:L6=L5/L7:BOTTOM=L7 |
| PE_RX2_DR2_N | PE_RX2_DR2-DIFF1 | PAIR | 3 | 6.5 | 5 | 10 | 5 | 50 | 20 | 25 | 12 | 12 | 20 | 12 | 7.5 | 85 Ohms | TOP=L2:L3=L2/L4:L6=L5/L7:BOTTOM=L7 |
| PE_RX2_DR2_N | PE_RX2_DR2-DIFF1 | PAIR | 4 | 6.5 | 5 | 10 | 5 | 50 | 20 | 25 | 12 | 12 | 20 | 12 | 7.5 | 85 Ohms | TOP=L2:L3=L2/L4:L6=L5/L7:BOTTOM=L7 |
| PE_RX2_DR2_N | PE_RX2_DR2-DIFF1 | PAIR | 5 | 6.5 | 5 | 10 | 5 | 50 | 20 | 25 | 12 | 12 | 20 | 12 | 7.5 | 85 Ohms | TOP=L2:L3=L2/L4:L6=L5/L7:BOTTOM=L7 |
| PE_RX2_DR2_N | PE_RX2_DR2-DIFF1 | PAIR | 6 | 6.5 | 5 | 10 | 5 | 50 | 20 | 25 | 12 | 12 | 20 | 12 | 7.5 | 85 Ohms | TOP=L2:L3=L2/L4:L6=L5/L7:BOTTOM=L7 |
| PE_RX2_DR2_N | PE_RX2_DR2-DIFF1 | PAIR | 7 | 6.5 | 5 | 10 | 5 | 50 | 20 | 25 | 12 | 12 | 20 | 12 | 7.5 | 85 Ohms | TOP=L2:L3=L2/L4:L6=L5/L7:BOTTOM=L7 |
| PE_RX2_DR2_N | PE_RX2_DR2-DIFF1 | PAIR | 8 | 6.88 | 5 | 10 | 5 | 50 | 20 | 36 | 12 | 12 | 20 | 12 | 5.13 | 85 Ohms | TOP=L2:L3=L2/L4:L6=L5/L7:BOTTOM=L7 |
| PE_RX2_DR2_P | PE_RX2_DR2-DIFF1 | PAIR | 1 | 6.88 | 5 | 10 | 5 | 50 | 20 | 36 | 12 | 12 | 20 | 12 | 5.13 | 85 Ohms | TOP=L2:L3=L2/L4:L6=L5/L7:BOTTOM=L7 |
| PE_RX2_DR2_P | PE_RX2_DR2-DIFF1 | PAIR | 2 | 6.5 | 5 | 10 | 5 | 50 | 20 | 25 | 12 | 12 | 20 | 12 | 7.5 | 85 Ohms | TOP=L2:L3=L2/L4:L6=L5/L7:BOTTOM=L7 |
| PE_RX2_DR2_P | PE_RX2_DR2-DIFF1 | PAIR | 3 | 6.5 | 5 | 10 | 5 | 50 | 20 | 25 | 12 | 12 | 20 | 12 | 7.5 | 85 Ohms | TOP=L2:L3=L2/L4:L6=L5/L7:BOTTOM=L7 |
| PE_RX2_DR2_P | PE_RX2_DR2-DIFF1 | PAIR | 4 | 6.5 | 5 | 10 | 5 | 50 | 20 | 25 | 12 | 12 | 20 | 12 | 7.5 | 85 Ohms | TOP=L2:L3=L2/L4:L6=L5/L7:BOTTOM=L7 |
| PE_RX2_DR2_P | PE_RX2_DR2-DIFF1 | PAIR | 5 | 6.5 | 5 | 10 | 5 | 50 | 20 | 25 | 12 | 12 | 20 | 12 | 7.5 | 85 Ohms | TOP=L2:L3=L2/L4:L6=L5/L7:BOTTOM=L7 |
| PE_RX2_DR2_P | PE_RX2_DR2-DIFF1 | PAIR | 6 | 6.5 | 5 | 10 | 5 | 50 | 20 | 25 | 12 | 12 | 20 | 12 | 7.5 | 85 Ohms | TOP=L2:L3=L2/L4:L6=L5/L7:BOTTOM=L7 |
| PE_RX2_DR2_P | PE_RX2_DR2-DIFF1 | PAIR | 7 | 6.5 | 5 | 10 | 5 | 50 | 20 | 25 | 12 | 12 | 20 | 12 | 7.5 | 85 Ohms | TOP=L2:L3=L2/L4:L6=L5/L7:BOTTOM=L7 |
| PE_RX2_DR2_P | PE_RX2_DR2-DIFF1 | PAIR | 8 | 6.88 | 5 | 10 | 5 | 50 | 20 | 36 | 12 | 12 | 20 | 12 | 5.13 | 85 Ohms | TOP=L2:L3=L2/L4:L6=L5/L7:BOTTOM=L7 |
| PE_RX2_DR3_N | PE_RX2_DR3-DIFF1 | PAIR | 1 | 6.88 | 5 | 10 | 5 | 50 | 20 | 36 | 12 | 12 | 20 | 12 | 5.13 | 85 Ohms | TOP=L2:L3=L2/L4:L6=L5/L7:BOTTOM=L7 |
| PE_RX2_DR3_N | PE_RX2_DR3-DIFF1 | PAIR | 2 | 6.5 | 5 | 10 | 5 | 50 | 20 | 25 | 12 | 12 | 20 | 12 | 7.5 | 85 Ohms | TOP=L2:L3=L2/L4:L6=L5/L7:BOTTOM=L7 |
| PE_RX2_DR3_N | PE_RX2_DR3-DIFF1 | PAIR | 3 | 6.5 | 5 | 10 | 5 | 50 | 20 | 25 | 12 | 12 | 20 | 12 | 7.5 | 85 Ohms | TOP=L2:L3=L2/L4:L6=L5/L7:BOTTOM=L7 |
| PE_RX2_DR3_N | PE_RX2_DR3-DIFF1 | PAIR | 4 | 6.5 | 5 | 10 | 5 | 50 | 20 | 25 | 12 | 12 | 20 | 12 | 7.5 | 85 Ohms | TOP=L2:L3=L2/L4:L6=L5/L7:BOTTOM=L7 |
| PE_RX2_DR3_N | PE_RX2_DR3-DIFF1 | PAIR | 5 | 6.5 | 5 | 10 | 5 | 50 | 20 | 25 | 12 | 12 | 20 | 12 | 7.5 | 85 Ohms | TOP=L2:L3=L2/L4:L6=L5/L7:BOTTOM=L7 |
| PE_RX2_DR3_N | PE_RX2_DR3-DIFF1 | PAIR | 6 | 6.5 | 5 | 10 | 5 | 50 | 20 | 25 | 12 | 12 | 20 | 12 | 7.5 | 85 Ohms | TOP=L2:L3=L2/L4:L6=L5/L7:BOTTOM=L7 |
| PE_RX2_DR3_N | PE_RX2_DR3-DIFF1 | PAIR | 7 | 6.5 | 5 | 10 | 5 | 50 | 20 | 25 | 12 | 12 | 20 | 12 | 7.5 | 85 Ohms | TOP=L2:L3=L2/L4:L6=L5/L7:BOTTOM=L7 |
| PE_RX2_DR3_N | PE_RX2_DR3-DIFF1 | PAIR | 8 | 6.88 | 5 | 10 | 5 | 50 | 20 | 36 | 12 | 12 | 20 | 12 | 5.13 | 85 Ohms | TOP=L2:L3=L2/L4:L6=L5/L7:BOTTOM=L7 |
| PE_RX2_DR3_P | PE_RX2_DR3-DIFF1 | PAIR | 1 | 6.88 | 5 | 10 | 5 | 50 | 20 | 36 | 12 | 12 | 20 | 12 | 5.13 | 85 Ohms | TOP=L2:L3=L2/L4:L6=L5/L7:BOTTOM=L7 |
| PE_RX2_DR3_P | PE_RX2_DR3-DIFF1 | PAIR | 2 | 6.5 | 5 | 10 | 5 | 50 | 20 | 25 | 12 | 12 | 20 | 12 | 7.5 | 85 Ohms | TOP=L2:L3=L2/L4:L6=L5/L7:BOTTOM=L7 |
| PE_RX2_DR3_P | PE_RX2_DR3-DIFF1 | PAIR | 3 | 6.5 | 5 | 10 | 5 | 50 | 20 | 25 | 12 | 12 | 20 | 12 | 7.5 | 85 Ohms | TOP=L2:L3=L2/L4:L6=L5/L7:BOTTOM=L7 |
| PE_RX2_DR3_P | PE_RX2_DR3-DIFF1 | PAIR | 4 | 6.5 | 5 | 10 | 5 | 50 | 20 | 25 | 12 | 12 | 20 | 12 | 7.5 | 85 Ohms | TOP=L2:L3=L2/L4:L6=L5/L7:BOTTOM=L7 |
| PE_RX2_DR3_P | PE_RX2_DR3-DIFF1 | PAIR | 5 | 6.5 | 5 | 10 | 5 | 50 | 20 | 25 | 12 | 12 | 20 | 12 | 7.5 | 85 Ohms | TOP=L2:L3=L2/L4:L6=L5/L7:BOTTOM=L7 |
| PE_RX2_DR3_P | PE_RX2_DR3-DIFF1 | PAIR | 6 | 6.5 | 5 | 10 | 5 | 50 | 20 | 25 | 12 | 12 | 20 | 12 | 7.5 | 85 Ohms | TOP=L2:L3=L2/L4:L6=L5/L7:BOTTOM=L7 |
| PE_RX2_DR3_P | PE_RX2_DR3-DIFF1 | PAIR | 7 | 6.5 | 5 | 10 | 5 | 50 | 20 | 25 | 12 | 12 | 20 | 12 | 7.5 | 85 Ohms | TOP=L2:L3=L2/L4:L6=L5/L7:BOTTOM=L7 |
| PE_RX2_DR3_P | PE_RX2_DR3-DIFF1 | PAIR | 8 | 6.88 | 5 | 10 | 5 | 50 | 20 | 36 | 12 | 12 | 20 | 12 | 5.13 | 85 Ohms | TOP=L2:L3=L2/L4:L6=L5/L7:BOTTOM=L7 |
| PE_RX2_DR4_N | PE_RX2_DR4-DIFF1 | PAIR | 1 | 6.88 | 5 | 10 | 5 | 50 | 20 | 36 | 12 | 12 | 20 | 12 | 5.13 | 85 Ohms | TOP=L2:L3=L2/L4:L6=L5/L7:BOTTOM=L7 |
| PE_RX2_DR4_N | PE_RX2_DR4-DIFF1 | PAIR | 2 | 6.5 | 5 | 10 | 5 | 50 | 20 | 25 | 12 | 12 | 20 | 12 | 7.5 | 85 Ohms | TOP=L2:L3=L2/L4:L6=L5/L7:BOTTOM=L7 |
| PE_RX2_DR4_N | PE_RX2_DR4-DIFF1 | PAIR | 3 | 6.5 | 5 | 10 | 5 | 50 | 20 | 25 | 12 | 12 | 20 | 12 | 7.5 | 85 Ohms | TOP=L2:L3=L2/L4:L6=L5/L7:BOTTOM=L7 |
| PE_RX2_DR4_N | PE_RX2_DR4-DIFF1 | PAIR | 4 | 6.5 | 5 | 10 | 5 | 50 | 20 | 25 | 12 | 12 | 20 | 12 | 7.5 | 85 Ohms | TOP=L2:L3=L2/L4:L6=L5/L7:BOTTOM=L7 |
| PE_RX2_DR4_N | PE_RX2_DR4-DIFF1 | PAIR | 5 | 6.5 | 5 | 10 | 5 | 50 | 20 | 25 | 12 | 12 | 20 | 12 | 7.5 | 85 Ohms | TOP=L2:L3=L2/L4:L6=L5/L7:BOTTOM=L7 |
| PE_RX2_DR4_N | PE_RX2_DR4-DIFF1 | PAIR | 6 | 6.5 | 5 | 10 | 5 | 50 | 20 | 25 | 12 | 12 | 20 | 12 | 7.5 | 85 Ohms | TOP=L2:L3=L2/L4:L6=L5/L7:BOTTOM=L7 |
| PE_RX2_DR4_N | PE_RX2_DR4-DIFF1 | PAIR | 7 | 6.5 | 5 | 10 | 5 | 50 | 20 | 25 | 12 | 12 | 20 | 12 | 7.5 | 85 Ohms | TOP=L2:L3=L2/L4:L6=L5/L7:BOTTOM=L7 |
| PE_RX2_DR4_N | PE_RX2_DR4-DIFF1 | PAIR | 8 | 6.88 | 5 | 10 | 5 | 50 | 20 | 36 | 12 | 12 | 20 | 12 | 5.13 | 85 Ohms | TOP=L2:L3=L2/L4:L6=L5/L7:BOTTOM=L7 |
| PE_RX2_DR4_P | PE_RX2_DR4-DIFF1 | PAIR | 1 | 6.88 | 5 | 10 | 5 | 50 | 20 | 36 | 12 | 12 | 20 | 12 | 5.13 | 85 Ohms | TOP=L2:L3=L2/L4:L6=L5/L7:BOTTOM=L7 |
| PE_RX2_DR4_P | PE_RX2_DR4-DIFF1 | PAIR | 2 | 6.5 | 5 | 10 | 5 | 50 | 20 | 25 | 12 | 12 | 20 | 12 | 7.5 | 85 Ohms | TOP=L2:L3=L2/L4:L6=L5/L7:BOTTOM=L7 |
| PE_RX2_DR4_P | PE_RX2_DR4-DIFF1 | PAIR | 3 | 6.5 | 5 | 10 | 5 | 50 | 20 | 25 | 12 | 12 | 20 | 12 | 7.5 | 85 Ohms | TOP=L2:L3=L2/L4:L6=L5/L7:BOTTOM=L7 |
| PE_RX2_DR4_P | PE_RX2_DR4-DIFF1 | PAIR | 4 | 6.5 | 5 | 10 | 5 | 50 | 20 | 25 | 12 | 12 | 20 | 12 | 7.5 | 85 Ohms | TOP=L2:L3=L2/L4:L6=L5/L7:BOTTOM=L7 |
| PE_RX2_DR4_P | PE_RX2_DR4-DIFF1 | PAIR | 5 | 6.5 | 5 | 10 | 5 | 50 | 20 | 25 | 12 | 12 | 20 | 12 | 7.5 | 85 Ohms | TOP=L2:L3=L2/L4:L6=L5/L7:BOTTOM=L7 |
| PE_RX2_DR4_P | PE_RX2_DR4-DIFF1 | PAIR | 6 | 6.5 | 5 | 10 | 5 | 50 | 20 | 25 | 12 | 12 | 20 | 12 | 7.5 | 85 Ohms | TOP=L2:L3=L2/L4:L6=L5/L7:BOTTOM=L7 |
| PE_RX2_DR4_P | PE_RX2_DR4-DIFF1 | PAIR | 7 | 6.5 | 5 | 10 | 5 | 50 | 20 | 25 | 12 | 12 | 20 | 12 | 7.5 | 85 Ohms | TOP=L2:L3=L2/L4:L6=L5/L7:BOTTOM=L7 |
| PE_RX2_DR4_P | PE_RX2_DR4-DIFF1 | PAIR | 8 | 6.88 | 5 | 10 | 5 | 50 | 20 | 36 | 12 | 12 | 20 | 12 | 5.13 | 85 Ohms | TOP=L2:L3=L2/L4:L6=L5/L7:BOTTOM=L7 |
| PE_RX2_DR5_N | PE_RX2_DR5-DIFF1 | PAIR | 1 | 6.88 | 5 | 10 | 5 | 50 | 20 | 36 | 12 | 12 | 20 | 12 | 5.13 | 85 Ohms | TOP=L2:L3=L2/L4:L6=L5/L7:BOTTOM=L7 |
| PE_RX2_DR5_N | PE_RX2_DR5-DIFF1 | PAIR | 2 | 6.5 | 5 | 10 | 5 | 50 | 20 | 25 | 12 | 12 | 20 | 12 | 7.5 | 85 Ohms | TOP=L2:L3=L2/L4:L6=L5/L7:BOTTOM=L7 |
| PE_RX2_DR5_N | PE_RX2_DR5-DIFF1 | PAIR | 3 | 6.5 | 5 | 10 | 5 | 50 | 20 | 25 | 12 | 12 | 20 | 12 | 7.5 | 85 Ohms | TOP=L2:L3=L2/L4:L6=L5/L7:BOTTOM=L7 |
| PE_RX2_DR5_N | PE_RX2_DR5-DIFF1 | PAIR | 4 | 6.5 | 5 | 10 | 5 | 50 | 20 | 25 | 12 | 12 | 20 | 12 | 7.5 | 85 Ohms | TOP=L2:L3=L2/L4:L6=L5/L7:BOTTOM=L7 |
| PE_RX2_DR5_N | PE_RX2_DR5-DIFF1 | PAIR | 5 | 6.5 | 5 | 10 | 5 | 50 | 20 | 25 | 12 | 12 | 20 | 12 | 7.5 | 85 Ohms | TOP=L2:L3=L2/L4:L6=L5/L7:BOTTOM=L7 |
| PE_RX2_DR5_N | PE_RX2_DR5-DIFF1 | PAIR | 6 | 6.5 | 5 | 10 | 5 | 50 | 20 | 25 | 12 | 12 | 20 | 12 | 7.5 | 85 Ohms | TOP=L2:L3=L2/L4:L6=L5/L7:BOTTOM=L7 |
| PE_RX2_DR5_N | PE_RX2_DR5-DIFF1 | PAIR | 7 | 6.5 | 5 | 10 | 5 | 50 | 20 | 25 | 12 | 12 | 20 | 12 | 7.5 | 85 Ohms | TOP=L2:L3=L2/L4:L6=L5/L7:BOTTOM=L7 |
| PE_RX2_DR5_N | PE_RX2_DR5-DIFF1 | PAIR | 8 | 6.88 | 5 | 10 | 5 | 50 | 20 | 36 | 12 | 12 | 20 | 12 | 5.13 | 85 Ohms | TOP=L2:L3=L2/L4:L6=L5/L7:BOTTOM=L7 |
| PE_RX2_DR5_P | PE_RX2_DR5-DIFF1 | PAIR | 1 | 6.88 | 5 | 10 | 5 | 50 | 20 | 36 | 12 | 12 | 20 | 12 | 5.13 | 85 Ohms | TOP=L2:L3=L2/L4:L6=L5/L7:BOTTOM=L7 |
| PE_RX2_DR5_P | PE_RX2_DR5-DIFF1 | PAIR | 2 | 6.5 | 5 | 10 | 5 | 50 | 20 | 25 | 12 | 12 | 20 | 12 | 7.5 | 85 Ohms | TOP=L2:L3=L2/L4:L6=L5/L7:BOTTOM=L7 |
| PE_RX2_DR5_P | PE_RX2_DR5-DIFF1 | PAIR | 3 | 6.5 | 5 | 10 | 5 | 50 | 20 | 25 | 12 | 12 | 20 | 12 | 7.5 | 85 Ohms | TOP=L2:L3=L2/L4:L6=L5/L7:BOTTOM=L7 |
| PE_RX2_DR5_P | PE_RX2_DR5-DIFF1 | PAIR | 4 | 6.5 | 5 | 10 | 5 | 50 | 20 | 25 | 12 | 12 | 20 | 12 | 7.5 | 85 Ohms | TOP=L2:L3=L2/L4:L6=L5/L7:BOTTOM=L7 |
| PE_RX2_DR5_P | PE_RX2_DR5-DIFF1 | PAIR | 5 | 6.5 | 5 | 10 | 5 | 50 | 20 | 25 | 12 | 12 | 20 | 12 | 7.5 | 85 Ohms | TOP=L2:L3=L2/L4:L6=L5/L7:BOTTOM=L7 |
| PE_RX2_DR5_P | PE_RX2_DR5-DIFF1 | PAIR | 6 | 6.5 | 5 | 10 | 5 | 50 | 20 | 25 | 12 | 12 | 20 | 12 | 7.5 | 85 Ohms | TOP=L2:L3=L2/L4:L6=L5/L7:BOTTOM=L7 |
| PE_RX2_DR5_P | PE_RX2_DR5-DIFF1 | PAIR | 7 | 6.5 | 5 | 10 | 5 | 50 | 20 | 25 | 12 | 12 | 20 | 12 | 7.5 | 85 Ohms | TOP=L2:L3=L2/L4:L6=L5/L7:BOTTOM=L7 |
| PE_RX2_DR5_P | PE_RX2_DR5-DIFF1 | PAIR | 8 | 6.88 | 5 | 10 | 5 | 50 | 20 | 36 | 12 | 12 | 20 | 12 | 5.13 | 85 Ohms | TOP=L2:L3=L2/L4:L6=L5/L7:BOTTOM=L7 |
| PE_RX2_DR6_N | PE_RX2_DR6-DIFF1 | PAIR | 1 | 6.88 | 5 | 10 | 5 | 50 | 20 | 36 | 12 | 12 | 20 | 12 | 5.13 | 85 Ohms | TOP=L2:L3=L2/L4:L6=L5/L7:BOTTOM=L7 |
| PE_RX2_DR6_N | PE_RX2_DR6-DIFF1 | PAIR | 2 | 6.5 | 5 | 10 | 5 | 50 | 20 | 25 | 12 | 12 | 20 | 12 | 7.5 | 85 Ohms | TOP=L2:L3=L2/L4:L6=L5/L7:BOTTOM=L7 |
| PE_RX2_DR6_N | PE_RX2_DR6-DIFF1 | PAIR | 3 | 6.5 | 5 | 10 | 5 | 50 | 20 | 25 | 12 | 12 | 20 | 12 | 7.5 | 85 Ohms | TOP=L2:L3=L2/L4:L6=L5/L7:BOTTOM=L7 |
| PE_RX2_DR6_N | PE_RX2_DR6-DIFF1 | PAIR | 4 | 6.5 | 5 | 10 | 5 | 50 | 20 | 25 | 12 | 12 | 20 | 12 | 7.5 | 85 Ohms | TOP=L2:L3=L2/L4:L6=L5/L7:BOTTOM=L7 |
| PE_RX2_DR6_N | PE_RX2_DR6-DIFF1 | PAIR | 5 | 6.5 | 5 | 10 | 5 | 50 | 20 | 25 | 12 | 12 | 20 | 12 | 7.5 | 85 Ohms | TOP=L2:L3=L2/L4:L6=L5/L7:BOTTOM=L7 |
| PE_RX2_DR6_N | PE_RX2_DR6-DIFF1 | PAIR | 6 | 6.5 | 5 | 10 | 5 | 50 | 20 | 25 | 12 | 12 | 20 | 12 | 7.5 | 85 Ohms | TOP=L2:L3=L2/L4:L6=L5/L7:BOTTOM=L7 |
| PE_RX2_DR6_N | PE_RX2_DR6-DIFF1 | PAIR | 7 | 6.5 | 5 | 10 | 5 | 50 | 20 | 25 | 12 | 12 | 20 | 12 | 7.5 | 85 Ohms | TOP=L2:L3=L2/L4:L6=L5/L7:BOTTOM=L7 |
| PE_RX2_DR6_N | PE_RX2_DR6-DIFF1 | PAIR | 8 | 6.88 | 5 | 10 | 5 | 50 | 20 | 36 | 12 | 12 | 20 | 12 | 5.13 | 85 Ohms | TOP=L2:L3=L2/L4:L6=L5/L7:BOTTOM=L7 |
| PE_RX2_DR6_P | PE_RX2_DR6-DIFF1 | PAIR | 1 | 6.88 | 5 | 10 | 5 | 50 | 20 | 36 | 12 | 12 | 20 | 12 | 5.13 | 85 Ohms | TOP=L2:L3=L2/L4:L6=L5/L7:BOTTOM=L7 |
| PE_RX2_DR6_P | PE_RX2_DR6-DIFF1 | PAIR | 2 | 6.5 | 5 | 10 | 5 | 50 | 20 | 25 | 12 | 12 | 20 | 12 | 7.5 | 85 Ohms | TOP=L2:L3=L2/L4:L6=L5/L7:BOTTOM=L7 |
| PE_RX2_DR6_P | PE_RX2_DR6-DIFF1 | PAIR | 3 | 6.5 | 5 | 10 | 5 | 50 | 20 | 25 | 12 | 12 | 20 | 12 | 7.5 | 85 Ohms | TOP=L2:L3=L2/L4:L6=L5/L7:BOTTOM=L7 |
| PE_RX2_DR6_P | PE_RX2_DR6-DIFF1 | PAIR | 4 | 6.5 | 5 | 10 | 5 | 50 | 20 | 25 | 12 | 12 | 20 | 12 | 7.5 | 85 Ohms | TOP=L2:L3=L2/L4:L6=L5/L7:BOTTOM=L7 |
| PE_RX2_DR6_P | PE_RX2_DR6-DIFF1 | PAIR | 5 | 6.5 | 5 | 10 | 5 | 50 | 20 | 25 | 12 | 12 | 20 | 12 | 7.5 | 85 Ohms | TOP=L2:L3=L2/L4:L6=L5/L7:BOTTOM=L7 |
| PE_RX2_DR6_P | PE_RX2_DR6-DIFF1 | PAIR | 6 | 6.5 | 5 | 10 | 5 | 50 | 20 | 25 | 12 | 12 | 20 | 12 | 7.5 | 85 Ohms | TOP=L2:L3=L2/L4:L6=L5/L7:BOTTOM=L7 |
| PE_RX2_DR6_P | PE_RX2_DR6-DIFF1 | PAIR | 7 | 6.5 | 5 | 10 | 5 | 50 | 20 | 25 | 12 | 12 | 20 | 12 | 7.5 | 85 Ohms | TOP=L2:L3=L2/L4:L6=L5/L7:BOTTOM=L7 |
| PE_RX2_DR6_P | PE_RX2_DR6-DIFF1 | PAIR | 8 | 6.88 | 5 | 10 | 5 | 50 | 20 | 36 | 12 | 12 | 20 | 12 | 5.13 | 85 Ohms | TOP=L2:L3=L2/L4:L6=L5/L7:BOTTOM=L7 |
| PE_RX2_DR7_N | PE_RX2_DR7-DIFF1 | PAIR | 1 | 6.88 | 5 | 10 | 5 | 50 | 20 | 36 | 12 | 12 | 20 | 12 | 5.13 | 85 Ohms | TOP=L2:L3=L2/L4:L6=L5/L7:BOTTOM=L7 |
| PE_RX2_DR7_N | PE_RX2_DR7-DIFF1 | PAIR | 2 | 6.5 | 5 | 10 | 5 | 50 | 20 | 25 | 12 | 12 | 20 | 12 | 7.5 | 85 Ohms | TOP=L2:L3=L2/L4:L6=L5/L7:BOTTOM=L7 |
| PE_RX2_DR7_N | PE_RX2_DR7-DIFF1 | PAIR | 3 | 6.5 | 5 | 10 | 5 | 50 | 20 | 25 | 12 | 12 | 20 | 12 | 7.5 | 85 Ohms | TOP=L2:L3=L2/L4:L6=L5/L7:BOTTOM=L7 |
| PE_RX2_DR7_N | PE_RX2_DR7-DIFF1 | PAIR | 4 | 6.5 | 5 | 10 | 5 | 50 | 20 | 25 | 12 | 12 | 20 | 12 | 7.5 | 85 Ohms | TOP=L2:L3=L2/L4:L6=L5/L7:BOTTOM=L7 |
| PE_RX2_DR7_N | PE_RX2_DR7-DIFF1 | PAIR | 5 | 6.5 | 5 | 10 | 5 | 50 | 20 | 25 | 12 | 12 | 20 | 12 | 7.5 | 85 Ohms | TOP=L2:L3=L2/L4:L6=L5/L7:BOTTOM=L7 |
| PE_RX2_DR7_N | PE_RX2_DR7-DIFF1 | PAIR | 6 | 6.5 | 5 | 10 | 5 | 50 | 20 | 25 | 12 | 12 | 20 | 12 | 7.5 | 85 Ohms | TOP=L2:L3=L2/L4:L6=L5/L7:BOTTOM=L7 |
| PE_RX2_DR7_N | PE_RX2_DR7-DIFF1 | PAIR | 7 | 6.5 | 5 | 10 | 5 | 50 | 20 | 25 | 12 | 12 | 20 | 12 | 7.5 | 85 Ohms | TOP=L2:L3=L2/L4:L6=L5/L7:BOTTOM=L7 |
| PE_RX2_DR7_N | PE_RX2_DR7-DIFF1 | PAIR | 8 | 6.88 | 5 | 10 | 5 | 50 | 20 | 36 | 12 | 12 | 20 | 12 | 5.13 | 85 Ohms | TOP=L2:L3=L2/L4:L6=L5/L7:BOTTOM=L7 |
| PE_RX2_DR7_P | PE_RX2_DR7-DIFF1 | PAIR | 1 | 6.88 | 5 | 10 | 5 | 50 | 20 | 36 | 12 | 12 | 20 | 12 | 5.13 | 85 Ohms | TOP=L2:L3=L2/L4:L6=L5/L7:BOTTOM=L7 |
| PE_RX2_DR7_P | PE_RX2_DR7-DIFF1 | PAIR | 2 | 6.5 | 5 | 10 | 5 | 50 | 20 | 25 | 12 | 12 | 20 | 12 | 7.5 | 85 Ohms | TOP=L2:L3=L2/L4:L6=L5/L7:BOTTOM=L7 |
| PE_RX2_DR7_P | PE_RX2_DR7-DIFF1 | PAIR | 3 | 6.5 | 5 | 10 | 5 | 50 | 20 | 25 | 12 | 12 | 20 | 12 | 7.5 | 85 Ohms | TOP=L2:L3=L2/L4:L6=L5/L7:BOTTOM=L7 |
| PE_RX2_DR7_P | PE_RX2_DR7-DIFF1 | PAIR | 4 | 6.5 | 5 | 10 | 5 | 50 | 20 | 25 | 12 | 12 | 20 | 12 | 7.5 | 85 Ohms | TOP=L2:L3=L2/L4:L6=L5/L7:BOTTOM=L7 |
| PE_RX2_DR7_P | PE_RX2_DR7-DIFF1 | PAIR | 5 | 6.5 | 5 | 10 | 5 | 50 | 20 | 25 | 12 | 12 | 20 | 12 | 7.5 | 85 Ohms | TOP=L2:L3=L2/L4:L6=L5/L7:BOTTOM=L7 |
| PE_RX2_DR7_P | PE_RX2_DR7-DIFF1 | PAIR | 6 | 6.5 | 5 | 10 | 5 | 50 | 20 | 25 | 12 | 12 | 20 | 12 | 7.5 | 85 Ohms | TOP=L2:L3=L2/L4:L6=L5/L7:BOTTOM=L7 |
| PE_RX2_DR7_P | PE_RX2_DR7-DIFF1 | PAIR | 7 | 6.5 | 5 | 10 | 5 | 50 | 20 | 25 | 12 | 12 | 20 | 12 | 7.5 | 85 Ohms | TOP=L2:L3=L2/L4:L6=L5/L7:BOTTOM=L7 |
| PE_RX2_DR7_P | PE_RX2_DR7-DIFF1 | PAIR | 8 | 6.88 | 5 | 10 | 5 | 50 | 20 | 36 | 12 | 12 | 20 | 12 | 5.13 | 85 Ohms | TOP=L2:L3=L2/L4:L6=L5/L7:BOTTOM=L7 |
| PE_RX2_DR8_N | PE_RX2_DR8-DIFF1 | PAIR | 1 | 6.88 | 5 | 10 | 5 | 50 | 20 | 36 | 12 | 12 | 20 | 12 | 5.13 | 85 Ohms | TOP=L2:L3=L2/L4:L6=L5/L7:BOTTOM=L7 |
| PE_RX2_DR8_N | PE_RX2_DR8-DIFF1 | PAIR | 2 | 6.5 | 5 | 10 | 5 | 50 | 20 | 25 | 12 | 12 | 20 | 12 | 7.5 | 85 Ohms | TOP=L2:L3=L2/L4:L6=L5/L7:BOTTOM=L7 |
| PE_RX2_DR8_N | PE_RX2_DR8-DIFF1 | PAIR | 3 | 6.5 | 5 | 10 | 5 | 50 | 20 | 25 | 12 | 12 | 20 | 12 | 7.5 | 85 Ohms | TOP=L2:L3=L2/L4:L6=L5/L7:BOTTOM=L7 |
| PE_RX2_DR8_N | PE_RX2_DR8-DIFF1 | PAIR | 4 | 6.5 | 5 | 10 | 5 | 50 | 20 | 25 | 12 | 12 | 20 | 12 | 7.5 | 85 Ohms | TOP=L2:L3=L2/L4:L6=L5/L7:BOTTOM=L7 |
| PE_RX2_DR8_N | PE_RX2_DR8-DIFF1 | PAIR | 5 | 6.5 | 5 | 10 | 5 | 50 | 20 | 25 | 12 | 12 | 20 | 12 | 7.5 | 85 Ohms | TOP=L2:L3=L2/L4:L6=L5/L7:BOTTOM=L7 |
| PE_RX2_DR8_N | PE_RX2_DR8-DIFF1 | PAIR | 6 | 6.5 | 5 | 10 | 5 | 50 | 20 | 25 | 12 | 12 | 20 | 12 | 7.5 | 85 Ohms | TOP=L2:L3=L2/L4:L6=L5/L7:BOTTOM=L7 |
| PE_RX2_DR8_N | PE_RX2_DR8-DIFF1 | PAIR | 7 | 6.5 | 5 | 10 | 5 | 50 | 20 | 25 | 12 | 12 | 20 | 12 | 7.5 | 85 Ohms | TOP=L2:L3=L2/L4:L6=L5/L7:BOTTOM=L7 |
| PE_RX2_DR8_N | PE_RX2_DR8-DIFF1 | PAIR | 8 | 6.88 | 5 | 10 | 5 | 50 | 20 | 36 | 12 | 12 | 20 | 12 | 5.13 | 85 Ohms | TOP=L2:L3=L2/L4:L6=L5/L7:BOTTOM=L7 |
| PE_RX2_DR8_P | PE_RX2_DR8-DIFF1 | PAIR | 1 | 6.88 | 5 | 10 | 5 | 50 | 20 | 36 | 12 | 12 | 20 | 12 | 5.13 | 85 Ohms | TOP=L2:L3=L2/L4:L6=L5/L7:BOTTOM=L7 |
| PE_RX2_DR8_P | PE_RX2_DR8-DIFF1 | PAIR | 2 | 6.5 | 5 | 10 | 5 | 50 | 20 | 25 | 12 | 12 | 20 | 12 | 7.5 | 85 Ohms | TOP=L2:L3=L2/L4:L6=L5/L7:BOTTOM=L7 |
| PE_RX2_DR8_P | PE_RX2_DR8-DIFF1 | PAIR | 3 | 6.5 | 5 | 10 | 5 | 50 | 20 | 25 | 12 | 12 | 20 | 12 | 7.5 | 85 Ohms | TOP=L2:L3=L2/L4:L6=L5/L7:BOTTOM=L7 |
| PE_RX2_DR8_P | PE_RX2_DR8-DIFF1 | PAIR | 4 | 6.5 | 5 | 10 | 5 | 50 | 20 | 25 | 12 | 12 | 20 | 12 | 7.5 | 85 Ohms | TOP=L2:L3=L2/L4:L6=L5/L7:BOTTOM=L7 |
| PE_RX2_DR8_P | PE_RX2_DR8-DIFF1 | PAIR | 5 | 6.5 | 5 | 10 | 5 | 50 | 20 | 25 | 12 | 12 | 20 | 12 | 7.5 | 85 Ohms | TOP=L2:L3=L2/L4:L6=L5/L7:BOTTOM=L7 |
| PE_RX2_DR8_P | PE_RX2_DR8-DIFF1 | PAIR | 6 | 6.5 | 5 | 10 | 5 | 50 | 20 | 25 | 12 | 12 | 20 | 12 | 7.5 | 85 Ohms | TOP=L2:L3=L2/L4:L6=L5/L7:BOTTOM=L7 |
| PE_RX2_DR8_P | PE_RX2_DR8-DIFF1 | PAIR | 7 | 6.5 | 5 | 10 | 5 | 50 | 20 | 25 | 12 | 12 | 20 | 12 | 7.5 | 85 Ohms | TOP=L2:L3=L2/L4:L6=L5/L7:BOTTOM=L7 |
| PE_RX2_DR8_P | PE_RX2_DR8-DIFF1 | PAIR | 8 | 6.88 | 5 | 10 | 5 | 50 | 20 | 36 | 12 | 12 | 20 | 12 | 5.13 | 85 Ohms | TOP=L2:L3=L2/L4:L6=L5/L7:BOTTOM=L7 |
| PE_RX2_DR9_N | PE_RX2_DR9-DIFF1 | PAIR | 1 | 6.88 | 5 | 10 | 5 | 50 | 20 | 36 | 12 | 12 | 20 | 12 | 5.13 | 85 Ohms | TOP=L2:L3=L2/L4:L6=L5/L7:BOTTOM=L7 |
| PE_RX2_DR9_N | PE_RX2_DR9-DIFF1 | PAIR | 2 | 6.5 | 5 | 10 | 5 | 50 | 20 | 25 | 12 | 12 | 20 | 12 | 7.5 | 85 Ohms | TOP=L2:L3=L2/L4:L6=L5/L7:BOTTOM=L7 |
| PE_RX2_DR9_N | PE_RX2_DR9-DIFF1 | PAIR | 3 | 6.5 | 5 | 10 | 5 | 50 | 20 | 25 | 12 | 12 | 20 | 12 | 7.5 | 85 Ohms | TOP=L2:L3=L2/L4:L6=L5/L7:BOTTOM=L7 |
| PE_RX2_DR9_N | PE_RX2_DR9-DIFF1 | PAIR | 4 | 6.5 | 5 | 10 | 5 | 50 | 20 | 25 | 12 | 12 | 20 | 12 | 7.5 | 85 Ohms | TOP=L2:L3=L2/L4:L6=L5/L7:BOTTOM=L7 |
| PE_RX2_DR9_N | PE_RX2_DR9-DIFF1 | PAIR | 5 | 6.5 | 5 | 10 | 5 | 50 | 20 | 25 | 12 | 12 | 20 | 12 | 7.5 | 85 Ohms | TOP=L2:L3=L2/L4:L6=L5/L7:BOTTOM=L7 |
| PE_RX2_DR9_N | PE_RX2_DR9-DIFF1 | PAIR | 6 | 6.5 | 5 | 10 | 5 | 50 | 20 | 25 | 12 | 12 | 20 | 12 | 7.5 | 85 Ohms | TOP=L2:L3=L2/L4:L6=L5/L7:BOTTOM=L7 |
| PE_RX2_DR9_N | PE_RX2_DR9-DIFF1 | PAIR | 7 | 6.5 | 5 | 10 | 5 | 50 | 20 | 25 | 12 | 12 | 20 | 12 | 7.5 | 85 Ohms | TOP=L2:L3=L2/L4:L6=L5/L7:BOTTOM=L7 |
| PE_RX2_DR9_N | PE_RX2_DR9-DIFF1 | PAIR | 8 | 6.88 | 5 | 10 | 5 | 50 | 20 | 36 | 12 | 12 | 20 | 12 | 5.13 | 85 Ohms | TOP=L2:L3=L2/L4:L6=L5/L7:BOTTOM=L7 |
| PE_RX2_DR9_P | PE_RX2_DR9-DIFF1 | PAIR | 1 | 6.88 | 5 | 10 | 5 | 50 | 20 | 36 | 12 | 12 | 20 | 12 | 5.13 | 85 Ohms | TOP=L2:L3=L2/L4:L6=L5/L7:BOTTOM=L7 |
| PE_RX2_DR9_P | PE_RX2_DR9-DIFF1 | PAIR | 2 | 6.5 | 5 | 10 | 5 | 50 | 20 | 25 | 12 | 12 | 20 | 12 | 7.5 | 85 Ohms | TOP=L2:L3=L2/L4:L6=L5/L7:BOTTOM=L7 |
| PE_RX2_DR9_P | PE_RX2_DR9-DIFF1 | PAIR | 3 | 6.5 | 5 | 10 | 5 | 50 | 20 | 25 | 12 | 12 | 20 | 12 | 7.5 | 85 Ohms | TOP=L2:L3=L2/L4:L6=L5/L7:BOTTOM=L7 |
| PE_RX2_DR9_P | PE_RX2_DR9-DIFF1 | PAIR | 4 | 6.5 | 5 | 10 | 5 | 50 | 20 | 25 | 12 | 12 | 20 | 12 | 7.5 | 85 Ohms | TOP=L2:L3=L2/L4:L6=L5/L7:BOTTOM=L7 |
| PE_RX2_DR9_P | PE_RX2_DR9-DIFF1 | PAIR | 5 | 6.5 | 5 | 10 | 5 | 50 | 20 | 25 | 12 | 12 | 20 | 12 | 7.5 | 85 Ohms | TOP=L2:L3=L2/L4:L6=L5/L7:BOTTOM=L7 |
| PE_RX2_DR9_P | PE_RX2_DR9-DIFF1 | PAIR | 6 | 6.5 | 5 | 10 | 5 | 50 | 20 | 25 | 12 | 12 | 20 | 12 | 7.5 | 85 Ohms | TOP=L2:L3=L2/L4:L6=L5/L7:BOTTOM=L7 |
| PE_RX2_DR9_P | PE_RX2_DR9-DIFF1 | PAIR | 7 | 6.5 | 5 | 10 | 5 | 50 | 20 | 25 | 12 | 12 | 20 | 12 | 7.5 | 85 Ohms | TOP=L2:L3=L2/L4:L6=L5/L7:BOTTOM=L7 |
| PE_RX2_DR9_P | PE_RX2_DR9-DIFF1 | PAIR | 8 | 6.88 | 5 | 10 | 5 | 50 | 20 | 36 | 12 | 12 | 20 | 12 | 5.13 | 85 Ohms | TOP=L2:L3=L2/L4:L6=L5/L7:BOTTOM=L7 |
| PE_RX3_DR0_N | PE_RX3_DR0-DIFF1 | PAIR | 1 | 6.88 | 5 | 10 | 5 | 50 | 20 | 36 | 12 | 12 | 20 | 12 | 5.13 | 85 Ohms | TOP=L2:L3=L2/L4:L6=L5/L7:BOTTOM=L7 |
| PE_RX3_DR0_N | PE_RX3_DR0-DIFF1 | PAIR | 2 | 6.5 | 5 | 10 | 5 | 50 | 20 | 25 | 12 | 12 | 20 | 12 | 7.5 | 85 Ohms | TOP=L2:L3=L2/L4:L6=L5/L7:BOTTOM=L7 |
| PE_RX3_DR0_N | PE_RX3_DR0-DIFF1 | PAIR | 3 | 6.5 | 5 | 10 | 5 | 50 | 20 | 25 | 12 | 12 | 20 | 12 | 7.5 | 85 Ohms | TOP=L2:L3=L2/L4:L6=L5/L7:BOTTOM=L7 |
| PE_RX3_DR0_N | PE_RX3_DR0-DIFF1 | PAIR | 4 | 6.5 | 5 | 10 | 5 | 50 | 20 | 25 | 12 | 12 | 20 | 12 | 7.5 | 85 Ohms | TOP=L2:L3=L2/L4:L6=L5/L7:BOTTOM=L7 |
| PE_RX3_DR0_N | PE_RX3_DR0-DIFF1 | PAIR | 5 | 6.5 | 5 | 10 | 5 | 50 | 20 | 25 | 12 | 12 | 20 | 12 | 7.5 | 85 Ohms | TOP=L2:L3=L2/L4:L6=L5/L7:BOTTOM=L7 |
| PE_RX3_DR0_N | PE_RX3_DR0-DIFF1 | PAIR | 6 | 6.5 | 5 | 10 | 5 | 50 | 20 | 25 | 12 | 12 | 20 | 12 | 7.5 | 85 Ohms | TOP=L2:L3=L2/L4:L6=L5/L7:BOTTOM=L7 |
| PE_RX3_DR0_N | PE_RX3_DR0-DIFF1 | PAIR | 7 | 6.5 | 5 | 10 | 5 | 50 | 20 | 25 | 12 | 12 | 20 | 12 | 7.5 | 85 Ohms | TOP=L2:L3=L2/L4:L6=L5/L7:BOTTOM=L7 |
| PE_RX3_DR0_N | PE_RX3_DR0-DIFF1 | PAIR | 8 | 6.88 | 5 | 10 | 5 | 50 | 20 | 36 | 12 | 12 | 20 | 12 | 5.13 | 85 Ohms | TOP=L2:L3=L2/L4:L6=L5/L7:BOTTOM=L7 |
| PE_RX3_DR0_P | PE_RX3_DR0-DIFF1 | PAIR | 1 | 6.88 | 5 | 10 | 5 | 50 | 20 | 36 | 12 | 12 | 20 | 12 | 5.13 | 85 Ohms | TOP=L2:L3=L2/L4:L6=L5/L7:BOTTOM=L7 |
| PE_RX3_DR0_P | PE_RX3_DR0-DIFF1 | PAIR | 2 | 6.5 | 5 | 10 | 5 | 50 | 20 | 25 | 12 | 12 | 20 | 12 | 7.5 | 85 Ohms | TOP=L2:L3=L2/L4:L6=L5/L7:BOTTOM=L7 |
| PE_RX3_DR0_P | PE_RX3_DR0-DIFF1 | PAIR | 3 | 6.5 | 5 | 10 | 5 | 50 | 20 | 25 | 12 | 12 | 20 | 12 | 7.5 | 85 Ohms | TOP=L2:L3=L2/L4:L6=L5/L7:BOTTOM=L7 |
| PE_RX3_DR0_P | PE_RX3_DR0-DIFF1 | PAIR | 4 | 6.5 | 5 | 10 | 5 | 50 | 20 | 25 | 12 | 12 | 20 | 12 | 7.5 | 85 Ohms | TOP=L2:L3=L2/L4:L6=L5/L7:BOTTOM=L7 |
| PE_RX3_DR0_P | PE_RX3_DR0-DIFF1 | PAIR | 5 | 6.5 | 5 | 10 | 5 | 50 | 20 | 25 | 12 | 12 | 20 | 12 | 7.5 | 85 Ohms | TOP=L2:L3=L2/L4:L6=L5/L7:BOTTOM=L7 |
| PE_RX3_DR0_P | PE_RX3_DR0-DIFF1 | PAIR | 6 | 6.5 | 5 | 10 | 5 | 50 | 20 | 25 | 12 | 12 | 20 | 12 | 7.5 | 85 Ohms | TOP=L2:L3=L2/L4:L6=L5/L7:BOTTOM=L7 |
| PE_RX3_DR0_P | PE_RX3_DR0-DIFF1 | PAIR | 7 | 6.5 | 5 | 10 | 5 | 50 | 20 | 25 | 12 | 12 | 20 | 12 | 7.5 | 85 Ohms | TOP=L2:L3=L2/L4:L6=L5/L7:BOTTOM=L7 |
| PE_RX3_DR0_P | PE_RX3_DR0-DIFF1 | PAIR | 8 | 6.88 | 5 | 10 | 5 | 50 | 20 | 36 | 12 | 12 | 20 | 12 | 5.13 | 85 Ohms | TOP=L2:L3=L2/L4:L6=L5/L7:BOTTOM=L7 |
| PE_RX3_DR10_N | PE_RX3_DR10-DIFF1 | PAIR | 1 | 6.88 | 5 | 10 | 5 | 50 | 20 | 36 | 12 | 12 | 20 | 12 | 5.13 | 85 Ohms | TOP=L2:L3=L2/L4:L6=L5/L7:BOTTOM=L7 |
| PE_RX3_DR10_N | PE_RX3_DR10-DIFF1 | PAIR | 2 | 6.5 | 5 | 10 | 5 | 50 | 20 | 25 | 12 | 12 | 20 | 12 | 7.5 | 85 Ohms | TOP=L2:L3=L2/L4:L6=L5/L7:BOTTOM=L7 |
| PE_RX3_DR10_N | PE_RX3_DR10-DIFF1 | PAIR | 3 | 6.5 | 5 | 10 | 5 | 50 | 20 | 25 | 12 | 12 | 20 | 12 | 7.5 | 85 Ohms | TOP=L2:L3=L2/L4:L6=L5/L7:BOTTOM=L7 |
| PE_RX3_DR10_N | PE_RX3_DR10-DIFF1 | PAIR | 4 | 6.5 | 5 | 10 | 5 | 50 | 20 | 25 | 12 | 12 | 20 | 12 | 7.5 | 85 Ohms | TOP=L2:L3=L2/L4:L6=L5/L7:BOTTOM=L7 |
| PE_RX3_DR10_N | PE_RX3_DR10-DIFF1 | PAIR | 5 | 6.5 | 5 | 10 | 5 | 50 | 20 | 25 | 12 | 12 | 20 | 12 | 7.5 | 85 Ohms | TOP=L2:L3=L2/L4:L6=L5/L7:BOTTOM=L7 |
| PE_RX3_DR10_N | PE_RX3_DR10-DIFF1 | PAIR | 6 | 6.5 | 5 | 10 | 5 | 50 | 20 | 25 | 12 | 12 | 20 | 12 | 7.5 | 85 Ohms | TOP=L2:L3=L2/L4:L6=L5/L7:BOTTOM=L7 |
| PE_RX3_DR10_N | PE_RX3_DR10-DIFF1 | PAIR | 7 | 6.5 | 5 | 10 | 5 | 50 | 20 | 25 | 12 | 12 | 20 | 12 | 7.5 | 85 Ohms | TOP=L2:L3=L2/L4:L6=L5/L7:BOTTOM=L7 |
| PE_RX3_DR10_N | PE_RX3_DR10-DIFF1 | PAIR | 8 | 6.88 | 5 | 10 | 5 | 50 | 20 | 36 | 12 | 12 | 20 | 12 | 5.13 | 85 Ohms | TOP=L2:L3=L2/L4:L6=L5/L7:BOTTOM=L7 |
| PE_RX3_DR10_P | PE_RX3_DR10-DIFF1 | PAIR | 1 | 6.88 | 5 | 10 | 5 | 50 | 20 | 36 | 12 | 12 | 20 | 12 | 5.13 | 85 Ohms | TOP=L2:L3=L2/L4:L6=L5/L7:BOTTOM=L7 |
| PE_RX3_DR10_P | PE_RX3_DR10-DIFF1 | PAIR | 2 | 6.5 | 5 | 10 | 5 | 50 | 20 | 25 | 12 | 12 | 20 | 12 | 7.5 | 85 Ohms | TOP=L2:L3=L2/L4:L6=L5/L7:BOTTOM=L7 |
| PE_RX3_DR10_P | PE_RX3_DR10-DIFF1 | PAIR | 3 | 6.5 | 5 | 10 | 5 | 50 | 20 | 25 | 12 | 12 | 20 | 12 | 7.5 | 85 Ohms | TOP=L2:L3=L2/L4:L6=L5/L7:BOTTOM=L7 |
| PE_RX3_DR10_P | PE_RX3_DR10-DIFF1 | PAIR | 4 | 6.5 | 5 | 10 | 5 | 50 | 20 | 25 | 12 | 12 | 20 | 12 | 7.5 | 85 Ohms | TOP=L2:L3=L2/L4:L6=L5/L7:BOTTOM=L7 |
| PE_RX3_DR10_P | PE_RX3_DR10-DIFF1 | PAIR | 5 | 6.5 | 5 | 10 | 5 | 50 | 20 | 25 | 12 | 12 | 20 | 12 | 7.5 | 85 Ohms | TOP=L2:L3=L2/L4:L6=L5/L7:BOTTOM=L7 |
| PE_RX3_DR10_P | PE_RX3_DR10-DIFF1 | PAIR | 6 | 6.5 | 5 | 10 | 5 | 50 | 20 | 25 | 12 | 12 | 20 | 12 | 7.5 | 85 Ohms | TOP=L2:L3=L2/L4:L6=L5/L7:BOTTOM=L7 |
| PE_RX3_DR10_P | PE_RX3_DR10-DIFF1 | PAIR | 7 | 6.5 | 5 | 10 | 5 | 50 | 20 | 25 | 12 | 12 | 20 | 12 | 7.5 | 85 Ohms | TOP=L2:L3=L2/L4:L6=L5/L7:BOTTOM=L7 |
| PE_RX3_DR10_P | PE_RX3_DR10-DIFF1 | PAIR | 8 | 6.88 | 5 | 10 | 5 | 50 | 20 | 36 | 12 | 12 | 20 | 12 | 5.13 | 85 Ohms | TOP=L2:L3=L2/L4:L6=L5/L7:BOTTOM=L7 |
| PE_RX3_DR11_N | PE_RX3_DR11-DIFF1 | PAIR | 1 | 6.88 | 5 | 10 | 5 | 50 | 20 | 36 | 12 | 12 | 20 | 12 | 5.13 | 85 Ohms | TOP=L2:L3=L2/L4:L6=L5/L7:BOTTOM=L7 |
| PE_RX3_DR11_N | PE_RX3_DR11-DIFF1 | PAIR | 2 | 6.5 | 5 | 10 | 5 | 50 | 20 | 25 | 12 | 12 | 20 | 12 | 7.5 | 85 Ohms | TOP=L2:L3=L2/L4:L6=L5/L7:BOTTOM=L7 |
| PE_RX3_DR11_N | PE_RX3_DR11-DIFF1 | PAIR | 3 | 6.5 | 5 | 10 | 5 | 50 | 20 | 25 | 12 | 12 | 20 | 12 | 7.5 | 85 Ohms | TOP=L2:L3=L2/L4:L6=L5/L7:BOTTOM=L7 |
| PE_RX3_DR11_N | PE_RX3_DR11-DIFF1 | PAIR | 4 | 6.5 | 5 | 10 | 5 | 50 | 20 | 25 | 12 | 12 | 20 | 12 | 7.5 | 85 Ohms | TOP=L2:L3=L2/L4:L6=L5/L7:BOTTOM=L7 |
| PE_RX3_DR11_N | PE_RX3_DR11-DIFF1 | PAIR | 5 | 6.5 | 5 | 10 | 5 | 50 | 20 | 25 | 12 | 12 | 20 | 12 | 7.5 | 85 Ohms | TOP=L2:L3=L2/L4:L6=L5/L7:BOTTOM=L7 |
| PE_RX3_DR11_N | PE_RX3_DR11-DIFF1 | PAIR | 6 | 6.5 | 5 | 10 | 5 | 50 | 20 | 25 | 12 | 12 | 20 | 12 | 7.5 | 85 Ohms | TOP=L2:L3=L2/L4:L6=L5/L7:BOTTOM=L7 |
| PE_RX3_DR11_N | PE_RX3_DR11-DIFF1 | PAIR | 7 | 6.5 | 5 | 10 | 5 | 50 | 20 | 25 | 12 | 12 | 20 | 12 | 7.5 | 85 Ohms | TOP=L2:L3=L2/L4:L6=L5/L7:BOTTOM=L7 |
| PE_RX3_DR11_N | PE_RX3_DR11-DIFF1 | PAIR | 8 | 6.88 | 5 | 10 | 5 | 50 | 20 | 36 | 12 | 12 | 20 | 12 | 5.13 | 85 Ohms | TOP=L2:L3=L2/L4:L6=L5/L7:BOTTOM=L7 |
| PE_RX3_DR11_P | PE_RX3_DR11-DIFF1 | PAIR | 1 | 6.88 | 5 | 10 | 5 | 50 | 20 | 36 | 12 | 12 | 20 | 12 | 5.13 | 85 Ohms | TOP=L2:L3=L2/L4:L6=L5/L7:BOTTOM=L7 |
| PE_RX3_DR11_P | PE_RX3_DR11-DIFF1 | PAIR | 2 | 6.5 | 5 | 10 | 5 | 50 | 20 | 25 | 12 | 12 | 20 | 12 | 7.5 | 85 Ohms | TOP=L2:L3=L2/L4:L6=L5/L7:BOTTOM=L7 |
| PE_RX3_DR11_P | PE_RX3_DR11-DIFF1 | PAIR | 3 | 6.5 | 5 | 10 | 5 | 50 | 20 | 25 | 12 | 12 | 20 | 12 | 7.5 | 85 Ohms | TOP=L2:L3=L2/L4:L6=L5/L7:BOTTOM=L7 |
| PE_RX3_DR11_P | PE_RX3_DR11-DIFF1 | PAIR | 4 | 6.5 | 5 | 10 | 5 | 50 | 20 | 25 | 12 | 12 | 20 | 12 | 7.5 | 85 Ohms | TOP=L2:L3=L2/L4:L6=L5/L7:BOTTOM=L7 |
| PE_RX3_DR11_P | PE_RX3_DR11-DIFF1 | PAIR | 5 | 6.5 | 5 | 10 | 5 | 50 | 20 | 25 | 12 | 12 | 20 | 12 | 7.5 | 85 Ohms | TOP=L2:L3=L2/L4:L6=L5/L7:BOTTOM=L7 |
| PE_RX3_DR11_P | PE_RX3_DR11-DIFF1 | PAIR | 6 | 6.5 | 5 | 10 | 5 | 50 | 20 | 25 | 12 | 12 | 20 | 12 | 7.5 | 85 Ohms | TOP=L2:L3=L2/L4:L6=L5/L7:BOTTOM=L7 |
| PE_RX3_DR11_P | PE_RX3_DR11-DIFF1 | PAIR | 7 | 6.5 | 5 | 10 | 5 | 50 | 20 | 25 | 12 | 12 | 20 | 12 | 7.5 | 85 Ohms | TOP=L2:L3=L2/L4:L6=L5/L7:BOTTOM=L7 |
| PE_RX3_DR11_P | PE_RX3_DR11-DIFF1 | PAIR | 8 | 6.88 | 5 | 10 | 5 | 50 | 20 | 36 | 12 | 12 | 20 | 12 | 5.13 | 85 Ohms | TOP=L2:L3=L2/L4:L6=L5/L7:BOTTOM=L7 |
| PE_RX3_DR12_N | PE_RX3_DR12-DIFF1 | PAIR | 1 | 6.88 | 5 | 10 | 5 | 50 | 20 | 36 | 12 | 12 | 20 | 12 | 5.13 | 85 Ohms | TOP=L2:L3=L2/L4:L6=L5/L7:BOTTOM=L7 |
| PE_RX3_DR12_N | PE_RX3_DR12-DIFF1 | PAIR | 2 | 6.5 | 5 | 10 | 5 | 50 | 20 | 25 | 12 | 12 | 20 | 12 | 7.5 | 85 Ohms | TOP=L2:L3=L2/L4:L6=L5/L7:BOTTOM=L7 |
| PE_RX3_DR12_N | PE_RX3_DR12-DIFF1 | PAIR | 3 | 6.5 | 5 | 10 | 5 | 50 | 20 | 25 | 12 | 12 | 20 | 12 | 7.5 | 85 Ohms | TOP=L2:L3=L2/L4:L6=L5/L7:BOTTOM=L7 |
| PE_RX3_DR12_N | PE_RX3_DR12-DIFF1 | PAIR | 4 | 6.5 | 5 | 10 | 5 | 50 | 20 | 25 | 12 | 12 | 20 | 12 | 7.5 | 85 Ohms | TOP=L2:L3=L2/L4:L6=L5/L7:BOTTOM=L7 |
| PE_RX3_DR12_N | PE_RX3_DR12-DIFF1 | PAIR | 5 | 6.5 | 5 | 10 | 5 | 50 | 20 | 25 | 12 | 12 | 20 | 12 | 7.5 | 85 Ohms | TOP=L2:L3=L2/L4:L6=L5/L7:BOTTOM=L7 |
| PE_RX3_DR12_N | PE_RX3_DR12-DIFF1 | PAIR | 6 | 6.5 | 5 | 10 | 5 | 50 | 20 | 25 | 12 | 12 | 20 | 12 | 7.5 | 85 Ohms | TOP=L2:L3=L2/L4:L6=L5/L7:BOTTOM=L7 |
| PE_RX3_DR12_N | PE_RX3_DR12-DIFF1 | PAIR | 7 | 6.5 | 5 | 10 | 5 | 50 | 20 | 25 | 12 | 12 | 20 | 12 | 7.5 | 85 Ohms | TOP=L2:L3=L2/L4:L6=L5/L7:BOTTOM=L7 |
| PE_RX3_DR12_N | PE_RX3_DR12-DIFF1 | PAIR | 8 | 6.88 | 5 | 10 | 5 | 50 | 20 | 36 | 12 | 12 | 20 | 12 | 5.13 | 85 Ohms | TOP=L2:L3=L2/L4:L6=L5/L7:BOTTOM=L7 |
| PE_RX3_DR12_P | PE_RX3_DR12-DIFF1 | PAIR | 1 | 6.88 | 5 | 10 | 5 | 50 | 20 | 36 | 12 | 12 | 20 | 12 | 5.13 | 85 Ohms | TOP=L2:L3=L2/L4:L6=L5/L7:BOTTOM=L7 |
| PE_RX3_DR12_P | PE_RX3_DR12-DIFF1 | PAIR | 2 | 6.5 | 5 | 10 | 5 | 50 | 20 | 25 | 12 | 12 | 20 | 12 | 7.5 | 85 Ohms | TOP=L2:L3=L2/L4:L6=L5/L7:BOTTOM=L7 |
| PE_RX3_DR12_P | PE_RX3_DR12-DIFF1 | PAIR | 3 | 6.5 | 5 | 10 | 5 | 50 | 20 | 25 | 12 | 12 | 20 | 12 | 7.5 | 85 Ohms | TOP=L2:L3=L2/L4:L6=L5/L7:BOTTOM=L7 |
| PE_RX3_DR12_P | PE_RX3_DR12-DIFF1 | PAIR | 4 | 6.5 | 5 | 10 | 5 | 50 | 20 | 25 | 12 | 12 | 20 | 12 | 7.5 | 85 Ohms | TOP=L2:L3=L2/L4:L6=L5/L7:BOTTOM=L7 |
| PE_RX3_DR12_P | PE_RX3_DR12-DIFF1 | PAIR | 5 | 6.5 | 5 | 10 | 5 | 50 | 20 | 25 | 12 | 12 | 20 | 12 | 7.5 | 85 Ohms | TOP=L2:L3=L2/L4:L6=L5/L7:BOTTOM=L7 |
| PE_RX3_DR12_P | PE_RX3_DR12-DIFF1 | PAIR | 6 | 6.5 | 5 | 10 | 5 | 50 | 20 | 25 | 12 | 12 | 20 | 12 | 7.5 | 85 Ohms | TOP=L2:L3=L2/L4:L6=L5/L7:BOTTOM=L7 |
| PE_RX3_DR12_P | PE_RX3_DR12-DIFF1 | PAIR | 7 | 6.5 | 5 | 10 | 5 | 50 | 20 | 25 | 12 | 12 | 20 | 12 | 7.5 | 85 Ohms | TOP=L2:L3=L2/L4:L6=L5/L7:BOTTOM=L7 |
| PE_RX3_DR12_P | PE_RX3_DR12-DIFF1 | PAIR | 8 | 6.88 | 5 | 10 | 5 | 50 | 20 | 36 | 12 | 12 | 20 | 12 | 5.13 | 85 Ohms | TOP=L2:L3=L2/L4:L6=L5/L7:BOTTOM=L7 |
| PE_RX3_DR13_N | PE_RX3_DR13-DIFF1 | PAIR | 1 | 6.88 | 5 | 10 | 5 | 50 | 20 | 36 | 12 | 12 | 20 | 12 | 5.13 | 85 Ohms | TOP=L2:L3=L2/L4:L6=L5/L7:BOTTOM=L7 |
| PE_RX3_DR13_N | PE_RX3_DR13-DIFF1 | PAIR | 2 | 6.5 | 5 | 10 | 5 | 50 | 20 | 25 | 12 | 12 | 20 | 12 | 7.5 | 85 Ohms | TOP=L2:L3=L2/L4:L6=L5/L7:BOTTOM=L7 |
| PE_RX3_DR13_N | PE_RX3_DR13-DIFF1 | PAIR | 3 | 6.5 | 5 | 10 | 5 | 50 | 20 | 25 | 12 | 12 | 20 | 12 | 7.5 | 85 Ohms | TOP=L2:L3=L2/L4:L6=L5/L7:BOTTOM=L7 |
| PE_RX3_DR13_N | PE_RX3_DR13-DIFF1 | PAIR | 4 | 6.5 | 5 | 10 | 5 | 50 | 20 | 25 | 12 | 12 | 20 | 12 | 7.5 | 85 Ohms | TOP=L2:L3=L2/L4:L6=L5/L7:BOTTOM=L7 |
| PE_RX3_DR13_N | PE_RX3_DR13-DIFF1 | PAIR | 5 | 6.5 | 5 | 10 | 5 | 50 | 20 | 25 | 12 | 12 | 20 | 12 | 7.5 | 85 Ohms | TOP=L2:L3=L2/L4:L6=L5/L7:BOTTOM=L7 |
| PE_RX3_DR13_N | PE_RX3_DR13-DIFF1 | PAIR | 6 | 6.5 | 5 | 10 | 5 | 50 | 20 | 25 | 12 | 12 | 20 | 12 | 7.5 | 85 Ohms | TOP=L2:L3=L2/L4:L6=L5/L7:BOTTOM=L7 |
| PE_RX3_DR13_N | PE_RX3_DR13-DIFF1 | PAIR | 7 | 6.5 | 5 | 10 | 5 | 50 | 20 | 25 | 12 | 12 | 20 | 12 | 7.5 | 85 Ohms | TOP=L2:L3=L2/L4:L6=L5/L7:BOTTOM=L7 |
| PE_RX3_DR13_N | PE_RX3_DR13-DIFF1 | PAIR | 8 | 6.88 | 5 | 10 | 5 | 50 | 20 | 36 | 12 | 12 | 20 | 12 | 5.13 | 85 Ohms | TOP=L2:L3=L2/L4:L6=L5/L7:BOTTOM=L7 |
| PE_RX3_DR13_P | PE_RX3_DR13-DIFF1 | PAIR | 1 | 6.88 | 5 | 10 | 5 | 50 | 20 | 36 | 12 | 12 | 20 | 12 | 5.13 | 85 Ohms | TOP=L2:L3=L2/L4:L6=L5/L7:BOTTOM=L7 |
| PE_RX3_DR13_P | PE_RX3_DR13-DIFF1 | PAIR | 2 | 6.5 | 5 | 10 | 5 | 50 | 20 | 25 | 12 | 12 | 20 | 12 | 7.5 | 85 Ohms | TOP=L2:L3=L2/L4:L6=L5/L7:BOTTOM=L7 |
| PE_RX3_DR13_P | PE_RX3_DR13-DIFF1 | PAIR | 3 | 6.5 | 5 | 10 | 5 | 50 | 20 | 25 | 12 | 12 | 20 | 12 | 7.5 | 85 Ohms | TOP=L2:L3=L2/L4:L6=L5/L7:BOTTOM=L7 |
| PE_RX3_DR13_P | PE_RX3_DR13-DIFF1 | PAIR | 4 | 6.5 | 5 | 10 | 5 | 50 | 20 | 25 | 12 | 12 | 20 | 12 | 7.5 | 85 Ohms | TOP=L2:L3=L2/L4:L6=L5/L7:BOTTOM=L7 |
| PE_RX3_DR13_P | PE_RX3_DR13-DIFF1 | PAIR | 5 | 6.5 | 5 | 10 | 5 | 50 | 20 | 25 | 12 | 12 | 20 | 12 | 7.5 | 85 Ohms | TOP=L2:L3=L2/L4:L6=L5/L7:BOTTOM=L7 |
| PE_RX3_DR13_P | PE_RX3_DR13-DIFF1 | PAIR | 6 | 6.5 | 5 | 10 | 5 | 50 | 20 | 25 | 12 | 12 | 20 | 12 | 7.5 | 85 Ohms | TOP=L2:L3=L2/L4:L6=L5/L7:BOTTOM=L7 |
| PE_RX3_DR13_P | PE_RX3_DR13-DIFF1 | PAIR | 7 | 6.5 | 5 | 10 | 5 | 50 | 20 | 25 | 12 | 12 | 20 | 12 | 7.5 | 85 Ohms | TOP=L2:L3=L2/L4:L6=L5/L7:BOTTOM=L7 |
| PE_RX3_DR13_P | PE_RX3_DR13-DIFF1 | PAIR | 8 | 6.88 | 5 | 10 | 5 | 50 | 20 | 36 | 12 | 12 | 20 | 12 | 5.13 | 85 Ohms | TOP=L2:L3=L2/L4:L6=L5/L7:BOTTOM=L7 |
| PE_RX3_DR14_N | PE_RX3_DR14-DIFF1 | PAIR | 1 | 6.88 | 5 | 10 | 5 | 50 | 20 | 36 | 12 | 12 | 20 | 12 | 5.13 | 85 Ohms | TOP=L2:L3=L2/L4:L6=L5/L7:BOTTOM=L7 |
| PE_RX3_DR14_N | PE_RX3_DR14-DIFF1 | PAIR | 2 | 6.5 | 5 | 10 | 5 | 50 | 20 | 25 | 12 | 12 | 20 | 12 | 7.5 | 85 Ohms | TOP=L2:L3=L2/L4:L6=L5/L7:BOTTOM=L7 |
| PE_RX3_DR14_N | PE_RX3_DR14-DIFF1 | PAIR | 3 | 6.5 | 5 | 10 | 5 | 50 | 20 | 25 | 12 | 12 | 20 | 12 | 7.5 | 85 Ohms | TOP=L2:L3=L2/L4:L6=L5/L7:BOTTOM=L7 |
| PE_RX3_DR14_N | PE_RX3_DR14-DIFF1 | PAIR | 4 | 6.5 | 5 | 10 | 5 | 50 | 20 | 25 | 12 | 12 | 20 | 12 | 7.5 | 85 Ohms | TOP=L2:L3=L2/L4:L6=L5/L7:BOTTOM=L7 |
| PE_RX3_DR14_N | PE_RX3_DR14-DIFF1 | PAIR | 5 | 6.5 | 5 | 10 | 5 | 50 | 20 | 25 | 12 | 12 | 20 | 12 | 7.5 | 85 Ohms | TOP=L2:L3=L2/L4:L6=L5/L7:BOTTOM=L7 |
| PE_RX3_DR14_N | PE_RX3_DR14-DIFF1 | PAIR | 6 | 6.5 | 5 | 10 | 5 | 50 | 20 | 25 | 12 | 12 | 20 | 12 | 7.5 | 85 Ohms | TOP=L2:L3=L2/L4:L6=L5/L7:BOTTOM=L7 |
| PE_RX3_DR14_N | PE_RX3_DR14-DIFF1 | PAIR | 7 | 6.5 | 5 | 10 | 5 | 50 | 20 | 25 | 12 | 12 | 20 | 12 | 7.5 | 85 Ohms | TOP=L2:L3=L2/L4:L6=L5/L7:BOTTOM=L7 |
| PE_RX3_DR14_N | PE_RX3_DR14-DIFF1 | PAIR | 8 | 6.88 | 5 | 10 | 5 | 50 | 20 | 36 | 12 | 12 | 20 | 12 | 5.13 | 85 Ohms | TOP=L2:L3=L2/L4:L6=L5/L7:BOTTOM=L7 |
| PE_RX3_DR14_P | PE_RX3_DR14-DIFF1 | PAIR | 1 | 6.88 | 5 | 10 | 5 | 50 | 20 | 36 | 12 | 12 | 20 | 12 | 5.13 | 85 Ohms | TOP=L2:L3=L2/L4:L6=L5/L7:BOTTOM=L7 |
| PE_RX3_DR14_P | PE_RX3_DR14-DIFF1 | PAIR | 2 | 6.5 | 5 | 10 | 5 | 50 | 20 | 25 | 12 | 12 | 20 | 12 | 7.5 | 85 Ohms | TOP=L2:L3=L2/L4:L6=L5/L7:BOTTOM=L7 |
| PE_RX3_DR14_P | PE_RX3_DR14-DIFF1 | PAIR | 3 | 6.5 | 5 | 10 | 5 | 50 | 20 | 25 | 12 | 12 | 20 | 12 | 7.5 | 85 Ohms | TOP=L2:L3=L2/L4:L6=L5/L7:BOTTOM=L7 |
| PE_RX3_DR14_P | PE_RX3_DR14-DIFF1 | PAIR | 4 | 6.5 | 5 | 10 | 5 | 50 | 20 | 25 | 12 | 12 | 20 | 12 | 7.5 | 85 Ohms | TOP=L2:L3=L2/L4:L6=L5/L7:BOTTOM=L7 |
| PE_RX3_DR14_P | PE_RX3_DR14-DIFF1 | PAIR | 5 | 6.5 | 5 | 10 | 5 | 50 | 20 | 25 | 12 | 12 | 20 | 12 | 7.5 | 85 Ohms | TOP=L2:L3=L2/L4:L6=L5/L7:BOTTOM=L7 |
| PE_RX3_DR14_P | PE_RX3_DR14-DIFF1 | PAIR | 6 | 6.5 | 5 | 10 | 5 | 50 | 20 | 25 | 12 | 12 | 20 | 12 | 7.5 | 85 Ohms | TOP=L2:L3=L2/L4:L6=L5/L7:BOTTOM=L7 |
| PE_RX3_DR14_P | PE_RX3_DR14-DIFF1 | PAIR | 7 | 6.5 | 5 | 10 | 5 | 50 | 20 | 25 | 12 | 12 | 20 | 12 | 7.5 | 85 Ohms | TOP=L2:L3=L2/L4:L6=L5/L7:BOTTOM=L7 |
| PE_RX3_DR14_P | PE_RX3_DR14-DIFF1 | PAIR | 8 | 6.88 | 5 | 10 | 5 | 50 | 20 | 36 | 12 | 12 | 20 | 12 | 5.13 | 85 Ohms | TOP=L2:L3=L2/L4:L6=L5/L7:BOTTOM=L7 |
| PE_RX3_DR1_N | PE_RX3_DR1-DIFF1 | PAIR | 1 | 6.88 | 5 | 10 | 5 | 50 | 20 | 36 | 12 | 12 | 20 | 12 | 5.13 | 85 Ohms | TOP=L2:L3=L2/L4:L6=L5/L7:BOTTOM=L7 |
| PE_RX3_DR1_N | PE_RX3_DR1-DIFF1 | PAIR | 2 | 6.5 | 5 | 10 | 5 | 50 | 20 | 25 | 12 | 12 | 20 | 12 | 7.5 | 85 Ohms | TOP=L2:L3=L2/L4:L6=L5/L7:BOTTOM=L7 |
| PE_RX3_DR1_N | PE_RX3_DR1-DIFF1 | PAIR | 3 | 6.5 | 5 | 10 | 5 | 50 | 20 | 25 | 12 | 12 | 20 | 12 | 7.5 | 85 Ohms | TOP=L2:L3=L2/L4:L6=L5/L7:BOTTOM=L7 |
| PE_RX3_DR1_N | PE_RX3_DR1-DIFF1 | PAIR | 4 | 6.5 | 5 | 10 | 5 | 50 | 20 | 25 | 12 | 12 | 20 | 12 | 7.5 | 85 Ohms | TOP=L2:L3=L2/L4:L6=L5/L7:BOTTOM=L7 |
| PE_RX3_DR1_N | PE_RX3_DR1-DIFF1 | PAIR | 5 | 6.5 | 5 | 10 | 5 | 50 | 20 | 25 | 12 | 12 | 20 | 12 | 7.5 | 85 Ohms | TOP=L2:L3=L2/L4:L6=L5/L7:BOTTOM=L7 |
| PE_RX3_DR1_N | PE_RX3_DR1-DIFF1 | PAIR | 6 | 6.5 | 5 | 10 | 5 | 50 | 20 | 25 | 12 | 12 | 20 | 12 | 7.5 | 85 Ohms | TOP=L2:L3=L2/L4:L6=L5/L7:BOTTOM=L7 |
| PE_RX3_DR1_N | PE_RX3_DR1-DIFF1 | PAIR | 7 | 6.5 | 5 | 10 | 5 | 50 | 20 | 25 | 12 | 12 | 20 | 12 | 7.5 | 85 Ohms | TOP=L2:L3=L2/L4:L6=L5/L7:BOTTOM=L7 |
| PE_RX3_DR1_N | PE_RX3_DR1-DIFF1 | PAIR | 8 | 6.88 | 5 | 10 | 5 | 50 | 20 | 36 | 12 | 12 | 20 | 12 | 5.13 | 85 Ohms | TOP=L2:L3=L2/L4:L6=L5/L7:BOTTOM=L7 |
| PE_RX3_DR1_P | PE_RX3_DR1-DIFF1 | PAIR | 1 | 6.88 | 5 | 10 | 5 | 50 | 20 | 36 | 12 | 12 | 20 | 12 | 5.13 | 85 Ohms | TOP=L2:L3=L2/L4:L6=L5/L7:BOTTOM=L7 |
| PE_RX3_DR1_P | PE_RX3_DR1-DIFF1 | PAIR | 2 | 6.5 | 5 | 10 | 5 | 50 | 20 | 25 | 12 | 12 | 20 | 12 | 7.5 | 85 Ohms | TOP=L2:L3=L2/L4:L6=L5/L7:BOTTOM=L7 |
| PE_RX3_DR1_P | PE_RX3_DR1-DIFF1 | PAIR | 3 | 6.5 | 5 | 10 | 5 | 50 | 20 | 25 | 12 | 12 | 20 | 12 | 7.5 | 85 Ohms | TOP=L2:L3=L2/L4:L6=L5/L7:BOTTOM=L7 |
| PE_RX3_DR1_P | PE_RX3_DR1-DIFF1 | PAIR | 4 | 6.5 | 5 | 10 | 5 | 50 | 20 | 25 | 12 | 12 | 20 | 12 | 7.5 | 85 Ohms | TOP=L2:L3=L2/L4:L6=L5/L7:BOTTOM=L7 |
| PE_RX3_DR1_P | PE_RX3_DR1-DIFF1 | PAIR | 5 | 6.5 | 5 | 10 | 5 | 50 | 20 | 25 | 12 | 12 | 20 | 12 | 7.5 | 85 Ohms | TOP=L2:L3=L2/L4:L6=L5/L7:BOTTOM=L7 |
| PE_RX3_DR1_P | PE_RX3_DR1-DIFF1 | PAIR | 6 | 6.5 | 5 | 10 | 5 | 50 | 20 | 25 | 12 | 12 | 20 | 12 | 7.5 | 85 Ohms | TOP=L2:L3=L2/L4:L6=L5/L7:BOTTOM=L7 |
| PE_RX3_DR1_P | PE_RX3_DR1-DIFF1 | PAIR | 7 | 6.5 | 5 | 10 | 5 | 50 | 20 | 25 | 12 | 12 | 20 | 12 | 7.5 | 85 Ohms | TOP=L2:L3=L2/L4:L6=L5/L7:BOTTOM=L7 |
| PE_RX3_DR1_P | PE_RX3_DR1-DIFF1 | PAIR | 8 | 6.88 | 5 | 10 | 5 | 50 | 20 | 36 | 12 | 12 | 20 | 12 | 5.13 | 85 Ohms | TOP=L2:L3=L2/L4:L6=L5/L7:BOTTOM=L7 |
| PE_RX3_DR2_N | PE_RX3_DR2-DIFF1 | PAIR | 1 | 6.88 | 5 | 10 | 5 | 50 | 20 | 36 | 12 | 12 | 20 | 12 | 5.13 | 85 Ohms | TOP=L2:L3=L2/L4:L6=L5/L7:BOTTOM=L7 |
| PE_RX3_DR2_N | PE_RX3_DR2-DIFF1 | PAIR | 2 | 6.5 | 5 | 10 | 5 | 50 | 20 | 25 | 12 | 12 | 20 | 12 | 7.5 | 85 Ohms | TOP=L2:L3=L2/L4:L6=L5/L7:BOTTOM=L7 |
| PE_RX3_DR2_N | PE_RX3_DR2-DIFF1 | PAIR | 3 | 6.5 | 5 | 10 | 5 | 50 | 20 | 25 | 12 | 12 | 20 | 12 | 7.5 | 85 Ohms | TOP=L2:L3=L2/L4:L6=L5/L7:BOTTOM=L7 |
| PE_RX3_DR2_N | PE_RX3_DR2-DIFF1 | PAIR | 4 | 6.5 | 5 | 10 | 5 | 50 | 20 | 25 | 12 | 12 | 20 | 12 | 7.5 | 85 Ohms | TOP=L2:L3=L2/L4:L6=L5/L7:BOTTOM=L7 |
| PE_RX3_DR2_N | PE_RX3_DR2-DIFF1 | PAIR | 5 | 6.5 | 5 | 10 | 5 | 50 | 20 | 25 | 12 | 12 | 20 | 12 | 7.5 | 85 Ohms | TOP=L2:L3=L2/L4:L6=L5/L7:BOTTOM=L7 |
| PE_RX3_DR2_N | PE_RX3_DR2-DIFF1 | PAIR | 6 | 6.5 | 5 | 10 | 5 | 50 | 20 | 25 | 12 | 12 | 20 | 12 | 7.5 | 85 Ohms | TOP=L2:L3=L2/L4:L6=L5/L7:BOTTOM=L7 |
| PE_RX3_DR2_N | PE_RX3_DR2-DIFF1 | PAIR | 7 | 6.5 | 5 | 10 | 5 | 50 | 20 | 25 | 12 | 12 | 20 | 12 | 7.5 | 85 Ohms | TOP=L2:L3=L2/L4:L6=L5/L7:BOTTOM=L7 |
| PE_RX3_DR2_N | PE_RX3_DR2-DIFF1 | PAIR | 8 | 6.88 | 5 | 10 | 5 | 50 | 20 | 36 | 12 | 12 | 20 | 12 | 5.13 | 85 Ohms | TOP=L2:L3=L2/L4:L6=L5/L7:BOTTOM=L7 |
| PE_RX3_DR2_P | PE_RX3_DR2-DIFF1 | PAIR | 1 | 6.88 | 5 | 10 | 5 | 50 | 20 | 36 | 12 | 12 | 20 | 12 | 5.13 | 85 Ohms | TOP=L2:L3=L2/L4:L6=L5/L7:BOTTOM=L7 |
| PE_RX3_DR2_P | PE_RX3_DR2-DIFF1 | PAIR | 2 | 6.5 | 5 | 10 | 5 | 50 | 20 | 25 | 12 | 12 | 20 | 12 | 7.5 | 85 Ohms | TOP=L2:L3=L2/L4:L6=L5/L7:BOTTOM=L7 |
| PE_RX3_DR2_P | PE_RX3_DR2-DIFF1 | PAIR | 3 | 6.5 | 5 | 10 | 5 | 50 | 20 | 25 | 12 | 12 | 20 | 12 | 7.5 | 85 Ohms | TOP=L2:L3=L2/L4:L6=L5/L7:BOTTOM=L7 |
| PE_RX3_DR2_P | PE_RX3_DR2-DIFF1 | PAIR | 4 | 6.5 | 5 | 10 | 5 | 50 | 20 | 25 | 12 | 12 | 20 | 12 | 7.5 | 85 Ohms | TOP=L2:L3=L2/L4:L6=L5/L7:BOTTOM=L7 |
| PE_RX3_DR2_P | PE_RX3_DR2-DIFF1 | PAIR | 5 | 6.5 | 5 | 10 | 5 | 50 | 20 | 25 | 12 | 12 | 20 | 12 | 7.5 | 85 Ohms | TOP=L2:L3=L2/L4:L6=L5/L7:BOTTOM=L7 |
| PE_RX3_DR2_P | PE_RX3_DR2-DIFF1 | PAIR | 6 | 6.5 | 5 | 10 | 5 | 50 | 20 | 25 | 12 | 12 | 20 | 12 | 7.5 | 85 Ohms | TOP=L2:L3=L2/L4:L6=L5/L7:BOTTOM=L7 |
| PE_RX3_DR2_P | PE_RX3_DR2-DIFF1 | PAIR | 7 | 6.5 | 5 | 10 | 5 | 50 | 20 | 25 | 12 | 12 | 20 | 12 | 7.5 | 85 Ohms | TOP=L2:L3=L2/L4:L6=L5/L7:BOTTOM=L7 |
| PE_RX3_DR2_P | PE_RX3_DR2-DIFF1 | PAIR | 8 | 6.88 | 5 | 10 | 5 | 50 | 20 | 36 | 12 | 12 | 20 | 12 | 5.13 | 85 Ohms | TOP=L2:L3=L2/L4:L6=L5/L7:BOTTOM=L7 |
| PE_RX3_DR3_N | PE_RX3_DR3-DIFF1 | PAIR | 1 | 6.88 | 5 | 10 | 5 | 50 | 20 | 36 | 12 | 12 | 20 | 12 | 5.13 | 85 Ohms | TOP=L2:L3=L2/L4:L6=L5/L7:BOTTOM=L7 |
| PE_RX3_DR3_N | PE_RX3_DR3-DIFF1 | PAIR | 2 | 6.5 | 5 | 10 | 5 | 50 | 20 | 25 | 12 | 12 | 20 | 12 | 7.5 | 85 Ohms | TOP=L2:L3=L2/L4:L6=L5/L7:BOTTOM=L7 |
| PE_RX3_DR3_N | PE_RX3_DR3-DIFF1 | PAIR | 3 | 6.5 | 5 | 10 | 5 | 50 | 20 | 25 | 12 | 12 | 20 | 12 | 7.5 | 85 Ohms | TOP=L2:L3=L2/L4:L6=L5/L7:BOTTOM=L7 |
| PE_RX3_DR3_N | PE_RX3_DR3-DIFF1 | PAIR | 4 | 6.5 | 5 | 10 | 5 | 50 | 20 | 25 | 12 | 12 | 20 | 12 | 7.5 | 85 Ohms | TOP=L2:L3=L2/L4:L6=L5/L7:BOTTOM=L7 |
| PE_RX3_DR3_N | PE_RX3_DR3-DIFF1 | PAIR | 5 | 6.5 | 5 | 10 | 5 | 50 | 20 | 25 | 12 | 12 | 20 | 12 | 7.5 | 85 Ohms | TOP=L2:L3=L2/L4:L6=L5/L7:BOTTOM=L7 |
| PE_RX3_DR3_N | PE_RX3_DR3-DIFF1 | PAIR | 6 | 6.5 | 5 | 10 | 5 | 50 | 20 | 25 | 12 | 12 | 20 | 12 | 7.5 | 85 Ohms | TOP=L2:L3=L2/L4:L6=L5/L7:BOTTOM=L7 |
| PE_RX3_DR3_N | PE_RX3_DR3-DIFF1 | PAIR | 7 | 6.5 | 5 | 10 | 5 | 50 | 20 | 25 | 12 | 12 | 20 | 12 | 7.5 | 85 Ohms | TOP=L2:L3=L2/L4:L6=L5/L7:BOTTOM=L7 |
| PE_RX3_DR3_N | PE_RX3_DR3-DIFF1 | PAIR | 8 | 6.88 | 5 | 10 | 5 | 50 | 20 | 36 | 12 | 12 | 20 | 12 | 5.13 | 85 Ohms | TOP=L2:L3=L2/L4:L6=L5/L7:BOTTOM=L7 |
| PE_RX3_DR3_P | PE_RX3_DR3-DIFF1 | PAIR | 1 | 6.88 | 5 | 10 | 5 | 50 | 20 | 36 | 12 | 12 | 20 | 12 | 5.13 | 85 Ohms | TOP=L2:L3=L2/L4:L6=L5/L7:BOTTOM=L7 |
| PE_RX3_DR3_P | PE_RX3_DR3-DIFF1 | PAIR | 2 | 6.5 | 5 | 10 | 5 | 50 | 20 | 25 | 12 | 12 | 20 | 12 | 7.5 | 85 Ohms | TOP=L2:L3=L2/L4:L6=L5/L7:BOTTOM=L7 |
| PE_RX3_DR3_P | PE_RX3_DR3-DIFF1 | PAIR | 3 | 6.5 | 5 | 10 | 5 | 50 | 20 | 25 | 12 | 12 | 20 | 12 | 7.5 | 85 Ohms | TOP=L2:L3=L2/L4:L6=L5/L7:BOTTOM=L7 |
| PE_RX3_DR3_P | PE_RX3_DR3-DIFF1 | PAIR | 4 | 6.5 | 5 | 10 | 5 | 50 | 20 | 25 | 12 | 12 | 20 | 12 | 7.5 | 85 Ohms | TOP=L2:L3=L2/L4:L6=L5/L7:BOTTOM=L7 |
| PE_RX3_DR3_P | PE_RX3_DR3-DIFF1 | PAIR | 5 | 6.5 | 5 | 10 | 5 | 50 | 20 | 25 | 12 | 12 | 20 | 12 | 7.5 | 85 Ohms | TOP=L2:L3=L2/L4:L6=L5/L7:BOTTOM=L7 |
| PE_RX3_DR3_P | PE_RX3_DR3-DIFF1 | PAIR | 6 | 6.5 | 5 | 10 | 5 | 50 | 20 | 25 | 12 | 12 | 20 | 12 | 7.5 | 85 Ohms | TOP=L2:L3=L2/L4:L6=L5/L7:BOTTOM=L7 |
| PE_RX3_DR3_P | PE_RX3_DR3-DIFF1 | PAIR | 7 | 6.5 | 5 | 10 | 5 | 50 | 20 | 25 | 12 | 12 | 20 | 12 | 7.5 | 85 Ohms | TOP=L2:L3=L2/L4:L6=L5/L7:BOTTOM=L7 |
| PE_RX3_DR3_P | PE_RX3_DR3-DIFF1 | PAIR | 8 | 6.88 | 5 | 10 | 5 | 50 | 20 | 36 | 12 | 12 | 20 | 12 | 5.13 | 85 Ohms | TOP=L2:L3=L2/L4:L6=L5/L7:BOTTOM=L7 |
| PE_RX3_DR4_N | PE_RX3_DR4-DIFF1 | PAIR | 1 | 6.88 | 5 | 10 | 5 | 50 | 20 | 36 | 12 | 12 | 20 | 12 | 5.13 | 85 Ohms | TOP=L2:L3=L2/L4:L6=L5/L7:BOTTOM=L7 |
| PE_RX3_DR4_N | PE_RX3_DR4-DIFF1 | PAIR | 2 | 6.5 | 5 | 10 | 5 | 50 | 20 | 25 | 12 | 12 | 20 | 12 | 7.5 | 85 Ohms | TOP=L2:L3=L2/L4:L6=L5/L7:BOTTOM=L7 |
| PE_RX3_DR4_N | PE_RX3_DR4-DIFF1 | PAIR | 3 | 6.5 | 5 | 10 | 5 | 50 | 20 | 25 | 12 | 12 | 20 | 12 | 7.5 | 85 Ohms | TOP=L2:L3=L2/L4:L6=L5/L7:BOTTOM=L7 |
| PE_RX3_DR4_N | PE_RX3_DR4-DIFF1 | PAIR | 4 | 6.5 | 5 | 10 | 5 | 50 | 20 | 25 | 12 | 12 | 20 | 12 | 7.5 | 85 Ohms | TOP=L2:L3=L2/L4:L6=L5/L7:BOTTOM=L7 |
| PE_RX3_DR4_N | PE_RX3_DR4-DIFF1 | PAIR | 5 | 6.5 | 5 | 10 | 5 | 50 | 20 | 25 | 12 | 12 | 20 | 12 | 7.5 | 85 Ohms | TOP=L2:L3=L2/L4:L6=L5/L7:BOTTOM=L7 |
| PE_RX3_DR4_N | PE_RX3_DR4-DIFF1 | PAIR | 6 | 6.5 | 5 | 10 | 5 | 50 | 20 | 25 | 12 | 12 | 20 | 12 | 7.5 | 85 Ohms | TOP=L2:L3=L2/L4:L6=L5/L7:BOTTOM=L7 |
| PE_RX3_DR4_N | PE_RX3_DR4-DIFF1 | PAIR | 7 | 6.5 | 5 | 10 | 5 | 50 | 20 | 25 | 12 | 12 | 20 | 12 | 7.5 | 85 Ohms | TOP=L2:L3=L2/L4:L6=L5/L7:BOTTOM=L7 |
| PE_RX3_DR4_N | PE_RX3_DR4-DIFF1 | PAIR | 8 | 6.88 | 5 | 10 | 5 | 50 | 20 | 36 | 12 | 12 | 20 | 12 | 5.13 | 85 Ohms | TOP=L2:L3=L2/L4:L6=L5/L7:BOTTOM=L7 |
| PE_RX3_DR4_P | PE_RX3_DR4-DIFF1 | PAIR | 1 | 6.88 | 5 | 10 | 5 | 50 | 20 | 36 | 12 | 12 | 20 | 12 | 5.13 | 85 Ohms | TOP=L2:L3=L2/L4:L6=L5/L7:BOTTOM=L7 |
| PE_RX3_DR4_P | PE_RX3_DR4-DIFF1 | PAIR | 2 | 6.5 | 5 | 10 | 5 | 50 | 20 | 25 | 12 | 12 | 20 | 12 | 7.5 | 85 Ohms | TOP=L2:L3=L2/L4:L6=L5/L7:BOTTOM=L7 |
| PE_RX3_DR4_P | PE_RX3_DR4-DIFF1 | PAIR | 3 | 6.5 | 5 | 10 | 5 | 50 | 20 | 25 | 12 | 12 | 20 | 12 | 7.5 | 85 Ohms | TOP=L2:L3=L2/L4:L6=L5/L7:BOTTOM=L7 |
| PE_RX3_DR4_P | PE_RX3_DR4-DIFF1 | PAIR | 4 | 6.5 | 5 | 10 | 5 | 50 | 20 | 25 | 12 | 12 | 20 | 12 | 7.5 | 85 Ohms | TOP=L2:L3=L2/L4:L6=L5/L7:BOTTOM=L7 |
| PE_RX3_DR4_P | PE_RX3_DR4-DIFF1 | PAIR | 5 | 6.5 | 5 | 10 | 5 | 50 | 20 | 25 | 12 | 12 | 20 | 12 | 7.5 | 85 Ohms | TOP=L2:L3=L2/L4:L6=L5/L7:BOTTOM=L7 |
| PE_RX3_DR4_P | PE_RX3_DR4-DIFF1 | PAIR | 6 | 6.5 | 5 | 10 | 5 | 50 | 20 | 25 | 12 | 12 | 20 | 12 | 7.5 | 85 Ohms | TOP=L2:L3=L2/L4:L6=L5/L7:BOTTOM=L7 |
| PE_RX3_DR4_P | PE_RX3_DR4-DIFF1 | PAIR | 7 | 6.5 | 5 | 10 | 5 | 50 | 20 | 25 | 12 | 12 | 20 | 12 | 7.5 | 85 Ohms | TOP=L2:L3=L2/L4:L6=L5/L7:BOTTOM=L7 |
| PE_RX3_DR4_P | PE_RX3_DR4-DIFF1 | PAIR | 8 | 6.88 | 5 | 10 | 5 | 50 | 20 | 36 | 12 | 12 | 20 | 12 | 5.13 | 85 Ohms | TOP=L2:L3=L2/L4:L6=L5/L7:BOTTOM=L7 |
| PE_RX3_DR5_N | PE_RX3_DR5-DIFF1 | PAIR | 1 | 6.88 | 5 | 10 | 5 | 50 | 20 | 36 | 12 | 12 | 20 | 12 | 5.13 | 85 Ohms | TOP=L2:L3=L2/L4:L6=L5/L7:BOTTOM=L7 |
| PE_RX3_DR5_N | PE_RX3_DR5-DIFF1 | PAIR | 2 | 6.5 | 5 | 10 | 5 | 50 | 20 | 25 | 12 | 12 | 20 | 12 | 7.5 | 85 Ohms | TOP=L2:L3=L2/L4:L6=L5/L7:BOTTOM=L7 |
| PE_RX3_DR5_N | PE_RX3_DR5-DIFF1 | PAIR | 3 | 6.5 | 5 | 10 | 5 | 50 | 20 | 25 | 12 | 12 | 20 | 12 | 7.5 | 85 Ohms | TOP=L2:L3=L2/L4:L6=L5/L7:BOTTOM=L7 |
| PE_RX3_DR5_N | PE_RX3_DR5-DIFF1 | PAIR | 4 | 6.5 | 5 | 10 | 5 | 50 | 20 | 25 | 12 | 12 | 20 | 12 | 7.5 | 85 Ohms | TOP=L2:L3=L2/L4:L6=L5/L7:BOTTOM=L7 |
| PE_RX3_DR5_N | PE_RX3_DR5-DIFF1 | PAIR | 5 | 6.5 | 5 | 10 | 5 | 50 | 20 | 25 | 12 | 12 | 20 | 12 | 7.5 | 85 Ohms | TOP=L2:L3=L2/L4:L6=L5/L7:BOTTOM=L7 |
| PE_RX3_DR5_N | PE_RX3_DR5-DIFF1 | PAIR | 6 | 6.5 | 5 | 10 | 5 | 50 | 20 | 25 | 12 | 12 | 20 | 12 | 7.5 | 85 Ohms | TOP=L2:L3=L2/L4:L6=L5/L7:BOTTOM=L7 |
| PE_RX3_DR5_N | PE_RX3_DR5-DIFF1 | PAIR | 7 | 6.5 | 5 | 10 | 5 | 50 | 20 | 25 | 12 | 12 | 20 | 12 | 7.5 | 85 Ohms | TOP=L2:L3=L2/L4:L6=L5/L7:BOTTOM=L7 |
| PE_RX3_DR5_N | PE_RX3_DR5-DIFF1 | PAIR | 8 | 6.88 | 5 | 10 | 5 | 50 | 20 | 36 | 12 | 12 | 20 | 12 | 5.13 | 85 Ohms | TOP=L2:L3=L2/L4:L6=L5/L7:BOTTOM=L7 |
| PE_RX3_DR5_P | PE_RX3_DR5-DIFF1 | PAIR | 1 | 6.88 | 5 | 10 | 5 | 50 | 20 | 36 | 12 | 12 | 20 | 12 | 5.13 | 85 Ohms | TOP=L2:L3=L2/L4:L6=L5/L7:BOTTOM=L7 |
| PE_RX3_DR5_P | PE_RX3_DR5-DIFF1 | PAIR | 2 | 6.5 | 5 | 10 | 5 | 50 | 20 | 25 | 12 | 12 | 20 | 12 | 7.5 | 85 Ohms | TOP=L2:L3=L2/L4:L6=L5/L7:BOTTOM=L7 |
| PE_RX3_DR5_P | PE_RX3_DR5-DIFF1 | PAIR | 3 | 6.5 | 5 | 10 | 5 | 50 | 20 | 25 | 12 | 12 | 20 | 12 | 7.5 | 85 Ohms | TOP=L2:L3=L2/L4:L6=L5/L7:BOTTOM=L7 |
| PE_RX3_DR5_P | PE_RX3_DR5-DIFF1 | PAIR | 4 | 6.5 | 5 | 10 | 5 | 50 | 20 | 25 | 12 | 12 | 20 | 12 | 7.5 | 85 Ohms | TOP=L2:L3=L2/L4:L6=L5/L7:BOTTOM=L7 |
| PE_RX3_DR5_P | PE_RX3_DR5-DIFF1 | PAIR | 5 | 6.5 | 5 | 10 | 5 | 50 | 20 | 25 | 12 | 12 | 20 | 12 | 7.5 | 85 Ohms | TOP=L2:L3=L2/L4:L6=L5/L7:BOTTOM=L7 |
| PE_RX3_DR5_P | PE_RX3_DR5-DIFF1 | PAIR | 6 | 6.5 | 5 | 10 | 5 | 50 | 20 | 25 | 12 | 12 | 20 | 12 | 7.5 | 85 Ohms | TOP=L2:L3=L2/L4:L6=L5/L7:BOTTOM=L7 |
| PE_RX3_DR5_P | PE_RX3_DR5-DIFF1 | PAIR | 7 | 6.5 | 5 | 10 | 5 | 50 | 20 | 25 | 12 | 12 | 20 | 12 | 7.5 | 85 Ohms | TOP=L2:L3=L2/L4:L6=L5/L7:BOTTOM=L7 |
| PE_RX3_DR5_P | PE_RX3_DR5-DIFF1 | PAIR | 8 | 6.88 | 5 | 10 | 5 | 50 | 20 | 36 | 12 | 12 | 20 | 12 | 5.13 | 85 Ohms | TOP=L2:L3=L2/L4:L6=L5/L7:BOTTOM=L7 |
| PE_RX3_DR6_N | PE_RX3_DR6-DIFF1 | PAIR | 1 | 6.88 | 5 | 10 | 5 | 50 | 20 | 36 | 12 | 12 | 20 | 12 | 5.13 | 85 Ohms | TOP=L2:L3=L2/L4:L6=L5/L7:BOTTOM=L7 |
| PE_RX3_DR6_N | PE_RX3_DR6-DIFF1 | PAIR | 2 | 6.5 | 5 | 10 | 5 | 50 | 20 | 25 | 12 | 12 | 20 | 12 | 7.5 | 85 Ohms | TOP=L2:L3=L2/L4:L6=L5/L7:BOTTOM=L7 |
| PE_RX3_DR6_N | PE_RX3_DR6-DIFF1 | PAIR | 3 | 6.5 | 5 | 10 | 5 | 50 | 20 | 25 | 12 | 12 | 20 | 12 | 7.5 | 85 Ohms | TOP=L2:L3=L2/L4:L6=L5/L7:BOTTOM=L7 |
| PE_RX3_DR6_N | PE_RX3_DR6-DIFF1 | PAIR | 4 | 6.5 | 5 | 10 | 5 | 50 | 20 | 25 | 12 | 12 | 20 | 12 | 7.5 | 85 Ohms | TOP=L2:L3=L2/L4:L6=L5/L7:BOTTOM=L7 |
| PE_RX3_DR6_N | PE_RX3_DR6-DIFF1 | PAIR | 5 | 6.5 | 5 | 10 | 5 | 50 | 20 | 25 | 12 | 12 | 20 | 12 | 7.5 | 85 Ohms | TOP=L2:L3=L2/L4:L6=L5/L7:BOTTOM=L7 |
| PE_RX3_DR6_N | PE_RX3_DR6-DIFF1 | PAIR | 6 | 6.5 | 5 | 10 | 5 | 50 | 20 | 25 | 12 | 12 | 20 | 12 | 7.5 | 85 Ohms | TOP=L2:L3=L2/L4:L6=L5/L7:BOTTOM=L7 |
| PE_RX3_DR6_N | PE_RX3_DR6-DIFF1 | PAIR | 7 | 6.5 | 5 | 10 | 5 | 50 | 20 | 25 | 12 | 12 | 20 | 12 | 7.5 | 85 Ohms | TOP=L2:L3=L2/L4:L6=L5/L7:BOTTOM=L7 |
| PE_RX3_DR6_N | PE_RX3_DR6-DIFF1 | PAIR | 8 | 6.88 | 5 | 10 | 5 | 50 | 20 | 36 | 12 | 12 | 20 | 12 | 5.13 | 85 Ohms | TOP=L2:L3=L2/L4:L6=L5/L7:BOTTOM=L7 |
| PE_RX3_DR6_P | PE_RX3_DR6-DIFF1 | PAIR | 1 | 6.88 | 5 | 10 | 5 | 50 | 20 | 36 | 12 | 12 | 20 | 12 | 5.13 | 85 Ohms | TOP=L2:L3=L2/L4:L6=L5/L7:BOTTOM=L7 |
| PE_RX3_DR6_P | PE_RX3_DR6-DIFF1 | PAIR | 2 | 6.5 | 5 | 10 | 5 | 50 | 20 | 25 | 12 | 12 | 20 | 12 | 7.5 | 85 Ohms | TOP=L2:L3=L2/L4:L6=L5/L7:BOTTOM=L7 |
| PE_RX3_DR6_P | PE_RX3_DR6-DIFF1 | PAIR | 3 | 6.5 | 5 | 10 | 5 | 50 | 20 | 25 | 12 | 12 | 20 | 12 | 7.5 | 85 Ohms | TOP=L2:L3=L2/L4:L6=L5/L7:BOTTOM=L7 |
| PE_RX3_DR6_P | PE_RX3_DR6-DIFF1 | PAIR | 4 | 6.5 | 5 | 10 | 5 | 50 | 20 | 25 | 12 | 12 | 20 | 12 | 7.5 | 85 Ohms | TOP=L2:L3=L2/L4:L6=L5/L7:BOTTOM=L7 |
| PE_RX3_DR6_P | PE_RX3_DR6-DIFF1 | PAIR | 5 | 6.5 | 5 | 10 | 5 | 50 | 20 | 25 | 12 | 12 | 20 | 12 | 7.5 | 85 Ohms | TOP=L2:L3=L2/L4:L6=L5/L7:BOTTOM=L7 |
| PE_RX3_DR6_P | PE_RX3_DR6-DIFF1 | PAIR | 6 | 6.5 | 5 | 10 | 5 | 50 | 20 | 25 | 12 | 12 | 20 | 12 | 7.5 | 85 Ohms | TOP=L2:L3=L2/L4:L6=L5/L7:BOTTOM=L7 |
| PE_RX3_DR6_P | PE_RX3_DR6-DIFF1 | PAIR | 7 | 6.5 | 5 | 10 | 5 | 50 | 20 | 25 | 12 | 12 | 20 | 12 | 7.5 | 85 Ohms | TOP=L2:L3=L2/L4:L6=L5/L7:BOTTOM=L7 |
| PE_RX3_DR6_P | PE_RX3_DR6-DIFF1 | PAIR | 8 | 6.88 | 5 | 10 | 5 | 50 | 20 | 36 | 12 | 12 | 20 | 12 | 5.13 | 85 Ohms | TOP=L2:L3=L2/L4:L6=L5/L7:BOTTOM=L7 |
| PE_RX3_DR7_N | PE_RX3_DR7-DIFF1 | PAIR | 1 | 6.88 | 5 | 10 | 5 | 50 | 20 | 36 | 12 | 12 | 20 | 12 | 5.13 | 85 Ohms | TOP=L2:L3=L2/L4:L6=L5/L7:BOTTOM=L7 |
| PE_RX3_DR7_N | PE_RX3_DR7-DIFF1 | PAIR | 2 | 6.5 | 5 | 10 | 5 | 50 | 20 | 25 | 12 | 12 | 20 | 12 | 7.5 | 85 Ohms | TOP=L2:L3=L2/L4:L6=L5/L7:BOTTOM=L7 |
| PE_RX3_DR7_N | PE_RX3_DR7-DIFF1 | PAIR | 3 | 6.5 | 5 | 10 | 5 | 50 | 20 | 25 | 12 | 12 | 20 | 12 | 7.5 | 85 Ohms | TOP=L2:L3=L2/L4:L6=L5/L7:BOTTOM=L7 |
| PE_RX3_DR7_N | PE_RX3_DR7-DIFF1 | PAIR | 4 | 6.5 | 5 | 10 | 5 | 50 | 20 | 25 | 12 | 12 | 20 | 12 | 7.5 | 85 Ohms | TOP=L2:L3=L2/L4:L6=L5/L7:BOTTOM=L7 |
| PE_RX3_DR7_N | PE_RX3_DR7-DIFF1 | PAIR | 5 | 6.5 | 5 | 10 | 5 | 50 | 20 | 25 | 12 | 12 | 20 | 12 | 7.5 | 85 Ohms | TOP=L2:L3=L2/L4:L6=L5/L7:BOTTOM=L7 |
| PE_RX3_DR7_N | PE_RX3_DR7-DIFF1 | PAIR | 6 | 6.5 | 5 | 10 | 5 | 50 | 20 | 25 | 12 | 12 | 20 | 12 | 7.5 | 85 Ohms | TOP=L2:L3=L2/L4:L6=L5/L7:BOTTOM=L7 |
| PE_RX3_DR7_N | PE_RX3_DR7-DIFF1 | PAIR | 7 | 6.5 | 5 | 10 | 5 | 50 | 20 | 25 | 12 | 12 | 20 | 12 | 7.5 | 85 Ohms | TOP=L2:L3=L2/L4:L6=L5/L7:BOTTOM=L7 |
| PE_RX3_DR7_N | PE_RX3_DR7-DIFF1 | PAIR | 8 | 6.88 | 5 | 10 | 5 | 50 | 20 | 36 | 12 | 12 | 20 | 12 | 5.13 | 85 Ohms | TOP=L2:L3=L2/L4:L6=L5/L7:BOTTOM=L7 |
| PE_RX3_DR7_P | PE_RX3_DR7-DIFF1 | PAIR | 1 | 6.88 | 5 | 10 | 5 | 50 | 20 | 36 | 12 | 12 | 20 | 12 | 5.13 | 85 Ohms | TOP=L2:L3=L2/L4:L6=L5/L7:BOTTOM=L7 |
| PE_RX3_DR7_P | PE_RX3_DR7-DIFF1 | PAIR | 2 | 6.5 | 5 | 10 | 5 | 50 | 20 | 25 | 12 | 12 | 20 | 12 | 7.5 | 85 Ohms | TOP=L2:L3=L2/L4:L6=L5/L7:BOTTOM=L7 |
| PE_RX3_DR7_P | PE_RX3_DR7-DIFF1 | PAIR | 3 | 6.5 | 5 | 10 | 5 | 50 | 20 | 25 | 12 | 12 | 20 | 12 | 7.5 | 85 Ohms | TOP=L2:L3=L2/L4:L6=L5/L7:BOTTOM=L7 |
| PE_RX3_DR7_P | PE_RX3_DR7-DIFF1 | PAIR | 4 | 6.5 | 5 | 10 | 5 | 50 | 20 | 25 | 12 | 12 | 20 | 12 | 7.5 | 85 Ohms | TOP=L2:L3=L2/L4:L6=L5/L7:BOTTOM=L7 |
| PE_RX3_DR7_P | PE_RX3_DR7-DIFF1 | PAIR | 5 | 6.5 | 5 | 10 | 5 | 50 | 20 | 25 | 12 | 12 | 20 | 12 | 7.5 | 85 Ohms | TOP=L2:L3=L2/L4:L6=L5/L7:BOTTOM=L7 |
| PE_RX3_DR7_P | PE_RX3_DR7-DIFF1 | PAIR | 6 | 6.5 | 5 | 10 | 5 | 50 | 20 | 25 | 12 | 12 | 20 | 12 | 7.5 | 85 Ohms | TOP=L2:L3=L2/L4:L6=L5/L7:BOTTOM=L7 |
| PE_RX3_DR7_P | PE_RX3_DR7-DIFF1 | PAIR | 7 | 6.5 | 5 | 10 | 5 | 50 | 20 | 25 | 12 | 12 | 20 | 12 | 7.5 | 85 Ohms | TOP=L2:L3=L2/L4:L6=L5/L7:BOTTOM=L7 |
| PE_RX3_DR7_P | PE_RX3_DR7-DIFF1 | PAIR | 8 | 6.88 | 5 | 10 | 5 | 50 | 20 | 36 | 12 | 12 | 20 | 12 | 5.13 | 85 Ohms | TOP=L2:L3=L2/L4:L6=L5/L7:BOTTOM=L7 |
| PE_RX3_DR8_N | PE_RX3_DR8-DIFF1 | PAIR | 1 | 6.88 | 5 | 10 | 5 | 50 | 20 | 36 | 12 | 12 | 20 | 12 | 5.13 | 85 Ohms | TOP=L2:L3=L2/L4:L6=L5/L7:BOTTOM=L7 |
| PE_RX3_DR8_N | PE_RX3_DR8-DIFF1 | PAIR | 2 | 6.5 | 5 | 10 | 5 | 50 | 20 | 25 | 12 | 12 | 20 | 12 | 7.5 | 85 Ohms | TOP=L2:L3=L2/L4:L6=L5/L7:BOTTOM=L7 |
| PE_RX3_DR8_N | PE_RX3_DR8-DIFF1 | PAIR | 3 | 6.5 | 5 | 10 | 5 | 50 | 20 | 25 | 12 | 12 | 20 | 12 | 7.5 | 85 Ohms | TOP=L2:L3=L2/L4:L6=L5/L7:BOTTOM=L7 |
| PE_RX3_DR8_N | PE_RX3_DR8-DIFF1 | PAIR | 4 | 6.5 | 5 | 10 | 5 | 50 | 20 | 25 | 12 | 12 | 20 | 12 | 7.5 | 85 Ohms | TOP=L2:L3=L2/L4:L6=L5/L7:BOTTOM=L7 |
| PE_RX3_DR8_N | PE_RX3_DR8-DIFF1 | PAIR | 5 | 6.5 | 5 | 10 | 5 | 50 | 20 | 25 | 12 | 12 | 20 | 12 | 7.5 | 85 Ohms | TOP=L2:L3=L2/L4:L6=L5/L7:BOTTOM=L7 |
| PE_RX3_DR8_N | PE_RX3_DR8-DIFF1 | PAIR | 6 | 6.5 | 5 | 10 | 5 | 50 | 20 | 25 | 12 | 12 | 20 | 12 | 7.5 | 85 Ohms | TOP=L2:L3=L2/L4:L6=L5/L7:BOTTOM=L7 |
| PE_RX3_DR8_N | PE_RX3_DR8-DIFF1 | PAIR | 7 | 6.5 | 5 | 10 | 5 | 50 | 20 | 25 | 12 | 12 | 20 | 12 | 7.5 | 85 Ohms | TOP=L2:L3=L2/L4:L6=L5/L7:BOTTOM=L7 |
| PE_RX3_DR8_N | PE_RX3_DR8-DIFF1 | PAIR | 8 | 6.88 | 5 | 10 | 5 | 50 | 20 | 36 | 12 | 12 | 20 | 12 | 5.13 | 85 Ohms | TOP=L2:L3=L2/L4:L6=L5/L7:BOTTOM=L7 |
| PE_RX3_DR8_P | PE_RX3_DR8-DIFF1 | PAIR | 1 | 6.88 | 5 | 10 | 5 | 50 | 20 | 36 | 12 | 12 | 20 | 12 | 5.13 | 85 Ohms | TOP=L2:L3=L2/L4:L6=L5/L7:BOTTOM=L7 |
| PE_RX3_DR8_P | PE_RX3_DR8-DIFF1 | PAIR | 2 | 6.5 | 5 | 10 | 5 | 50 | 20 | 25 | 12 | 12 | 20 | 12 | 7.5 | 85 Ohms | TOP=L2:L3=L2/L4:L6=L5/L7:BOTTOM=L7 |
| PE_RX3_DR8_P | PE_RX3_DR8-DIFF1 | PAIR | 3 | 6.5 | 5 | 10 | 5 | 50 | 20 | 25 | 12 | 12 | 20 | 12 | 7.5 | 85 Ohms | TOP=L2:L3=L2/L4:L6=L5/L7:BOTTOM=L7 |
| PE_RX3_DR8_P | PE_RX3_DR8-DIFF1 | PAIR | 4 | 6.5 | 5 | 10 | 5 | 50 | 20 | 25 | 12 | 12 | 20 | 12 | 7.5 | 85 Ohms | TOP=L2:L3=L2/L4:L6=L5/L7:BOTTOM=L7 |
| PE_RX3_DR8_P | PE_RX3_DR8-DIFF1 | PAIR | 5 | 6.5 | 5 | 10 | 5 | 50 | 20 | 25 | 12 | 12 | 20 | 12 | 7.5 | 85 Ohms | TOP=L2:L3=L2/L4:L6=L5/L7:BOTTOM=L7 |
| PE_RX3_DR8_P | PE_RX3_DR8-DIFF1 | PAIR | 6 | 6.5 | 5 | 10 | 5 | 50 | 20 | 25 | 12 | 12 | 20 | 12 | 7.5 | 85 Ohms | TOP=L2:L3=L2/L4:L6=L5/L7:BOTTOM=L7 |
| PE_RX3_DR8_P | PE_RX3_DR8-DIFF1 | PAIR | 7 | 6.5 | 5 | 10 | 5 | 50 | 20 | 25 | 12 | 12 | 20 | 12 | 7.5 | 85 Ohms | TOP=L2:L3=L2/L4:L6=L5/L7:BOTTOM=L7 |
| PE_RX3_DR8_P | PE_RX3_DR8-DIFF1 | PAIR | 8 | 6.88 | 5 | 10 | 5 | 50 | 20 | 36 | 12 | 12 | 20 | 12 | 5.13 | 85 Ohms | TOP=L2:L3=L2/L4:L6=L5/L7:BOTTOM=L7 |
| PE_RX3_DR9_N | PE_RX3_DR9-DIFF1 | PAIR | 1 | 6.88 | 5 | 10 | 5 | 50 | 20 | 36 | 12 | 12 | 20 | 12 | 5.13 | 85 Ohms | TOP=L2:L3=L2/L4:L6=L5/L7:BOTTOM=L7 |
| PE_RX3_DR9_N | PE_RX3_DR9-DIFF1 | PAIR | 2 | 6.5 | 5 | 10 | 5 | 50 | 20 | 25 | 12 | 12 | 20 | 12 | 7.5 | 85 Ohms | TOP=L2:L3=L2/L4:L6=L5/L7:BOTTOM=L7 |
| PE_RX3_DR9_N | PE_RX3_DR9-DIFF1 | PAIR | 3 | 6.5 | 5 | 10 | 5 | 50 | 20 | 25 | 12 | 12 | 20 | 12 | 7.5 | 85 Ohms | TOP=L2:L3=L2/L4:L6=L5/L7:BOTTOM=L7 |
| PE_RX3_DR9_N | PE_RX3_DR9-DIFF1 | PAIR | 4 | 6.5 | 5 | 10 | 5 | 50 | 20 | 25 | 12 | 12 | 20 | 12 | 7.5 | 85 Ohms | TOP=L2:L3=L2/L4:L6=L5/L7:BOTTOM=L7 |
| PE_RX3_DR9_N | PE_RX3_DR9-DIFF1 | PAIR | 5 | 6.5 | 5 | 10 | 5 | 50 | 20 | 25 | 12 | 12 | 20 | 12 | 7.5 | 85 Ohms | TOP=L2:L3=L2/L4:L6=L5/L7:BOTTOM=L7 |
| PE_RX3_DR9_N | PE_RX3_DR9-DIFF1 | PAIR | 6 | 6.5 | 5 | 10 | 5 | 50 | 20 | 25 | 12 | 12 | 20 | 12 | 7.5 | 85 Ohms | TOP=L2:L3=L2/L4:L6=L5/L7:BOTTOM=L7 |
| PE_RX3_DR9_N | PE_RX3_DR9-DIFF1 | PAIR | 7 | 6.5 | 5 | 10 | 5 | 50 | 20 | 25 | 12 | 12 | 20 | 12 | 7.5 | 85 Ohms | TOP=L2:L3=L2/L4:L6=L5/L7:BOTTOM=L7 |
| PE_RX3_DR9_N | PE_RX3_DR9-DIFF1 | PAIR | 8 | 6.88 | 5 | 10 | 5 | 50 | 20 | 36 | 12 | 12 | 20 | 12 | 5.13 | 85 Ohms | TOP=L2:L3=L2/L4:L6=L5/L7:BOTTOM=L7 |
| PE_RX3_DR9_P | PE_RX3_DR9-DIFF1 | PAIR | 1 | 6.88 | 5 | 10 | 5 | 50 | 20 | 36 | 12 | 12 | 20 | 12 | 5.13 | 85 Ohms | TOP=L2:L3=L2/L4:L6=L5/L7:BOTTOM=L7 |
| PE_RX3_DR9_P | PE_RX3_DR9-DIFF1 | PAIR | 2 | 6.5 | 5 | 10 | 5 | 50 | 20 | 25 | 12 | 12 | 20 | 12 | 7.5 | 85 Ohms | TOP=L2:L3=L2/L4:L6=L5/L7:BOTTOM=L7 |
| PE_RX3_DR9_P | PE_RX3_DR9-DIFF1 | PAIR | 3 | 6.5 | 5 | 10 | 5 | 50 | 20 | 25 | 12 | 12 | 20 | 12 | 7.5 | 85 Ohms | TOP=L2:L3=L2/L4:L6=L5/L7:BOTTOM=L7 |
| PE_RX3_DR9_P | PE_RX3_DR9-DIFF1 | PAIR | 4 | 6.5 | 5 | 10 | 5 | 50 | 20 | 25 | 12 | 12 | 20 | 12 | 7.5 | 85 Ohms | TOP=L2:L3=L2/L4:L6=L5/L7:BOTTOM=L7 |
| PE_RX3_DR9_P | PE_RX3_DR9-DIFF1 | PAIR | 5 | 6.5 | 5 | 10 | 5 | 50 | 20 | 25 | 12 | 12 | 20 | 12 | 7.5 | 85 Ohms | TOP=L2:L3=L2/L4:L6=L5/L7:BOTTOM=L7 |
| PE_RX3_DR9_P | PE_RX3_DR9-DIFF1 | PAIR | 6 | 6.5 | 5 | 10 | 5 | 50 | 20 | 25 | 12 | 12 | 20 | 12 | 7.5 | 85 Ohms | TOP=L2:L3=L2/L4:L6=L5/L7:BOTTOM=L7 |
| PE_RX3_DR9_P | PE_RX3_DR9-DIFF1 | PAIR | 7 | 6.5 | 5 | 10 | 5 | 50 | 20 | 25 | 12 | 12 | 20 | 12 | 7.5 | 85 Ohms | TOP=L2:L3=L2/L4:L6=L5/L7:BOTTOM=L7 |
| PE_RX3_DR9_P | PE_RX3_DR9-DIFF1 | PAIR | 8 | 6.88 | 5 | 10 | 5 | 50 | 20 | 36 | 12 | 12 | 20 | 12 | 5.13 | 85 Ohms | TOP=L2:L3=L2/L4:L6=L5/L7:BOTTOM=L7 |
| PE_RX4_DR0_N | PE_RX4_DR0-DIFF1 | PAIR | 1 | 6.88 | 5 | 10 | 5 | 50 | 20 | 36 | 12 | 12 | 20 | 12 | 5.13 | 85 Ohms | TOP=L2:L3=L2/L4:L6=L5/L7:BOTTOM=L7 |
| PE_RX4_DR0_N | PE_RX4_DR0-DIFF1 | PAIR | 2 | 6.5 | 5 | 10 | 5 | 50 | 20 | 25 | 12 | 12 | 20 | 12 | 7.5 | 85 Ohms | TOP=L2:L3=L2/L4:L6=L5/L7:BOTTOM=L7 |
| PE_RX4_DR0_N | PE_RX4_DR0-DIFF1 | PAIR | 3 | 6.5 | 5 | 10 | 5 | 50 | 20 | 25 | 12 | 12 | 20 | 12 | 7.5 | 85 Ohms | TOP=L2:L3=L2/L4:L6=L5/L7:BOTTOM=L7 |
| PE_RX4_DR0_N | PE_RX4_DR0-DIFF1 | PAIR | 4 | 6.5 | 5 | 10 | 5 | 50 | 20 | 25 | 12 | 12 | 20 | 12 | 7.5 | 85 Ohms | TOP=L2:L3=L2/L4:L6=L5/L7:BOTTOM=L7 |
| PE_RX4_DR0_N | PE_RX4_DR0-DIFF1 | PAIR | 5 | 6.5 | 5 | 10 | 5 | 50 | 20 | 25 | 12 | 12 | 20 | 12 | 7.5 | 85 Ohms | TOP=L2:L3=L2/L4:L6=L5/L7:BOTTOM=L7 |
| PE_RX4_DR0_N | PE_RX4_DR0-DIFF1 | PAIR | 6 | 6.5 | 5 | 10 | 5 | 50 | 20 | 25 | 12 | 12 | 20 | 12 | 7.5 | 85 Ohms | TOP=L2:L3=L2/L4:L6=L5/L7:BOTTOM=L7 |
| PE_RX4_DR0_N | PE_RX4_DR0-DIFF1 | PAIR | 7 | 6.5 | 5 | 10 | 5 | 50 | 20 | 25 | 12 | 12 | 20 | 12 | 7.5 | 85 Ohms | TOP=L2:L3=L2/L4:L6=L5/L7:BOTTOM=L7 |
| PE_RX4_DR0_N | PE_RX4_DR0-DIFF1 | PAIR | 8 | 6.88 | 5 | 10 | 5 | 50 | 20 | 36 | 12 | 12 | 20 | 12 | 5.13 | 85 Ohms | TOP=L2:L3=L2/L4:L6=L5/L7:BOTTOM=L7 |
| PE_RX4_DR0_P | PE_RX4_DR0-DIFF1 | PAIR | 1 | 6.88 | 5 | 10 | 5 | 50 | 20 | 36 | 12 | 12 | 20 | 12 | 5.13 | 85 Ohms | TOP=L2:L3=L2/L4:L6=L5/L7:BOTTOM=L7 |
| PE_RX4_DR0_P | PE_RX4_DR0-DIFF1 | PAIR | 2 | 6.5 | 5 | 10 | 5 | 50 | 20 | 25 | 12 | 12 | 20 | 12 | 7.5 | 85 Ohms | TOP=L2:L3=L2/L4:L6=L5/L7:BOTTOM=L7 |
| PE_RX4_DR0_P | PE_RX4_DR0-DIFF1 | PAIR | 3 | 6.5 | 5 | 10 | 5 | 50 | 20 | 25 | 12 | 12 | 20 | 12 | 7.5 | 85 Ohms | TOP=L2:L3=L2/L4:L6=L5/L7:BOTTOM=L7 |
| PE_RX4_DR0_P | PE_RX4_DR0-DIFF1 | PAIR | 4 | 6.5 | 5 | 10 | 5 | 50 | 20 | 25 | 12 | 12 | 20 | 12 | 7.5 | 85 Ohms | TOP=L2:L3=L2/L4:L6=L5/L7:BOTTOM=L7 |
| PE_RX4_DR0_P | PE_RX4_DR0-DIFF1 | PAIR | 5 | 6.5 | 5 | 10 | 5 | 50 | 20 | 25 | 12 | 12 | 20 | 12 | 7.5 | 85 Ohms | TOP=L2:L3=L2/L4:L6=L5/L7:BOTTOM=L7 |
| PE_RX4_DR0_P | PE_RX4_DR0-DIFF1 | PAIR | 6 | 6.5 | 5 | 10 | 5 | 50 | 20 | 25 | 12 | 12 | 20 | 12 | 7.5 | 85 Ohms | TOP=L2:L3=L2/L4:L6=L5/L7:BOTTOM=L7 |
| PE_RX4_DR0_P | PE_RX4_DR0-DIFF1 | PAIR | 7 | 6.5 | 5 | 10 | 5 | 50 | 20 | 25 | 12 | 12 | 20 | 12 | 7.5 | 85 Ohms | TOP=L2:L3=L2/L4:L6=L5/L7:BOTTOM=L7 |
| PE_RX4_DR0_P | PE_RX4_DR0-DIFF1 | PAIR | 8 | 6.88 | 5 | 10 | 5 | 50 | 20 | 36 | 12 | 12 | 20 | 12 | 5.13 | 85 Ohms | TOP=L2:L3=L2/L4:L6=L5/L7:BOTTOM=L7 |
| PE_RX4_DR10_N | PE_RX4_DR10-DIFF1 | PAIR | 1 | 6.88 | 5 | 10 | 5 | 50 | 20 | 36 | 12 | 12 | 20 | 12 | 5.13 | 85 Ohms | TOP=L2:L3=L2/L4:L6=L5/L7:BOTTOM=L7 |
| PE_RX4_DR10_N | PE_RX4_DR10-DIFF1 | PAIR | 2 | 6.5 | 5 | 10 | 5 | 50 | 20 | 25 | 12 | 12 | 20 | 12 | 7.5 | 85 Ohms | TOP=L2:L3=L2/L4:L6=L5/L7:BOTTOM=L7 |
| PE_RX4_DR10_N | PE_RX4_DR10-DIFF1 | PAIR | 3 | 6.5 | 5 | 10 | 5 | 50 | 20 | 25 | 12 | 12 | 20 | 12 | 7.5 | 85 Ohms | TOP=L2:L3=L2/L4:L6=L5/L7:BOTTOM=L7 |
| PE_RX4_DR10_N | PE_RX4_DR10-DIFF1 | PAIR | 4 | 6.5 | 5 | 10 | 5 | 50 | 20 | 25 | 12 | 12 | 20 | 12 | 7.5 | 85 Ohms | TOP=L2:L3=L2/L4:L6=L5/L7:BOTTOM=L7 |
| PE_RX4_DR10_N | PE_RX4_DR10-DIFF1 | PAIR | 5 | 6.5 | 5 | 10 | 5 | 50 | 20 | 25 | 12 | 12 | 20 | 12 | 7.5 | 85 Ohms | TOP=L2:L3=L2/L4:L6=L5/L7:BOTTOM=L7 |
| PE_RX4_DR10_N | PE_RX4_DR10-DIFF1 | PAIR | 6 | 6.5 | 5 | 10 | 5 | 50 | 20 | 25 | 12 | 12 | 20 | 12 | 7.5 | 85 Ohms | TOP=L2:L3=L2/L4:L6=L5/L7:BOTTOM=L7 |
| PE_RX4_DR10_N | PE_RX4_DR10-DIFF1 | PAIR | 7 | 6.5 | 5 | 10 | 5 | 50 | 20 | 25 | 12 | 12 | 20 | 12 | 7.5 | 85 Ohms | TOP=L2:L3=L2/L4:L6=L5/L7:BOTTOM=L7 |
| PE_RX4_DR10_N | PE_RX4_DR10-DIFF1 | PAIR | 8 | 6.88 | 5 | 10 | 5 | 50 | 20 | 36 | 12 | 12 | 20 | 12 | 5.13 | 85 Ohms | TOP=L2:L3=L2/L4:L6=L5/L7:BOTTOM=L7 |
| PE_RX4_DR10_P | PE_RX4_DR10-DIFF1 | PAIR | 1 | 6.88 | 5 | 10 | 5 | 50 | 20 | 36 | 12 | 12 | 20 | 12 | 5.13 | 85 Ohms | TOP=L2:L3=L2/L4:L6=L5/L7:BOTTOM=L7 |
| PE_RX4_DR10_P | PE_RX4_DR10-DIFF1 | PAIR | 2 | 6.5 | 5 | 10 | 5 | 50 | 20 | 25 | 12 | 12 | 20 | 12 | 7.5 | 85 Ohms | TOP=L2:L3=L2/L4:L6=L5/L7:BOTTOM=L7 |
| PE_RX4_DR10_P | PE_RX4_DR10-DIFF1 | PAIR | 3 | 6.5 | 5 | 10 | 5 | 50 | 20 | 25 | 12 | 12 | 20 | 12 | 7.5 | 85 Ohms | TOP=L2:L3=L2/L4:L6=L5/L7:BOTTOM=L7 |
| PE_RX4_DR10_P | PE_RX4_DR10-DIFF1 | PAIR | 4 | 6.5 | 5 | 10 | 5 | 50 | 20 | 25 | 12 | 12 | 20 | 12 | 7.5 | 85 Ohms | TOP=L2:L3=L2/L4:L6=L5/L7:BOTTOM=L7 |
| PE_RX4_DR10_P | PE_RX4_DR10-DIFF1 | PAIR | 5 | 6.5 | 5 | 10 | 5 | 50 | 20 | 25 | 12 | 12 | 20 | 12 | 7.5 | 85 Ohms | TOP=L2:L3=L2/L4:L6=L5/L7:BOTTOM=L7 |
| PE_RX4_DR10_P | PE_RX4_DR10-DIFF1 | PAIR | 6 | 6.5 | 5 | 10 | 5 | 50 | 20 | 25 | 12 | 12 | 20 | 12 | 7.5 | 85 Ohms | TOP=L2:L3=L2/L4:L6=L5/L7:BOTTOM=L7 |
| PE_RX4_DR10_P | PE_RX4_DR10-DIFF1 | PAIR | 7 | 6.5 | 5 | 10 | 5 | 50 | 20 | 25 | 12 | 12 | 20 | 12 | 7.5 | 85 Ohms | TOP=L2:L3=L2/L4:L6=L5/L7:BOTTOM=L7 |
| PE_RX4_DR10_P | PE_RX4_DR10-DIFF1 | PAIR | 8 | 6.88 | 5 | 10 | 5 | 50 | 20 | 36 | 12 | 12 | 20 | 12 | 5.13 | 85 Ohms | TOP=L2:L3=L2/L4:L6=L5/L7:BOTTOM=L7 |
| PE_RX4_DR11_N | PE_RX4_DR11-DIFF1 | PAIR | 1 | 6.88 | 5 | 10 | 5 | 50 | 20 | 36 | 12 | 12 | 20 | 12 | 5.13 | 85 Ohms | TOP=L2:L3=L2/L4:L6=L5/L7:BOTTOM=L7 |
| PE_RX4_DR11_N | PE_RX4_DR11-DIFF1 | PAIR | 2 | 6.5 | 5 | 10 | 5 | 50 | 20 | 25 | 12 | 12 | 20 | 12 | 7.5 | 85 Ohms | TOP=L2:L3=L2/L4:L6=L5/L7:BOTTOM=L7 |
| PE_RX4_DR11_N | PE_RX4_DR11-DIFF1 | PAIR | 3 | 6.5 | 5 | 10 | 5 | 50 | 20 | 25 | 12 | 12 | 20 | 12 | 7.5 | 85 Ohms | TOP=L2:L3=L2/L4:L6=L5/L7:BOTTOM=L7 |
| PE_RX4_DR11_N | PE_RX4_DR11-DIFF1 | PAIR | 4 | 6.5 | 5 | 10 | 5 | 50 | 20 | 25 | 12 | 12 | 20 | 12 | 7.5 | 85 Ohms | TOP=L2:L3=L2/L4:L6=L5/L7:BOTTOM=L7 |
| PE_RX4_DR11_N | PE_RX4_DR11-DIFF1 | PAIR | 5 | 6.5 | 5 | 10 | 5 | 50 | 20 | 25 | 12 | 12 | 20 | 12 | 7.5 | 85 Ohms | TOP=L2:L3=L2/L4:L6=L5/L7:BOTTOM=L7 |
| PE_RX4_DR11_N | PE_RX4_DR11-DIFF1 | PAIR | 6 | 6.5 | 5 | 10 | 5 | 50 | 20 | 25 | 12 | 12 | 20 | 12 | 7.5 | 85 Ohms | TOP=L2:L3=L2/L4:L6=L5/L7:BOTTOM=L7 |
| PE_RX4_DR11_N | PE_RX4_DR11-DIFF1 | PAIR | 7 | 6.5 | 5 | 10 | 5 | 50 | 20 | 25 | 12 | 12 | 20 | 12 | 7.5 | 85 Ohms | TOP=L2:L3=L2/L4:L6=L5/L7:BOTTOM=L7 |
| PE_RX4_DR11_N | PE_RX4_DR11-DIFF1 | PAIR | 8 | 6.88 | 5 | 10 | 5 | 50 | 20 | 36 | 12 | 12 | 20 | 12 | 5.13 | 85 Ohms | TOP=L2:L3=L2/L4:L6=L5/L7:BOTTOM=L7 |
| PE_RX4_DR11_P | PE_RX4_DR11-DIFF1 | PAIR | 1 | 6.88 | 5 | 10 | 5 | 50 | 20 | 36 | 12 | 12 | 20 | 12 | 5.13 | 85 Ohms | TOP=L2:L3=L2/L4:L6=L5/L7:BOTTOM=L7 |
| PE_RX4_DR11_P | PE_RX4_DR11-DIFF1 | PAIR | 2 | 6.5 | 5 | 10 | 5 | 50 | 20 | 25 | 12 | 12 | 20 | 12 | 7.5 | 85 Ohms | TOP=L2:L3=L2/L4:L6=L5/L7:BOTTOM=L7 |
| PE_RX4_DR11_P | PE_RX4_DR11-DIFF1 | PAIR | 3 | 6.5 | 5 | 10 | 5 | 50 | 20 | 25 | 12 | 12 | 20 | 12 | 7.5 | 85 Ohms | TOP=L2:L3=L2/L4:L6=L5/L7:BOTTOM=L7 |
| PE_RX4_DR11_P | PE_RX4_DR11-DIFF1 | PAIR | 4 | 6.5 | 5 | 10 | 5 | 50 | 20 | 25 | 12 | 12 | 20 | 12 | 7.5 | 85 Ohms | TOP=L2:L3=L2/L4:L6=L5/L7:BOTTOM=L7 |
| PE_RX4_DR11_P | PE_RX4_DR11-DIFF1 | PAIR | 5 | 6.5 | 5 | 10 | 5 | 50 | 20 | 25 | 12 | 12 | 20 | 12 | 7.5 | 85 Ohms | TOP=L2:L3=L2/L4:L6=L5/L7:BOTTOM=L7 |
| PE_RX4_DR11_P | PE_RX4_DR11-DIFF1 | PAIR | 6 | 6.5 | 5 | 10 | 5 | 50 | 20 | 25 | 12 | 12 | 20 | 12 | 7.5 | 85 Ohms | TOP=L2:L3=L2/L4:L6=L5/L7:BOTTOM=L7 |
| PE_RX4_DR11_P | PE_RX4_DR11-DIFF1 | PAIR | 7 | 6.5 | 5 | 10 | 5 | 50 | 20 | 25 | 12 | 12 | 20 | 12 | 7.5 | 85 Ohms | TOP=L2:L3=L2/L4:L6=L5/L7:BOTTOM=L7 |
| PE_RX4_DR11_P | PE_RX4_DR11-DIFF1 | PAIR | 8 | 6.88 | 5 | 10 | 5 | 50 | 20 | 36 | 12 | 12 | 20 | 12 | 5.13 | 85 Ohms | TOP=L2:L3=L2/L4:L6=L5/L7:BOTTOM=L7 |
| PE_RX4_DR12_N | PE_RX4_DR12-DIFF1 | PAIR | 1 | 6.88 | 5 | 10 | 5 | 50 | 20 | 36 | 12 | 12 | 20 | 12 | 5.13 | 85 Ohms | TOP=L2:L3=L2/L4:L6=L5/L7:BOTTOM=L7 |
| PE_RX4_DR12_N | PE_RX4_DR12-DIFF1 | PAIR | 2 | 6.5 | 5 | 10 | 5 | 50 | 20 | 25 | 12 | 12 | 20 | 12 | 7.5 | 85 Ohms | TOP=L2:L3=L2/L4:L6=L5/L7:BOTTOM=L7 |
| PE_RX4_DR12_N | PE_RX4_DR12-DIFF1 | PAIR | 3 | 6.5 | 5 | 10 | 5 | 50 | 20 | 25 | 12 | 12 | 20 | 12 | 7.5 | 85 Ohms | TOP=L2:L3=L2/L4:L6=L5/L7:BOTTOM=L7 |
| PE_RX4_DR12_N | PE_RX4_DR12-DIFF1 | PAIR | 4 | 6.5 | 5 | 10 | 5 | 50 | 20 | 25 | 12 | 12 | 20 | 12 | 7.5 | 85 Ohms | TOP=L2:L3=L2/L4:L6=L5/L7:BOTTOM=L7 |
| PE_RX4_DR12_N | PE_RX4_DR12-DIFF1 | PAIR | 5 | 6.5 | 5 | 10 | 5 | 50 | 20 | 25 | 12 | 12 | 20 | 12 | 7.5 | 85 Ohms | TOP=L2:L3=L2/L4:L6=L5/L7:BOTTOM=L7 |
| PE_RX4_DR12_N | PE_RX4_DR12-DIFF1 | PAIR | 6 | 6.5 | 5 | 10 | 5 | 50 | 20 | 25 | 12 | 12 | 20 | 12 | 7.5 | 85 Ohms | TOP=L2:L3=L2/L4:L6=L5/L7:BOTTOM=L7 |
| PE_RX4_DR12_N | PE_RX4_DR12-DIFF1 | PAIR | 7 | 6.5 | 5 | 10 | 5 | 50 | 20 | 25 | 12 | 12 | 20 | 12 | 7.5 | 85 Ohms | TOP=L2:L3=L2/L4:L6=L5/L7:BOTTOM=L7 |
| PE_RX4_DR12_N | PE_RX4_DR12-DIFF1 | PAIR | 8 | 6.88 | 5 | 10 | 5 | 50 | 20 | 36 | 12 | 12 | 20 | 12 | 5.13 | 85 Ohms | TOP=L2:L3=L2/L4:L6=L5/L7:BOTTOM=L7 |
| PE_RX4_DR12_P | PE_RX4_DR12-DIFF1 | PAIR | 1 | 6.88 | 5 | 10 | 5 | 50 | 20 | 36 | 12 | 12 | 20 | 12 | 5.13 | 85 Ohms | TOP=L2:L3=L2/L4:L6=L5/L7:BOTTOM=L7 |
| PE_RX4_DR12_P | PE_RX4_DR12-DIFF1 | PAIR | 2 | 6.5 | 5 | 10 | 5 | 50 | 20 | 25 | 12 | 12 | 20 | 12 | 7.5 | 85 Ohms | TOP=L2:L3=L2/L4:L6=L5/L7:BOTTOM=L7 |
| PE_RX4_DR12_P | PE_RX4_DR12-DIFF1 | PAIR | 3 | 6.5 | 5 | 10 | 5 | 50 | 20 | 25 | 12 | 12 | 20 | 12 | 7.5 | 85 Ohms | TOP=L2:L3=L2/L4:L6=L5/L7:BOTTOM=L7 |
| PE_RX4_DR12_P | PE_RX4_DR12-DIFF1 | PAIR | 4 | 6.5 | 5 | 10 | 5 | 50 | 20 | 25 | 12 | 12 | 20 | 12 | 7.5 | 85 Ohms | TOP=L2:L3=L2/L4:L6=L5/L7:BOTTOM=L7 |
| PE_RX4_DR12_P | PE_RX4_DR12-DIFF1 | PAIR | 5 | 6.5 | 5 | 10 | 5 | 50 | 20 | 25 | 12 | 12 | 20 | 12 | 7.5 | 85 Ohms | TOP=L2:L3=L2/L4:L6=L5/L7:BOTTOM=L7 |
| PE_RX4_DR12_P | PE_RX4_DR12-DIFF1 | PAIR | 6 | 6.5 | 5 | 10 | 5 | 50 | 20 | 25 | 12 | 12 | 20 | 12 | 7.5 | 85 Ohms | TOP=L2:L3=L2/L4:L6=L5/L7:BOTTOM=L7 |
| PE_RX4_DR12_P | PE_RX4_DR12-DIFF1 | PAIR | 7 | 6.5 | 5 | 10 | 5 | 50 | 20 | 25 | 12 | 12 | 20 | 12 | 7.5 | 85 Ohms | TOP=L2:L3=L2/L4:L6=L5/L7:BOTTOM=L7 |
| PE_RX4_DR12_P | PE_RX4_DR12-DIFF1 | PAIR | 8 | 6.88 | 5 | 10 | 5 | 50 | 20 | 36 | 12 | 12 | 20 | 12 | 5.13 | 85 Ohms | TOP=L2:L3=L2/L4:L6=L5/L7:BOTTOM=L7 |
| PE_RX4_DR13_N | PE_RX4_DR13-DIFF1 | PAIR | 1 | 6.88 | 5 | 10 | 5 | 50 | 20 | 36 | 12 | 12 | 20 | 12 | 5.13 | 85 Ohms | TOP=L2:L3=L2/L4:L6=L5/L7:BOTTOM=L7 |
| PE_RX4_DR13_N | PE_RX4_DR13-DIFF1 | PAIR | 2 | 6.5 | 5 | 10 | 5 | 50 | 20 | 25 | 12 | 12 | 20 | 12 | 7.5 | 85 Ohms | TOP=L2:L3=L2/L4:L6=L5/L7:BOTTOM=L7 |
| PE_RX4_DR13_N | PE_RX4_DR13-DIFF1 | PAIR | 3 | 6.5 | 5 | 10 | 5 | 50 | 20 | 25 | 12 | 12 | 20 | 12 | 7.5 | 85 Ohms | TOP=L2:L3=L2/L4:L6=L5/L7:BOTTOM=L7 |
| PE_RX4_DR13_N | PE_RX4_DR13-DIFF1 | PAIR | 4 | 6.5 | 5 | 10 | 5 | 50 | 20 | 25 | 12 | 12 | 20 | 12 | 7.5 | 85 Ohms | TOP=L2:L3=L2/L4:L6=L5/L7:BOTTOM=L7 |
| PE_RX4_DR13_N | PE_RX4_DR13-DIFF1 | PAIR | 5 | 6.5 | 5 | 10 | 5 | 50 | 20 | 25 | 12 | 12 | 20 | 12 | 7.5 | 85 Ohms | TOP=L2:L3=L2/L4:L6=L5/L7:BOTTOM=L7 |
| PE_RX4_DR13_N | PE_RX4_DR13-DIFF1 | PAIR | 6 | 6.5 | 5 | 10 | 5 | 50 | 20 | 25 | 12 | 12 | 20 | 12 | 7.5 | 85 Ohms | TOP=L2:L3=L2/L4:L6=L5/L7:BOTTOM=L7 |
| PE_RX4_DR13_N | PE_RX4_DR13-DIFF1 | PAIR | 7 | 6.5 | 5 | 10 | 5 | 50 | 20 | 25 | 12 | 12 | 20 | 12 | 7.5 | 85 Ohms | TOP=L2:L3=L2/L4:L6=L5/L7:BOTTOM=L7 |
| PE_RX4_DR13_N | PE_RX4_DR13-DIFF1 | PAIR | 8 | 6.88 | 5 | 10 | 5 | 50 | 20 | 36 | 12 | 12 | 20 | 12 | 5.13 | 85 Ohms | TOP=L2:L3=L2/L4:L6=L5/L7:BOTTOM=L7 |
| PE_RX4_DR13_P | PE_RX4_DR13-DIFF1 | PAIR | 1 | 6.88 | 5 | 10 | 5 | 50 | 20 | 36 | 12 | 12 | 20 | 12 | 5.13 | 85 Ohms | TOP=L2:L3=L2/L4:L6=L5/L7:BOTTOM=L7 |
| PE_RX4_DR13_P | PE_RX4_DR13-DIFF1 | PAIR | 2 | 6.5 | 5 | 10 | 5 | 50 | 20 | 25 | 12 | 12 | 20 | 12 | 7.5 | 85 Ohms | TOP=L2:L3=L2/L4:L6=L5/L7:BOTTOM=L7 |
| PE_RX4_DR13_P | PE_RX4_DR13-DIFF1 | PAIR | 3 | 6.5 | 5 | 10 | 5 | 50 | 20 | 25 | 12 | 12 | 20 | 12 | 7.5 | 85 Ohms | TOP=L2:L3=L2/L4:L6=L5/L7:BOTTOM=L7 |
| PE_RX4_DR13_P | PE_RX4_DR13-DIFF1 | PAIR | 4 | 6.5 | 5 | 10 | 5 | 50 | 20 | 25 | 12 | 12 | 20 | 12 | 7.5 | 85 Ohms | TOP=L2:L3=L2/L4:L6=L5/L7:BOTTOM=L7 |
| PE_RX4_DR13_P | PE_RX4_DR13-DIFF1 | PAIR | 5 | 6.5 | 5 | 10 | 5 | 50 | 20 | 25 | 12 | 12 | 20 | 12 | 7.5 | 85 Ohms | TOP=L2:L3=L2/L4:L6=L5/L7:BOTTOM=L7 |
| PE_RX4_DR13_P | PE_RX4_DR13-DIFF1 | PAIR | 6 | 6.5 | 5 | 10 | 5 | 50 | 20 | 25 | 12 | 12 | 20 | 12 | 7.5 | 85 Ohms | TOP=L2:L3=L2/L4:L6=L5/L7:BOTTOM=L7 |
| PE_RX4_DR13_P | PE_RX4_DR13-DIFF1 | PAIR | 7 | 6.5 | 5 | 10 | 5 | 50 | 20 | 25 | 12 | 12 | 20 | 12 | 7.5 | 85 Ohms | TOP=L2:L3=L2/L4:L6=L5/L7:BOTTOM=L7 |
| PE_RX4_DR13_P | PE_RX4_DR13-DIFF1 | PAIR | 8 | 6.88 | 5 | 10 | 5 | 50 | 20 | 36 | 12 | 12 | 20 | 12 | 5.13 | 85 Ohms | TOP=L2:L3=L2/L4:L6=L5/L7:BOTTOM=L7 |
| PE_RX4_DR14_N | PE_RX4_DR14-DIFF1 | PAIR | 1 | 6.88 | 5 | 10 | 5 | 50 | 20 | 36 | 12 | 12 | 20 | 12 | 5.13 | 85 Ohms | TOP=L2:L3=L2/L4:L6=L5/L7:BOTTOM=L7 |
| PE_RX4_DR14_N | PE_RX4_DR14-DIFF1 | PAIR | 2 | 6.5 | 5 | 10 | 5 | 50 | 20 | 25 | 12 | 12 | 20 | 12 | 7.5 | 85 Ohms | TOP=L2:L3=L2/L4:L6=L5/L7:BOTTOM=L7 |
| PE_RX4_DR14_N | PE_RX4_DR14-DIFF1 | PAIR | 3 | 6.5 | 5 | 10 | 5 | 50 | 20 | 25 | 12 | 12 | 20 | 12 | 7.5 | 85 Ohms | TOP=L2:L3=L2/L4:L6=L5/L7:BOTTOM=L7 |
| PE_RX4_DR14_N | PE_RX4_DR14-DIFF1 | PAIR | 4 | 6.5 | 5 | 10 | 5 | 50 | 20 | 25 | 12 | 12 | 20 | 12 | 7.5 | 85 Ohms | TOP=L2:L3=L2/L4:L6=L5/L7:BOTTOM=L7 |
| PE_RX4_DR14_N | PE_RX4_DR14-DIFF1 | PAIR | 5 | 6.5 | 5 | 10 | 5 | 50 | 20 | 25 | 12 | 12 | 20 | 12 | 7.5 | 85 Ohms | TOP=L2:L3=L2/L4:L6=L5/L7:BOTTOM=L7 |
| PE_RX4_DR14_N | PE_RX4_DR14-DIFF1 | PAIR | 6 | 6.5 | 5 | 10 | 5 | 50 | 20 | 25 | 12 | 12 | 20 | 12 | 7.5 | 85 Ohms | TOP=L2:L3=L2/L4:L6=L5/L7:BOTTOM=L7 |
| PE_RX4_DR14_N | PE_RX4_DR14-DIFF1 | PAIR | 7 | 6.5 | 5 | 10 | 5 | 50 | 20 | 25 | 12 | 12 | 20 | 12 | 7.5 | 85 Ohms | TOP=L2:L3=L2/L4:L6=L5/L7:BOTTOM=L7 |
| PE_RX4_DR14_N | PE_RX4_DR14-DIFF1 | PAIR | 8 | 6.88 | 5 | 10 | 5 | 50 | 20 | 36 | 12 | 12 | 20 | 12 | 5.13 | 85 Ohms | TOP=L2:L3=L2/L4:L6=L5/L7:BOTTOM=L7 |
| PE_RX4_DR14_P | PE_RX4_DR14-DIFF1 | PAIR | 1 | 6.88 | 5 | 10 | 5 | 50 | 20 | 36 | 12 | 12 | 20 | 12 | 5.13 | 85 Ohms | TOP=L2:L3=L2/L4:L6=L5/L7:BOTTOM=L7 |
| PE_RX4_DR14_P | PE_RX4_DR14-DIFF1 | PAIR | 2 | 6.5 | 5 | 10 | 5 | 50 | 20 | 25 | 12 | 12 | 20 | 12 | 7.5 | 85 Ohms | TOP=L2:L3=L2/L4:L6=L5/L7:BOTTOM=L7 |
| PE_RX4_DR14_P | PE_RX4_DR14-DIFF1 | PAIR | 3 | 6.5 | 5 | 10 | 5 | 50 | 20 | 25 | 12 | 12 | 20 | 12 | 7.5 | 85 Ohms | TOP=L2:L3=L2/L4:L6=L5/L7:BOTTOM=L7 |
| PE_RX4_DR14_P | PE_RX4_DR14-DIFF1 | PAIR | 4 | 6.5 | 5 | 10 | 5 | 50 | 20 | 25 | 12 | 12 | 20 | 12 | 7.5 | 85 Ohms | TOP=L2:L3=L2/L4:L6=L5/L7:BOTTOM=L7 |
| PE_RX4_DR14_P | PE_RX4_DR14-DIFF1 | PAIR | 5 | 6.5 | 5 | 10 | 5 | 50 | 20 | 25 | 12 | 12 | 20 | 12 | 7.5 | 85 Ohms | TOP=L2:L3=L2/L4:L6=L5/L7:BOTTOM=L7 |
| PE_RX4_DR14_P | PE_RX4_DR14-DIFF1 | PAIR | 6 | 6.5 | 5 | 10 | 5 | 50 | 20 | 25 | 12 | 12 | 20 | 12 | 7.5 | 85 Ohms | TOP=L2:L3=L2/L4:L6=L5/L7:BOTTOM=L7 |
| PE_RX4_DR14_P | PE_RX4_DR14-DIFF1 | PAIR | 7 | 6.5 | 5 | 10 | 5 | 50 | 20 | 25 | 12 | 12 | 20 | 12 | 7.5 | 85 Ohms | TOP=L2:L3=L2/L4:L6=L5/L7:BOTTOM=L7 |
| PE_RX4_DR14_P | PE_RX4_DR14-DIFF1 | PAIR | 8 | 6.88 | 5 | 10 | 5 | 50 | 20 | 36 | 12 | 12 | 20 | 12 | 5.13 | 85 Ohms | TOP=L2:L3=L2/L4:L6=L5/L7:BOTTOM=L7 |
| PE_RX4_DR1_N | PE_RX4_DR1-DIFF1 | PAIR | 1 | 6.88 | 5 | 10 | 5 | 50 | 20 | 36 | 12 | 12 | 20 | 12 | 5.13 | 85 Ohms | TOP=L2:L3=L2/L4:L6=L5/L7:BOTTOM=L7 |
| PE_RX4_DR1_N | PE_RX4_DR1-DIFF1 | PAIR | 2 | 6.5 | 5 | 10 | 5 | 50 | 20 | 25 | 12 | 12 | 20 | 12 | 7.5 | 85 Ohms | TOP=L2:L3=L2/L4:L6=L5/L7:BOTTOM=L7 |
| PE_RX4_DR1_N | PE_RX4_DR1-DIFF1 | PAIR | 3 | 6.5 | 5 | 10 | 5 | 50 | 20 | 25 | 12 | 12 | 20 | 12 | 7.5 | 85 Ohms | TOP=L2:L3=L2/L4:L6=L5/L7:BOTTOM=L7 |
| PE_RX4_DR1_N | PE_RX4_DR1-DIFF1 | PAIR | 4 | 6.5 | 5 | 10 | 5 | 50 | 20 | 25 | 12 | 12 | 20 | 12 | 7.5 | 85 Ohms | TOP=L2:L3=L2/L4:L6=L5/L7:BOTTOM=L7 |
| PE_RX4_DR1_N | PE_RX4_DR1-DIFF1 | PAIR | 5 | 6.5 | 5 | 10 | 5 | 50 | 20 | 25 | 12 | 12 | 20 | 12 | 7.5 | 85 Ohms | TOP=L2:L3=L2/L4:L6=L5/L7:BOTTOM=L7 |
| PE_RX4_DR1_N | PE_RX4_DR1-DIFF1 | PAIR | 6 | 6.5 | 5 | 10 | 5 | 50 | 20 | 25 | 12 | 12 | 20 | 12 | 7.5 | 85 Ohms | TOP=L2:L3=L2/L4:L6=L5/L7:BOTTOM=L7 |
| PE_RX4_DR1_N | PE_RX4_DR1-DIFF1 | PAIR | 7 | 6.5 | 5 | 10 | 5 | 50 | 20 | 25 | 12 | 12 | 20 | 12 | 7.5 | 85 Ohms | TOP=L2:L3=L2/L4:L6=L5/L7:BOTTOM=L7 |
| PE_RX4_DR1_N | PE_RX4_DR1-DIFF1 | PAIR | 8 | 6.88 | 5 | 10 | 5 | 50 | 20 | 36 | 12 | 12 | 20 | 12 | 5.13 | 85 Ohms | TOP=L2:L3=L2/L4:L6=L5/L7:BOTTOM=L7 |
| PE_RX4_DR1_P | PE_RX4_DR1-DIFF1 | PAIR | 1 | 6.88 | 5 | 10 | 5 | 50 | 20 | 36 | 12 | 12 | 20 | 12 | 5.13 | 85 Ohms | TOP=L2:L3=L2/L4:L6=L5/L7:BOTTOM=L7 |
| PE_RX4_DR1_P | PE_RX4_DR1-DIFF1 | PAIR | 2 | 6.5 | 5 | 10 | 5 | 50 | 20 | 25 | 12 | 12 | 20 | 12 | 7.5 | 85 Ohms | TOP=L2:L3=L2/L4:L6=L5/L7:BOTTOM=L7 |
| PE_RX4_DR1_P | PE_RX4_DR1-DIFF1 | PAIR | 3 | 6.5 | 5 | 10 | 5 | 50 | 20 | 25 | 12 | 12 | 20 | 12 | 7.5 | 85 Ohms | TOP=L2:L3=L2/L4:L6=L5/L7:BOTTOM=L7 |
| PE_RX4_DR1_P | PE_RX4_DR1-DIFF1 | PAIR | 4 | 6.5 | 5 | 10 | 5 | 50 | 20 | 25 | 12 | 12 | 20 | 12 | 7.5 | 85 Ohms | TOP=L2:L3=L2/L4:L6=L5/L7:BOTTOM=L7 |
| PE_RX4_DR1_P | PE_RX4_DR1-DIFF1 | PAIR | 5 | 6.5 | 5 | 10 | 5 | 50 | 20 | 25 | 12 | 12 | 20 | 12 | 7.5 | 85 Ohms | TOP=L2:L3=L2/L4:L6=L5/L7:BOTTOM=L7 |
| PE_RX4_DR1_P | PE_RX4_DR1-DIFF1 | PAIR | 6 | 6.5 | 5 | 10 | 5 | 50 | 20 | 25 | 12 | 12 | 20 | 12 | 7.5 | 85 Ohms | TOP=L2:L3=L2/L4:L6=L5/L7:BOTTOM=L7 |
| PE_RX4_DR1_P | PE_RX4_DR1-DIFF1 | PAIR | 7 | 6.5 | 5 | 10 | 5 | 50 | 20 | 25 | 12 | 12 | 20 | 12 | 7.5 | 85 Ohms | TOP=L2:L3=L2/L4:L6=L5/L7:BOTTOM=L7 |
| PE_RX4_DR1_P | PE_RX4_DR1-DIFF1 | PAIR | 8 | 6.88 | 5 | 10 | 5 | 50 | 20 | 36 | 12 | 12 | 20 | 12 | 5.13 | 85 Ohms | TOP=L2:L3=L2/L4:L6=L5/L7:BOTTOM=L7 |
| PE_RX4_DR2_N | PE_RX4_DR2-DIFF1 | PAIR | 1 | 6.88 | 5 | 10 | 5 | 50 | 20 | 36 | 12 | 12 | 20 | 12 | 5.13 | 85 Ohms | TOP=L2:L3=L2/L4:L6=L5/L7:BOTTOM=L7 |
| PE_RX4_DR2_N | PE_RX4_DR2-DIFF1 | PAIR | 2 | 6.5 | 5 | 10 | 5 | 50 | 20 | 25 | 12 | 12 | 20 | 12 | 7.5 | 85 Ohms | TOP=L2:L3=L2/L4:L6=L5/L7:BOTTOM=L7 |
| PE_RX4_DR2_N | PE_RX4_DR2-DIFF1 | PAIR | 3 | 6.5 | 5 | 10 | 5 | 50 | 20 | 25 | 12 | 12 | 20 | 12 | 7.5 | 85 Ohms | TOP=L2:L3=L2/L4:L6=L5/L7:BOTTOM=L7 |
| PE_RX4_DR2_N | PE_RX4_DR2-DIFF1 | PAIR | 4 | 6.5 | 5 | 10 | 5 | 50 | 20 | 25 | 12 | 12 | 20 | 12 | 7.5 | 85 Ohms | TOP=L2:L3=L2/L4:L6=L5/L7:BOTTOM=L7 |
| PE_RX4_DR2_N | PE_RX4_DR2-DIFF1 | PAIR | 5 | 6.5 | 5 | 10 | 5 | 50 | 20 | 25 | 12 | 12 | 20 | 12 | 7.5 | 85 Ohms | TOP=L2:L3=L2/L4:L6=L5/L7:BOTTOM=L7 |
| PE_RX4_DR2_N | PE_RX4_DR2-DIFF1 | PAIR | 6 | 6.5 | 5 | 10 | 5 | 50 | 20 | 25 | 12 | 12 | 20 | 12 | 7.5 | 85 Ohms | TOP=L2:L3=L2/L4:L6=L5/L7:BOTTOM=L7 |
| PE_RX4_DR2_N | PE_RX4_DR2-DIFF1 | PAIR | 7 | 6.5 | 5 | 10 | 5 | 50 | 20 | 25 | 12 | 12 | 20 | 12 | 7.5 | 85 Ohms | TOP=L2:L3=L2/L4:L6=L5/L7:BOTTOM=L7 |
| PE_RX4_DR2_N | PE_RX4_DR2-DIFF1 | PAIR | 8 | 6.88 | 5 | 10 | 5 | 50 | 20 | 36 | 12 | 12 | 20 | 12 | 5.13 | 85 Ohms | TOP=L2:L3=L2/L4:L6=L5/L7:BOTTOM=L7 |
| PE_RX4_DR2_P | PE_RX4_DR2-DIFF1 | PAIR | 1 | 6.88 | 5 | 10 | 5 | 50 | 20 | 36 | 12 | 12 | 20 | 12 | 5.13 | 85 Ohms | TOP=L2:L3=L2/L4:L6=L5/L7:BOTTOM=L7 |
| PE_RX4_DR2_P | PE_RX4_DR2-DIFF1 | PAIR | 2 | 6.5 | 5 | 10 | 5 | 50 | 20 | 25 | 12 | 12 | 20 | 12 | 7.5 | 85 Ohms | TOP=L2:L3=L2/L4:L6=L5/L7:BOTTOM=L7 |
| PE_RX4_DR2_P | PE_RX4_DR2-DIFF1 | PAIR | 3 | 6.5 | 5 | 10 | 5 | 50 | 20 | 25 | 12 | 12 | 20 | 12 | 7.5 | 85 Ohms | TOP=L2:L3=L2/L4:L6=L5/L7:BOTTOM=L7 |
| PE_RX4_DR2_P | PE_RX4_DR2-DIFF1 | PAIR | 4 | 6.5 | 5 | 10 | 5 | 50 | 20 | 25 | 12 | 12 | 20 | 12 | 7.5 | 85 Ohms | TOP=L2:L3=L2/L4:L6=L5/L7:BOTTOM=L7 |
| PE_RX4_DR2_P | PE_RX4_DR2-DIFF1 | PAIR | 5 | 6.5 | 5 | 10 | 5 | 50 | 20 | 25 | 12 | 12 | 20 | 12 | 7.5 | 85 Ohms | TOP=L2:L3=L2/L4:L6=L5/L7:BOTTOM=L7 |
| PE_RX4_DR2_P | PE_RX4_DR2-DIFF1 | PAIR | 6 | 6.5 | 5 | 10 | 5 | 50 | 20 | 25 | 12 | 12 | 20 | 12 | 7.5 | 85 Ohms | TOP=L2:L3=L2/L4:L6=L5/L7:BOTTOM=L7 |
| PE_RX4_DR2_P | PE_RX4_DR2-DIFF1 | PAIR | 7 | 6.5 | 5 | 10 | 5 | 50 | 20 | 25 | 12 | 12 | 20 | 12 | 7.5 | 85 Ohms | TOP=L2:L3=L2/L4:L6=L5/L7:BOTTOM=L7 |
| PE_RX4_DR2_P | PE_RX4_DR2-DIFF1 | PAIR | 8 | 6.88 | 5 | 10 | 5 | 50 | 20 | 36 | 12 | 12 | 20 | 12 | 5.13 | 85 Ohms | TOP=L2:L3=L2/L4:L6=L5/L7:BOTTOM=L7 |
| PE_RX4_DR3_N | PE_RX4_DR3-DIFF1 | PAIR | 1 | 6.88 | 5 | 10 | 5 | 50 | 20 | 36 | 12 | 12 | 20 | 12 | 5.13 | 85 Ohms | TOP=L2:L3=L2/L4:L6=L5/L7:BOTTOM=L7 |
| PE_RX4_DR3_N | PE_RX4_DR3-DIFF1 | PAIR | 2 | 6.5 | 5 | 10 | 5 | 50 | 20 | 25 | 12 | 12 | 20 | 12 | 7.5 | 85 Ohms | TOP=L2:L3=L2/L4:L6=L5/L7:BOTTOM=L7 |
| PE_RX4_DR3_N | PE_RX4_DR3-DIFF1 | PAIR | 3 | 6.5 | 5 | 10 | 5 | 50 | 20 | 25 | 12 | 12 | 20 | 12 | 7.5 | 85 Ohms | TOP=L2:L3=L2/L4:L6=L5/L7:BOTTOM=L7 |
| PE_RX4_DR3_N | PE_RX4_DR3-DIFF1 | PAIR | 4 | 6.5 | 5 | 10 | 5 | 50 | 20 | 25 | 12 | 12 | 20 | 12 | 7.5 | 85 Ohms | TOP=L2:L3=L2/L4:L6=L5/L7:BOTTOM=L7 |
| PE_RX4_DR3_N | PE_RX4_DR3-DIFF1 | PAIR | 5 | 6.5 | 5 | 10 | 5 | 50 | 20 | 25 | 12 | 12 | 20 | 12 | 7.5 | 85 Ohms | TOP=L2:L3=L2/L4:L6=L5/L7:BOTTOM=L7 |
| PE_RX4_DR3_N | PE_RX4_DR3-DIFF1 | PAIR | 6 | 6.5 | 5 | 10 | 5 | 50 | 20 | 25 | 12 | 12 | 20 | 12 | 7.5 | 85 Ohms | TOP=L2:L3=L2/L4:L6=L5/L7:BOTTOM=L7 |
| PE_RX4_DR3_N | PE_RX4_DR3-DIFF1 | PAIR | 7 | 6.5 | 5 | 10 | 5 | 50 | 20 | 25 | 12 | 12 | 20 | 12 | 7.5 | 85 Ohms | TOP=L2:L3=L2/L4:L6=L5/L7:BOTTOM=L7 |
| PE_RX4_DR3_N | PE_RX4_DR3-DIFF1 | PAIR | 8 | 6.88 | 5 | 10 | 5 | 50 | 20 | 36 | 12 | 12 | 20 | 12 | 5.13 | 85 Ohms | TOP=L2:L3=L2/L4:L6=L5/L7:BOTTOM=L7 |
| PE_RX4_DR3_P | PE_RX4_DR3-DIFF1 | PAIR | 1 | 6.88 | 5 | 10 | 5 | 50 | 20 | 36 | 12 | 12 | 20 | 12 | 5.13 | 85 Ohms | TOP=L2:L3=L2/L4:L6=L5/L7:BOTTOM=L7 |
| PE_RX4_DR3_P | PE_RX4_DR3-DIFF1 | PAIR | 2 | 6.5 | 5 | 10 | 5 | 50 | 20 | 25 | 12 | 12 | 20 | 12 | 7.5 | 85 Ohms | TOP=L2:L3=L2/L4:L6=L5/L7:BOTTOM=L7 |
| PE_RX4_DR3_P | PE_RX4_DR3-DIFF1 | PAIR | 3 | 6.5 | 5 | 10 | 5 | 50 | 20 | 25 | 12 | 12 | 20 | 12 | 7.5 | 85 Ohms | TOP=L2:L3=L2/L4:L6=L5/L7:BOTTOM=L7 |
| PE_RX4_DR3_P | PE_RX4_DR3-DIFF1 | PAIR | 4 | 6.5 | 5 | 10 | 5 | 50 | 20 | 25 | 12 | 12 | 20 | 12 | 7.5 | 85 Ohms | TOP=L2:L3=L2/L4:L6=L5/L7:BOTTOM=L7 |
| PE_RX4_DR3_P | PE_RX4_DR3-DIFF1 | PAIR | 5 | 6.5 | 5 | 10 | 5 | 50 | 20 | 25 | 12 | 12 | 20 | 12 | 7.5 | 85 Ohms | TOP=L2:L3=L2/L4:L6=L5/L7:BOTTOM=L7 |
| PE_RX4_DR3_P | PE_RX4_DR3-DIFF1 | PAIR | 6 | 6.5 | 5 | 10 | 5 | 50 | 20 | 25 | 12 | 12 | 20 | 12 | 7.5 | 85 Ohms | TOP=L2:L3=L2/L4:L6=L5/L7:BOTTOM=L7 |
| PE_RX4_DR3_P | PE_RX4_DR3-DIFF1 | PAIR | 7 | 6.5 | 5 | 10 | 5 | 50 | 20 | 25 | 12 | 12 | 20 | 12 | 7.5 | 85 Ohms | TOP=L2:L3=L2/L4:L6=L5/L7:BOTTOM=L7 |
| PE_RX4_DR3_P | PE_RX4_DR3-DIFF1 | PAIR | 8 | 6.88 | 5 | 10 | 5 | 50 | 20 | 36 | 12 | 12 | 20 | 12 | 5.13 | 85 Ohms | TOP=L2:L3=L2/L4:L6=L5/L7:BOTTOM=L7 |
| PE_RX4_DR4_N | PE_RX4_DR4-DIFF1 | PAIR | 1 | 6.88 | 5 | 10 | 5 | 50 | 20 | 36 | 12 | 12 | 20 | 12 | 5.13 | 85 Ohms | TOP=L2:L3=L2/L4:L6=L5/L7:BOTTOM=L7 |
| PE_RX4_DR4_N | PE_RX4_DR4-DIFF1 | PAIR | 2 | 6.5 | 5 | 10 | 5 | 50 | 20 | 25 | 12 | 12 | 20 | 12 | 7.5 | 85 Ohms | TOP=L2:L3=L2/L4:L6=L5/L7:BOTTOM=L7 |
| PE_RX4_DR4_N | PE_RX4_DR4-DIFF1 | PAIR | 3 | 6.5 | 5 | 10 | 5 | 50 | 20 | 25 | 12 | 12 | 20 | 12 | 7.5 | 85 Ohms | TOP=L2:L3=L2/L4:L6=L5/L7:BOTTOM=L7 |
| PE_RX4_DR4_N | PE_RX4_DR4-DIFF1 | PAIR | 4 | 6.5 | 5 | 10 | 5 | 50 | 20 | 25 | 12 | 12 | 20 | 12 | 7.5 | 85 Ohms | TOP=L2:L3=L2/L4:L6=L5/L7:BOTTOM=L7 |
| PE_RX4_DR4_N | PE_RX4_DR4-DIFF1 | PAIR | 5 | 6.5 | 5 | 10 | 5 | 50 | 20 | 25 | 12 | 12 | 20 | 12 | 7.5 | 85 Ohms | TOP=L2:L3=L2/L4:L6=L5/L7:BOTTOM=L7 |
| PE_RX4_DR4_N | PE_RX4_DR4-DIFF1 | PAIR | 6 | 6.5 | 5 | 10 | 5 | 50 | 20 | 25 | 12 | 12 | 20 | 12 | 7.5 | 85 Ohms | TOP=L2:L3=L2/L4:L6=L5/L7:BOTTOM=L7 |
| PE_RX4_DR4_N | PE_RX4_DR4-DIFF1 | PAIR | 7 | 6.5 | 5 | 10 | 5 | 50 | 20 | 25 | 12 | 12 | 20 | 12 | 7.5 | 85 Ohms | TOP=L2:L3=L2/L4:L6=L5/L7:BOTTOM=L7 |
| PE_RX4_DR4_N | PE_RX4_DR4-DIFF1 | PAIR | 8 | 6.88 | 5 | 10 | 5 | 50 | 20 | 36 | 12 | 12 | 20 | 12 | 5.13 | 85 Ohms | TOP=L2:L3=L2/L4:L6=L5/L7:BOTTOM=L7 |
| PE_RX4_DR4_P | PE_RX4_DR4-DIFF1 | PAIR | 1 | 6.88 | 5 | 10 | 5 | 50 | 20 | 36 | 12 | 12 | 20 | 12 | 5.13 | 85 Ohms | TOP=L2:L3=L2/L4:L6=L5/L7:BOTTOM=L7 |
| PE_RX4_DR4_P | PE_RX4_DR4-DIFF1 | PAIR | 2 | 6.5 | 5 | 10 | 5 | 50 | 20 | 25 | 12 | 12 | 20 | 12 | 7.5 | 85 Ohms | TOP=L2:L3=L2/L4:L6=L5/L7:BOTTOM=L7 |
| PE_RX4_DR4_P | PE_RX4_DR4-DIFF1 | PAIR | 3 | 6.5 | 5 | 10 | 5 | 50 | 20 | 25 | 12 | 12 | 20 | 12 | 7.5 | 85 Ohms | TOP=L2:L3=L2/L4:L6=L5/L7:BOTTOM=L7 |
| PE_RX4_DR4_P | PE_RX4_DR4-DIFF1 | PAIR | 4 | 6.5 | 5 | 10 | 5 | 50 | 20 | 25 | 12 | 12 | 20 | 12 | 7.5 | 85 Ohms | TOP=L2:L3=L2/L4:L6=L5/L7:BOTTOM=L7 |
| PE_RX4_DR4_P | PE_RX4_DR4-DIFF1 | PAIR | 5 | 6.5 | 5 | 10 | 5 | 50 | 20 | 25 | 12 | 12 | 20 | 12 | 7.5 | 85 Ohms | TOP=L2:L3=L2/L4:L6=L5/L7:BOTTOM=L7 |
| PE_RX4_DR4_P | PE_RX4_DR4-DIFF1 | PAIR | 6 | 6.5 | 5 | 10 | 5 | 50 | 20 | 25 | 12 | 12 | 20 | 12 | 7.5 | 85 Ohms | TOP=L2:L3=L2/L4:L6=L5/L7:BOTTOM=L7 |
| PE_RX4_DR4_P | PE_RX4_DR4-DIFF1 | PAIR | 7 | 6.5 | 5 | 10 | 5 | 50 | 20 | 25 | 12 | 12 | 20 | 12 | 7.5 | 85 Ohms | TOP=L2:L3=L2/L4:L6=L5/L7:BOTTOM=L7 |
| PE_RX4_DR4_P | PE_RX4_DR4-DIFF1 | PAIR | 8 | 6.88 | 5 | 10 | 5 | 50 | 20 | 36 | 12 | 12 | 20 | 12 | 5.13 | 85 Ohms | TOP=L2:L3=L2/L4:L6=L5/L7:BOTTOM=L7 |
| PE_RX4_DR5_N | PE_RX4_DR5-DIFF1 | PAIR | 1 | 6.88 | 5 | 10 | 5 | 50 | 20 | 36 | 12 | 12 | 20 | 12 | 5.13 | 85 Ohms | TOP=L2:L3=L2/L4:L6=L5/L7:BOTTOM=L7 |
| PE_RX4_DR5_N | PE_RX4_DR5-DIFF1 | PAIR | 2 | 6.5 | 5 | 10 | 5 | 50 | 20 | 25 | 12 | 12 | 20 | 12 | 7.5 | 85 Ohms | TOP=L2:L3=L2/L4:L6=L5/L7:BOTTOM=L7 |
| PE_RX4_DR5_N | PE_RX4_DR5-DIFF1 | PAIR | 3 | 6.5 | 5 | 10 | 5 | 50 | 20 | 25 | 12 | 12 | 20 | 12 | 7.5 | 85 Ohms | TOP=L2:L3=L2/L4:L6=L5/L7:BOTTOM=L7 |
| PE_RX4_DR5_N | PE_RX4_DR5-DIFF1 | PAIR | 4 | 6.5 | 5 | 10 | 5 | 50 | 20 | 25 | 12 | 12 | 20 | 12 | 7.5 | 85 Ohms | TOP=L2:L3=L2/L4:L6=L5/L7:BOTTOM=L7 |
| PE_RX4_DR5_N | PE_RX4_DR5-DIFF1 | PAIR | 5 | 6.5 | 5 | 10 | 5 | 50 | 20 | 25 | 12 | 12 | 20 | 12 | 7.5 | 85 Ohms | TOP=L2:L3=L2/L4:L6=L5/L7:BOTTOM=L7 |
| PE_RX4_DR5_N | PE_RX4_DR5-DIFF1 | PAIR | 6 | 6.5 | 5 | 10 | 5 | 50 | 20 | 25 | 12 | 12 | 20 | 12 | 7.5 | 85 Ohms | TOP=L2:L3=L2/L4:L6=L5/L7:BOTTOM=L7 |
| PE_RX4_DR5_N | PE_RX4_DR5-DIFF1 | PAIR | 7 | 6.5 | 5 | 10 | 5 | 50 | 20 | 25 | 12 | 12 | 20 | 12 | 7.5 | 85 Ohms | TOP=L2:L3=L2/L4:L6=L5/L7:BOTTOM=L7 |
| PE_RX4_DR5_N | PE_RX4_DR5-DIFF1 | PAIR | 8 | 6.88 | 5 | 10 | 5 | 50 | 20 | 36 | 12 | 12 | 20 | 12 | 5.13 | 85 Ohms | TOP=L2:L3=L2/L4:L6=L5/L7:BOTTOM=L7 |
| PE_RX4_DR5_P | PE_RX4_DR5-DIFF1 | PAIR | 1 | 6.88 | 5 | 10 | 5 | 50 | 20 | 36 | 12 | 12 | 20 | 12 | 5.13 | 85 Ohms | TOP=L2:L3=L2/L4:L6=L5/L7:BOTTOM=L7 |
| PE_RX4_DR5_P | PE_RX4_DR5-DIFF1 | PAIR | 2 | 6.5 | 5 | 10 | 5 | 50 | 20 | 25 | 12 | 12 | 20 | 12 | 7.5 | 85 Ohms | TOP=L2:L3=L2/L4:L6=L5/L7:BOTTOM=L7 |
| PE_RX4_DR5_P | PE_RX4_DR5-DIFF1 | PAIR | 3 | 6.5 | 5 | 10 | 5 | 50 | 20 | 25 | 12 | 12 | 20 | 12 | 7.5 | 85 Ohms | TOP=L2:L3=L2/L4:L6=L5/L7:BOTTOM=L7 |
| PE_RX4_DR5_P | PE_RX4_DR5-DIFF1 | PAIR | 4 | 6.5 | 5 | 10 | 5 | 50 | 20 | 25 | 12 | 12 | 20 | 12 | 7.5 | 85 Ohms | TOP=L2:L3=L2/L4:L6=L5/L7:BOTTOM=L7 |
| PE_RX4_DR5_P | PE_RX4_DR5-DIFF1 | PAIR | 5 | 6.5 | 5 | 10 | 5 | 50 | 20 | 25 | 12 | 12 | 20 | 12 | 7.5 | 85 Ohms | TOP=L2:L3=L2/L4:L6=L5/L7:BOTTOM=L7 |
| PE_RX4_DR5_P | PE_RX4_DR5-DIFF1 | PAIR | 6 | 6.5 | 5 | 10 | 5 | 50 | 20 | 25 | 12 | 12 | 20 | 12 | 7.5 | 85 Ohms | TOP=L2:L3=L2/L4:L6=L5/L7:BOTTOM=L7 |
| PE_RX4_DR5_P | PE_RX4_DR5-DIFF1 | PAIR | 7 | 6.5 | 5 | 10 | 5 | 50 | 20 | 25 | 12 | 12 | 20 | 12 | 7.5 | 85 Ohms | TOP=L2:L3=L2/L4:L6=L5/L7:BOTTOM=L7 |
| PE_RX4_DR5_P | PE_RX4_DR5-DIFF1 | PAIR | 8 | 6.88 | 5 | 10 | 5 | 50 | 20 | 36 | 12 | 12 | 20 | 12 | 5.13 | 85 Ohms | TOP=L2:L3=L2/L4:L6=L5/L7:BOTTOM=L7 |
| PE_RX4_DR6_N | PE_RX4_DR6-DIFF1 | PAIR | 1 | 6.88 | 5 | 10 | 5 | 50 | 20 | 36 | 12 | 12 | 20 | 12 | 5.13 | 85 Ohms | TOP=L2:L3=L2/L4:L6=L5/L7:BOTTOM=L7 |
| PE_RX4_DR6_N | PE_RX4_DR6-DIFF1 | PAIR | 2 | 6.5 | 5 | 10 | 5 | 50 | 20 | 25 | 12 | 12 | 20 | 12 | 7.5 | 85 Ohms | TOP=L2:L3=L2/L4:L6=L5/L7:BOTTOM=L7 |
| PE_RX4_DR6_N | PE_RX4_DR6-DIFF1 | PAIR | 3 | 6.5 | 5 | 10 | 5 | 50 | 20 | 25 | 12 | 12 | 20 | 12 | 7.5 | 85 Ohms | TOP=L2:L3=L2/L4:L6=L5/L7:BOTTOM=L7 |
| PE_RX4_DR6_N | PE_RX4_DR6-DIFF1 | PAIR | 4 | 6.5 | 5 | 10 | 5 | 50 | 20 | 25 | 12 | 12 | 20 | 12 | 7.5 | 85 Ohms | TOP=L2:L3=L2/L4:L6=L5/L7:BOTTOM=L7 |
| PE_RX4_DR6_N | PE_RX4_DR6-DIFF1 | PAIR | 5 | 6.5 | 5 | 10 | 5 | 50 | 20 | 25 | 12 | 12 | 20 | 12 | 7.5 | 85 Ohms | TOP=L2:L3=L2/L4:L6=L5/L7:BOTTOM=L7 |
| PE_RX4_DR6_N | PE_RX4_DR6-DIFF1 | PAIR | 6 | 6.5 | 5 | 10 | 5 | 50 | 20 | 25 | 12 | 12 | 20 | 12 | 7.5 | 85 Ohms | TOP=L2:L3=L2/L4:L6=L5/L7:BOTTOM=L7 |
| PE_RX4_DR6_N | PE_RX4_DR6-DIFF1 | PAIR | 7 | 6.5 | 5 | 10 | 5 | 50 | 20 | 25 | 12 | 12 | 20 | 12 | 7.5 | 85 Ohms | TOP=L2:L3=L2/L4:L6=L5/L7:BOTTOM=L7 |
| PE_RX4_DR6_N | PE_RX4_DR6-DIFF1 | PAIR | 8 | 6.88 | 5 | 10 | 5 | 50 | 20 | 36 | 12 | 12 | 20 | 12 | 5.13 | 85 Ohms | TOP=L2:L3=L2/L4:L6=L5/L7:BOTTOM=L7 |
| PE_RX4_DR6_P | PE_RX4_DR6-DIFF1 | PAIR | 1 | 6.88 | 5 | 10 | 5 | 50 | 20 | 36 | 12 | 12 | 20 | 12 | 5.13 | 85 Ohms | TOP=L2:L3=L2/L4:L6=L5/L7:BOTTOM=L7 |
| PE_RX4_DR6_P | PE_RX4_DR6-DIFF1 | PAIR | 2 | 6.5 | 5 | 10 | 5 | 50 | 20 | 25 | 12 | 12 | 20 | 12 | 7.5 | 85 Ohms | TOP=L2:L3=L2/L4:L6=L5/L7:BOTTOM=L7 |
| PE_RX4_DR6_P | PE_RX4_DR6-DIFF1 | PAIR | 3 | 6.5 | 5 | 10 | 5 | 50 | 20 | 25 | 12 | 12 | 20 | 12 | 7.5 | 85 Ohms | TOP=L2:L3=L2/L4:L6=L5/L7:BOTTOM=L7 |
| PE_RX4_DR6_P | PE_RX4_DR6-DIFF1 | PAIR | 4 | 6.5 | 5 | 10 | 5 | 50 | 20 | 25 | 12 | 12 | 20 | 12 | 7.5 | 85 Ohms | TOP=L2:L3=L2/L4:L6=L5/L7:BOTTOM=L7 |
| PE_RX4_DR6_P | PE_RX4_DR6-DIFF1 | PAIR | 5 | 6.5 | 5 | 10 | 5 | 50 | 20 | 25 | 12 | 12 | 20 | 12 | 7.5 | 85 Ohms | TOP=L2:L3=L2/L4:L6=L5/L7:BOTTOM=L7 |
| PE_RX4_DR6_P | PE_RX4_DR6-DIFF1 | PAIR | 6 | 6.5 | 5 | 10 | 5 | 50 | 20 | 25 | 12 | 12 | 20 | 12 | 7.5 | 85 Ohms | TOP=L2:L3=L2/L4:L6=L5/L7:BOTTOM=L7 |
| PE_RX4_DR6_P | PE_RX4_DR6-DIFF1 | PAIR | 7 | 6.5 | 5 | 10 | 5 | 50 | 20 | 25 | 12 | 12 | 20 | 12 | 7.5 | 85 Ohms | TOP=L2:L3=L2/L4:L6=L5/L7:BOTTOM=L7 |
| PE_RX4_DR6_P | PE_RX4_DR6-DIFF1 | PAIR | 8 | 6.88 | 5 | 10 | 5 | 50 | 20 | 36 | 12 | 12 | 20 | 12 | 5.13 | 85 Ohms | TOP=L2:L3=L2/L4:L6=L5/L7:BOTTOM=L7 |
| PE_RX4_DR7_N | PE_RX4_DR7-DIFF1 | PAIR | 1 | 6.88 | 5 | 10 | 5 | 50 | 20 | 36 | 12 | 12 | 20 | 12 | 5.13 | 85 Ohms | TOP=L2:L3=L2/L4:L6=L5/L7:BOTTOM=L7 |
| PE_RX4_DR7_N | PE_RX4_DR7-DIFF1 | PAIR | 2 | 6.5 | 5 | 10 | 5 | 50 | 20 | 25 | 12 | 12 | 20 | 12 | 7.5 | 85 Ohms | TOP=L2:L3=L2/L4:L6=L5/L7:BOTTOM=L7 |
| PE_RX4_DR7_N | PE_RX4_DR7-DIFF1 | PAIR | 3 | 6.5 | 5 | 10 | 5 | 50 | 20 | 25 | 12 | 12 | 20 | 12 | 7.5 | 85 Ohms | TOP=L2:L3=L2/L4:L6=L5/L7:BOTTOM=L7 |
| PE_RX4_DR7_N | PE_RX4_DR7-DIFF1 | PAIR | 4 | 6.5 | 5 | 10 | 5 | 50 | 20 | 25 | 12 | 12 | 20 | 12 | 7.5 | 85 Ohms | TOP=L2:L3=L2/L4:L6=L5/L7:BOTTOM=L7 |
| PE_RX4_DR7_N | PE_RX4_DR7-DIFF1 | PAIR | 5 | 6.5 | 5 | 10 | 5 | 50 | 20 | 25 | 12 | 12 | 20 | 12 | 7.5 | 85 Ohms | TOP=L2:L3=L2/L4:L6=L5/L7:BOTTOM=L7 |
| PE_RX4_DR7_N | PE_RX4_DR7-DIFF1 | PAIR | 6 | 6.5 | 5 | 10 | 5 | 50 | 20 | 25 | 12 | 12 | 20 | 12 | 7.5 | 85 Ohms | TOP=L2:L3=L2/L4:L6=L5/L7:BOTTOM=L7 |
| PE_RX4_DR7_N | PE_RX4_DR7-DIFF1 | PAIR | 7 | 6.5 | 5 | 10 | 5 | 50 | 20 | 25 | 12 | 12 | 20 | 12 | 7.5 | 85 Ohms | TOP=L2:L3=L2/L4:L6=L5/L7:BOTTOM=L7 |
| PE_RX4_DR7_N | PE_RX4_DR7-DIFF1 | PAIR | 8 | 6.88 | 5 | 10 | 5 | 50 | 20 | 36 | 12 | 12 | 20 | 12 | 5.13 | 85 Ohms | TOP=L2:L3=L2/L4:L6=L5/L7:BOTTOM=L7 |
| PE_RX4_DR7_P | PE_RX4_DR7-DIFF1 | PAIR | 1 | 6.88 | 5 | 10 | 5 | 50 | 20 | 36 | 12 | 12 | 20 | 12 | 5.13 | 85 Ohms | TOP=L2:L3=L2/L4:L6=L5/L7:BOTTOM=L7 |
| PE_RX4_DR7_P | PE_RX4_DR7-DIFF1 | PAIR | 2 | 6.5 | 5 | 10 | 5 | 50 | 20 | 25 | 12 | 12 | 20 | 12 | 7.5 | 85 Ohms | TOP=L2:L3=L2/L4:L6=L5/L7:BOTTOM=L7 |
| PE_RX4_DR7_P | PE_RX4_DR7-DIFF1 | PAIR | 3 | 6.5 | 5 | 10 | 5 | 50 | 20 | 25 | 12 | 12 | 20 | 12 | 7.5 | 85 Ohms | TOP=L2:L3=L2/L4:L6=L5/L7:BOTTOM=L7 |
| PE_RX4_DR7_P | PE_RX4_DR7-DIFF1 | PAIR | 4 | 6.5 | 5 | 10 | 5 | 50 | 20 | 25 | 12 | 12 | 20 | 12 | 7.5 | 85 Ohms | TOP=L2:L3=L2/L4:L6=L5/L7:BOTTOM=L7 |
| PE_RX4_DR7_P | PE_RX4_DR7-DIFF1 | PAIR | 5 | 6.5 | 5 | 10 | 5 | 50 | 20 | 25 | 12 | 12 | 20 | 12 | 7.5 | 85 Ohms | TOP=L2:L3=L2/L4:L6=L5/L7:BOTTOM=L7 |
| PE_RX4_DR7_P | PE_RX4_DR7-DIFF1 | PAIR | 6 | 6.5 | 5 | 10 | 5 | 50 | 20 | 25 | 12 | 12 | 20 | 12 | 7.5 | 85 Ohms | TOP=L2:L3=L2/L4:L6=L5/L7:BOTTOM=L7 |
| PE_RX4_DR7_P | PE_RX4_DR7-DIFF1 | PAIR | 7 | 6.5 | 5 | 10 | 5 | 50 | 20 | 25 | 12 | 12 | 20 | 12 | 7.5 | 85 Ohms | TOP=L2:L3=L2/L4:L6=L5/L7:BOTTOM=L7 |
| PE_RX4_DR7_P | PE_RX4_DR7-DIFF1 | PAIR | 8 | 6.88 | 5 | 10 | 5 | 50 | 20 | 36 | 12 | 12 | 20 | 12 | 5.13 | 85 Ohms | TOP=L2:L3=L2/L4:L6=L5/L7:BOTTOM=L7 |
| PE_RX4_DR8_N | PE_RX4_DR8-DIFF1 | PAIR | 1 | 6.88 | 5 | 10 | 5 | 50 | 20 | 36 | 12 | 12 | 20 | 12 | 5.13 | 85 Ohms | TOP=L2:L3=L2/L4:L6=L5/L7:BOTTOM=L7 |
| PE_RX4_DR8_N | PE_RX4_DR8-DIFF1 | PAIR | 2 | 6.5 | 5 | 10 | 5 | 50 | 20 | 25 | 12 | 12 | 20 | 12 | 7.5 | 85 Ohms | TOP=L2:L3=L2/L4:L6=L5/L7:BOTTOM=L7 |
| PE_RX4_DR8_N | PE_RX4_DR8-DIFF1 | PAIR | 3 | 6.5 | 5 | 10 | 5 | 50 | 20 | 25 | 12 | 12 | 20 | 12 | 7.5 | 85 Ohms | TOP=L2:L3=L2/L4:L6=L5/L7:BOTTOM=L7 |
| PE_RX4_DR8_N | PE_RX4_DR8-DIFF1 | PAIR | 4 | 6.5 | 5 | 10 | 5 | 50 | 20 | 25 | 12 | 12 | 20 | 12 | 7.5 | 85 Ohms | TOP=L2:L3=L2/L4:L6=L5/L7:BOTTOM=L7 |
| PE_RX4_DR8_N | PE_RX4_DR8-DIFF1 | PAIR | 5 | 6.5 | 5 | 10 | 5 | 50 | 20 | 25 | 12 | 12 | 20 | 12 | 7.5 | 85 Ohms | TOP=L2:L3=L2/L4:L6=L5/L7:BOTTOM=L7 |
| PE_RX4_DR8_N | PE_RX4_DR8-DIFF1 | PAIR | 6 | 6.5 | 5 | 10 | 5 | 50 | 20 | 25 | 12 | 12 | 20 | 12 | 7.5 | 85 Ohms | TOP=L2:L3=L2/L4:L6=L5/L7:BOTTOM=L7 |
| PE_RX4_DR8_N | PE_RX4_DR8-DIFF1 | PAIR | 7 | 6.5 | 5 | 10 | 5 | 50 | 20 | 25 | 12 | 12 | 20 | 12 | 7.5 | 85 Ohms | TOP=L2:L3=L2/L4:L6=L5/L7:BOTTOM=L7 |
| PE_RX4_DR8_N | PE_RX4_DR8-DIFF1 | PAIR | 8 | 6.88 | 5 | 10 | 5 | 50 | 20 | 36 | 12 | 12 | 20 | 12 | 5.13 | 85 Ohms | TOP=L2:L3=L2/L4:L6=L5/L7:BOTTOM=L7 |
| PE_RX4_DR8_P | PE_RX4_DR8-DIFF1 | PAIR | 1 | 6.88 | 5 | 10 | 5 | 50 | 20 | 36 | 12 | 12 | 20 | 12 | 5.13 | 85 Ohms | TOP=L2:L3=L2/L4:L6=L5/L7:BOTTOM=L7 |
| PE_RX4_DR8_P | PE_RX4_DR8-DIFF1 | PAIR | 2 | 6.5 | 5 | 10 | 5 | 50 | 20 | 25 | 12 | 12 | 20 | 12 | 7.5 | 85 Ohms | TOP=L2:L3=L2/L4:L6=L5/L7:BOTTOM=L7 |
| PE_RX4_DR8_P | PE_RX4_DR8-DIFF1 | PAIR | 3 | 6.5 | 5 | 10 | 5 | 50 | 20 | 25 | 12 | 12 | 20 | 12 | 7.5 | 85 Ohms | TOP=L2:L3=L2/L4:L6=L5/L7:BOTTOM=L7 |
| PE_RX4_DR8_P | PE_RX4_DR8-DIFF1 | PAIR | 4 | 6.5 | 5 | 10 | 5 | 50 | 20 | 25 | 12 | 12 | 20 | 12 | 7.5 | 85 Ohms | TOP=L2:L3=L2/L4:L6=L5/L7:BOTTOM=L7 |
| PE_RX4_DR8_P | PE_RX4_DR8-DIFF1 | PAIR | 5 | 6.5 | 5 | 10 | 5 | 50 | 20 | 25 | 12 | 12 | 20 | 12 | 7.5 | 85 Ohms | TOP=L2:L3=L2/L4:L6=L5/L7:BOTTOM=L7 |
| PE_RX4_DR8_P | PE_RX4_DR8-DIFF1 | PAIR | 6 | 6.5 | 5 | 10 | 5 | 50 | 20 | 25 | 12 | 12 | 20 | 12 | 7.5 | 85 Ohms | TOP=L2:L3=L2/L4:L6=L5/L7:BOTTOM=L7 |
| PE_RX4_DR8_P | PE_RX4_DR8-DIFF1 | PAIR | 7 | 6.5 | 5 | 10 | 5 | 50 | 20 | 25 | 12 | 12 | 20 | 12 | 7.5 | 85 Ohms | TOP=L2:L3=L2/L4:L6=L5/L7:BOTTOM=L7 |
| PE_RX4_DR8_P | PE_RX4_DR8-DIFF1 | PAIR | 8 | 6.88 | 5 | 10 | 5 | 50 | 20 | 36 | 12 | 12 | 20 | 12 | 5.13 | 85 Ohms | TOP=L2:L3=L2/L4:L6=L5/L7:BOTTOM=L7 |
| PE_RX4_DR9_N | PE_RX4_DR9-DIFF1 | PAIR | 1 | 6.88 | 5 | 10 | 5 | 50 | 20 | 36 | 12 | 12 | 20 | 12 | 5.13 | 85 Ohms | TOP=L2:L3=L2/L4:L6=L5/L7:BOTTOM=L7 |
| PE_RX4_DR9_N | PE_RX4_DR9-DIFF1 | PAIR | 2 | 6.5 | 5 | 10 | 5 | 50 | 20 | 25 | 12 | 12 | 20 | 12 | 7.5 | 85 Ohms | TOP=L2:L3=L2/L4:L6=L5/L7:BOTTOM=L7 |
| PE_RX4_DR9_N | PE_RX4_DR9-DIFF1 | PAIR | 3 | 6.5 | 5 | 10 | 5 | 50 | 20 | 25 | 12 | 12 | 20 | 12 | 7.5 | 85 Ohms | TOP=L2:L3=L2/L4:L6=L5/L7:BOTTOM=L7 |
| PE_RX4_DR9_N | PE_RX4_DR9-DIFF1 | PAIR | 4 | 6.5 | 5 | 10 | 5 | 50 | 20 | 25 | 12 | 12 | 20 | 12 | 7.5 | 85 Ohms | TOP=L2:L3=L2/L4:L6=L5/L7:BOTTOM=L7 |
| PE_RX4_DR9_N | PE_RX4_DR9-DIFF1 | PAIR | 5 | 6.5 | 5 | 10 | 5 | 50 | 20 | 25 | 12 | 12 | 20 | 12 | 7.5 | 85 Ohms | TOP=L2:L3=L2/L4:L6=L5/L7:BOTTOM=L7 |
| PE_RX4_DR9_N | PE_RX4_DR9-DIFF1 | PAIR | 6 | 6.5 | 5 | 10 | 5 | 50 | 20 | 25 | 12 | 12 | 20 | 12 | 7.5 | 85 Ohms | TOP=L2:L3=L2/L4:L6=L5/L7:BOTTOM=L7 |
| PE_RX4_DR9_N | PE_RX4_DR9-DIFF1 | PAIR | 7 | 6.5 | 5 | 10 | 5 | 50 | 20 | 25 | 12 | 12 | 20 | 12 | 7.5 | 85 Ohms | TOP=L2:L3=L2/L4:L6=L5/L7:BOTTOM=L7 |
| PE_RX4_DR9_N | PE_RX4_DR9-DIFF1 | PAIR | 8 | 6.88 | 5 | 10 | 5 | 50 | 20 | 36 | 12 | 12 | 20 | 12 | 5.13 | 85 Ohms | TOP=L2:L3=L2/L4:L6=L5/L7:BOTTOM=L7 |
| PE_RX4_DR9_P | PE_RX4_DR9-DIFF1 | PAIR | 1 | 6.88 | 5 | 10 | 5 | 50 | 20 | 36 | 12 | 12 | 20 | 12 | 5.13 | 85 Ohms | TOP=L2:L3=L2/L4:L6=L5/L7:BOTTOM=L7 |
| PE_RX4_DR9_P | PE_RX4_DR9-DIFF1 | PAIR | 2 | 6.5 | 5 | 10 | 5 | 50 | 20 | 25 | 12 | 12 | 20 | 12 | 7.5 | 85 Ohms | TOP=L2:L3=L2/L4:L6=L5/L7:BOTTOM=L7 |
| PE_RX4_DR9_P | PE_RX4_DR9-DIFF1 | PAIR | 3 | 6.5 | 5 | 10 | 5 | 50 | 20 | 25 | 12 | 12 | 20 | 12 | 7.5 | 85 Ohms | TOP=L2:L3=L2/L4:L6=L5/L7:BOTTOM=L7 |
| PE_RX4_DR9_P | PE_RX4_DR9-DIFF1 | PAIR | 4 | 6.5 | 5 | 10 | 5 | 50 | 20 | 25 | 12 | 12 | 20 | 12 | 7.5 | 85 Ohms | TOP=L2:L3=L2/L4:L6=L5/L7:BOTTOM=L7 |
| PE_RX4_DR9_P | PE_RX4_DR9-DIFF1 | PAIR | 5 | 6.5 | 5 | 10 | 5 | 50 | 20 | 25 | 12 | 12 | 20 | 12 | 7.5 | 85 Ohms | TOP=L2:L3=L2/L4:L6=L5/L7:BOTTOM=L7 |
| PE_RX4_DR9_P | PE_RX4_DR9-DIFF1 | PAIR | 6 | 6.5 | 5 | 10 | 5 | 50 | 20 | 25 | 12 | 12 | 20 | 12 | 7.5 | 85 Ohms | TOP=L2:L3=L2/L4:L6=L5/L7:BOTTOM=L7 |
| PE_RX4_DR9_P | PE_RX4_DR9-DIFF1 | PAIR | 7 | 6.5 | 5 | 10 | 5 | 50 | 20 | 25 | 12 | 12 | 20 | 12 | 7.5 | 85 Ohms | TOP=L2:L3=L2/L4:L6=L5/L7:BOTTOM=L7 |
| PE_RX4_DR9_P | PE_RX4_DR9-DIFF1 | PAIR | 8 | 6.88 | 5 | 10 | 5 | 50 | 20 | 36 | 12 | 12 | 20 | 12 | 5.13 | 85 Ohms | TOP=L2:L3=L2/L4:L6=L5/L7:BOTTOM=L7 |
| PE_TX1_DR0_N | PE_TX1_DR0-DIFF1 | PAIR | 1 | 6.88 | 5 | 10 | 5 | 50 | 20 | 36 | 12 | 12 | 20 | 12 | 5.13 | 85 Ohms | TOP=L2:L3=L2/L4:L6=L5/L7:BOTTOM=L7 |
| PE_TX1_DR0_N | PE_TX1_DR0-DIFF1 | PAIR | 2 | 6.5 | 5 | 10 | 5 | 50 | 20 | 25 | 12 | 12 | 20 | 12 | 7.5 | 85 Ohms | TOP=L2:L3=L2/L4:L6=L5/L7:BOTTOM=L7 |
| PE_TX1_DR0_N | PE_TX1_DR0-DIFF1 | PAIR | 3 | 6.5 | 5 | 10 | 5 | 50 | 20 | 25 | 12 | 12 | 20 | 12 | 7.5 | 85 Ohms | TOP=L2:L3=L2/L4:L6=L5/L7:BOTTOM=L7 |
| PE_TX1_DR0_N | PE_TX1_DR0-DIFF1 | PAIR | 4 | 6.5 | 5 | 10 | 5 | 50 | 20 | 25 | 12 | 12 | 20 | 12 | 7.5 | 85 Ohms | TOP=L2:L3=L2/L4:L6=L5/L7:BOTTOM=L7 |
| PE_TX1_DR0_N | PE_TX1_DR0-DIFF1 | PAIR | 5 | 6.5 | 5 | 10 | 5 | 50 | 20 | 25 | 12 | 12 | 20 | 12 | 7.5 | 85 Ohms | TOP=L2:L3=L2/L4:L6=L5/L7:BOTTOM=L7 |
| PE_TX1_DR0_N | PE_TX1_DR0-DIFF1 | PAIR | 6 | 6.5 | 5 | 10 | 5 | 50 | 20 | 25 | 12 | 12 | 20 | 12 | 7.5 | 85 Ohms | TOP=L2:L3=L2/L4:L6=L5/L7:BOTTOM=L7 |
| PE_TX1_DR0_N | PE_TX1_DR0-DIFF1 | PAIR | 7 | 6.5 | 5 | 10 | 5 | 50 | 20 | 25 | 12 | 12 | 20 | 12 | 7.5 | 85 Ohms | TOP=L2:L3=L2/L4:L6=L5/L7:BOTTOM=L7 |
| PE_TX1_DR0_N | PE_TX1_DR0-DIFF1 | PAIR | 8 | 6.88 | 5 | 10 | 5 | 50 | 20 | 36 | 12 | 12 | 20 | 12 | 5.13 | 85 Ohms | TOP=L2:L3=L2/L4:L6=L5/L7:BOTTOM=L7 |
| PE_TX1_DR0_P | PE_TX1_DR0-DIFF1 | PAIR | 1 | 6.88 | 5 | 10 | 5 | 50 | 20 | 36 | 12 | 12 | 20 | 12 | 5.13 | 85 Ohms | TOP=L2:L3=L2/L4:L6=L5/L7:BOTTOM=L7 |
| PE_TX1_DR0_P | PE_TX1_DR0-DIFF1 | PAIR | 2 | 6.5 | 5 | 10 | 5 | 50 | 20 | 25 | 12 | 12 | 20 | 12 | 7.5 | 85 Ohms | TOP=L2:L3=L2/L4:L6=L5/L7:BOTTOM=L7 |
| PE_TX1_DR0_P | PE_TX1_DR0-DIFF1 | PAIR | 3 | 6.5 | 5 | 10 | 5 | 50 | 20 | 25 | 12 | 12 | 20 | 12 | 7.5 | 85 Ohms | TOP=L2:L3=L2/L4:L6=L5/L7:BOTTOM=L7 |
| PE_TX1_DR0_P | PE_TX1_DR0-DIFF1 | PAIR | 4 | 6.5 | 5 | 10 | 5 | 50 | 20 | 25 | 12 | 12 | 20 | 12 | 7.5 | 85 Ohms | TOP=L2:L3=L2/L4:L6=L5/L7:BOTTOM=L7 |
| PE_TX1_DR0_P | PE_TX1_DR0-DIFF1 | PAIR | 5 | 6.5 | 5 | 10 | 5 | 50 | 20 | 25 | 12 | 12 | 20 | 12 | 7.5 | 85 Ohms | TOP=L2:L3=L2/L4:L6=L5/L7:BOTTOM=L7 |
| PE_TX1_DR0_P | PE_TX1_DR0-DIFF1 | PAIR | 6 | 6.5 | 5 | 10 | 5 | 50 | 20 | 25 | 12 | 12 | 20 | 12 | 7.5 | 85 Ohms | TOP=L2:L3=L2/L4:L6=L5/L7:BOTTOM=L7 |
| PE_TX1_DR0_P | PE_TX1_DR0-DIFF1 | PAIR | 7 | 6.5 | 5 | 10 | 5 | 50 | 20 | 25 | 12 | 12 | 20 | 12 | 7.5 | 85 Ohms | TOP=L2:L3=L2/L4:L6=L5/L7:BOTTOM=L7 |
| PE_TX1_DR0_P | PE_TX1_DR0-DIFF1 | PAIR | 8 | 6.88 | 5 | 10 | 5 | 50 | 20 | 36 | 12 | 12 | 20 | 12 | 5.13 | 85 Ohms | TOP=L2:L3=L2/L4:L6=L5/L7:BOTTOM=L7 |
| PE_TX1_DR10_N | PE_TX1_DR10-DIFF1 | PAIR | 1 | 6.88 | 5 | 10 | 5 | 50 | 20 | 36 | 12 | 12 | 20 | 12 | 5.13 | 85 Ohms | TOP=L2:L3=L2/L4:L6=L5/L7:BOTTOM=L7 |
| PE_TX1_DR10_N | PE_TX1_DR10-DIFF1 | PAIR | 2 | 6.5 | 5 | 10 | 5 | 50 | 20 | 25 | 12 | 12 | 20 | 12 | 7.5 | 85 Ohms | TOP=L2:L3=L2/L4:L6=L5/L7:BOTTOM=L7 |
| PE_TX1_DR10_N | PE_TX1_DR10-DIFF1 | PAIR | 3 | 6.5 | 5 | 10 | 5 | 50 | 20 | 25 | 12 | 12 | 20 | 12 | 7.5 | 85 Ohms | TOP=L2:L3=L2/L4:L6=L5/L7:BOTTOM=L7 |
| PE_TX1_DR10_N | PE_TX1_DR10-DIFF1 | PAIR | 4 | 6.5 | 5 | 10 | 5 | 50 | 20 | 25 | 12 | 12 | 20 | 12 | 7.5 | 85 Ohms | TOP=L2:L3=L2/L4:L6=L5/L7:BOTTOM=L7 |
| PE_TX1_DR10_N | PE_TX1_DR10-DIFF1 | PAIR | 5 | 6.5 | 5 | 10 | 5 | 50 | 20 | 25 | 12 | 12 | 20 | 12 | 7.5 | 85 Ohms | TOP=L2:L3=L2/L4:L6=L5/L7:BOTTOM=L7 |
| PE_TX1_DR10_N | PE_TX1_DR10-DIFF1 | PAIR | 6 | 6.5 | 5 | 10 | 5 | 50 | 20 | 25 | 12 | 12 | 20 | 12 | 7.5 | 85 Ohms | TOP=L2:L3=L2/L4:L6=L5/L7:BOTTOM=L7 |
| PE_TX1_DR10_N | PE_TX1_DR10-DIFF1 | PAIR | 7 | 6.5 | 5 | 10 | 5 | 50 | 20 | 25 | 12 | 12 | 20 | 12 | 7.5 | 85 Ohms | TOP=L2:L3=L2/L4:L6=L5/L7:BOTTOM=L7 |
| PE_TX1_DR10_N | PE_TX1_DR10-DIFF1 | PAIR | 8 | 6.88 | 5 | 10 | 5 | 50 | 20 | 36 | 12 | 12 | 20 | 12 | 5.13 | 85 Ohms | TOP=L2:L3=L2/L4:L6=L5/L7:BOTTOM=L7 |
| PE_TX1_DR10_P | PE_TX1_DR10-DIFF1 | PAIR | 1 | 6.88 | 5 | 10 | 5 | 50 | 20 | 36 | 12 | 12 | 20 | 12 | 5.13 | 85 Ohms | TOP=L2:L3=L2/L4:L6=L5/L7:BOTTOM=L7 |
| PE_TX1_DR10_P | PE_TX1_DR10-DIFF1 | PAIR | 2 | 6.5 | 5 | 10 | 5 | 50 | 20 | 25 | 12 | 12 | 20 | 12 | 7.5 | 85 Ohms | TOP=L2:L3=L2/L4:L6=L5/L7:BOTTOM=L7 |
| PE_TX1_DR10_P | PE_TX1_DR10-DIFF1 | PAIR | 3 | 6.5 | 5 | 10 | 5 | 50 | 20 | 25 | 12 | 12 | 20 | 12 | 7.5 | 85 Ohms | TOP=L2:L3=L2/L4:L6=L5/L7:BOTTOM=L7 |
| PE_TX1_DR10_P | PE_TX1_DR10-DIFF1 | PAIR | 4 | 6.5 | 5 | 10 | 5 | 50 | 20 | 25 | 12 | 12 | 20 | 12 | 7.5 | 85 Ohms | TOP=L2:L3=L2/L4:L6=L5/L7:BOTTOM=L7 |
| PE_TX1_DR10_P | PE_TX1_DR10-DIFF1 | PAIR | 5 | 6.5 | 5 | 10 | 5 | 50 | 20 | 25 | 12 | 12 | 20 | 12 | 7.5 | 85 Ohms | TOP=L2:L3=L2/L4:L6=L5/L7:BOTTOM=L7 |
| PE_TX1_DR10_P | PE_TX1_DR10-DIFF1 | PAIR | 6 | 6.5 | 5 | 10 | 5 | 50 | 20 | 25 | 12 | 12 | 20 | 12 | 7.5 | 85 Ohms | TOP=L2:L3=L2/L4:L6=L5/L7:BOTTOM=L7 |
| PE_TX1_DR10_P | PE_TX1_DR10-DIFF1 | PAIR | 7 | 6.5 | 5 | 10 | 5 | 50 | 20 | 25 | 12 | 12 | 20 | 12 | 7.5 | 85 Ohms | TOP=L2:L3=L2/L4:L6=L5/L7:BOTTOM=L7 |
| PE_TX1_DR10_P | PE_TX1_DR10-DIFF1 | PAIR | 8 | 6.88 | 5 | 10 | 5 | 50 | 20 | 36 | 12 | 12 | 20 | 12 | 5.13 | 85 Ohms | TOP=L2:L3=L2/L4:L6=L5/L7:BOTTOM=L7 |
| PE_TX1_DR11_N | PE_TX1_DR11-DIFF1 | PAIR | 1 | 6.88 | 5 | 10 | 5 | 50 | 20 | 36 | 12 | 12 | 20 | 12 | 5.13 | 85 Ohms | TOP=L2:L3=L2/L4:L6=L5/L7:BOTTOM=L7 |
| PE_TX1_DR11_N | PE_TX1_DR11-DIFF1 | PAIR | 2 | 6.5 | 5 | 10 | 5 | 50 | 20 | 25 | 12 | 12 | 20 | 12 | 7.5 | 85 Ohms | TOP=L2:L3=L2/L4:L6=L5/L7:BOTTOM=L7 |
| PE_TX1_DR11_N | PE_TX1_DR11-DIFF1 | PAIR | 3 | 6.5 | 5 | 10 | 5 | 50 | 20 | 25 | 12 | 12 | 20 | 12 | 7.5 | 85 Ohms | TOP=L2:L3=L2/L4:L6=L5/L7:BOTTOM=L7 |
| PE_TX1_DR11_N | PE_TX1_DR11-DIFF1 | PAIR | 4 | 6.5 | 5 | 10 | 5 | 50 | 20 | 25 | 12 | 12 | 20 | 12 | 7.5 | 85 Ohms | TOP=L2:L3=L2/L4:L6=L5/L7:BOTTOM=L7 |
| PE_TX1_DR11_N | PE_TX1_DR11-DIFF1 | PAIR | 5 | 6.5 | 5 | 10 | 5 | 50 | 20 | 25 | 12 | 12 | 20 | 12 | 7.5 | 85 Ohms | TOP=L2:L3=L2/L4:L6=L5/L7:BOTTOM=L7 |
| PE_TX1_DR11_N | PE_TX1_DR11-DIFF1 | PAIR | 6 | 6.5 | 5 | 10 | 5 | 50 | 20 | 25 | 12 | 12 | 20 | 12 | 7.5 | 85 Ohms | TOP=L2:L3=L2/L4:L6=L5/L7:BOTTOM=L7 |
| PE_TX1_DR11_N | PE_TX1_DR11-DIFF1 | PAIR | 7 | 6.5 | 5 | 10 | 5 | 50 | 20 | 25 | 12 | 12 | 20 | 12 | 7.5 | 85 Ohms | TOP=L2:L3=L2/L4:L6=L5/L7:BOTTOM=L7 |
| PE_TX1_DR11_N | PE_TX1_DR11-DIFF1 | PAIR | 8 | 6.88 | 5 | 10 | 5 | 50 | 20 | 36 | 12 | 12 | 20 | 12 | 5.13 | 85 Ohms | TOP=L2:L3=L2/L4:L6=L5/L7:BOTTOM=L7 |
| PE_TX1_DR11_P | PE_TX1_DR11-DIFF1 | PAIR | 1 | 6.88 | 5 | 10 | 5 | 50 | 20 | 36 | 12 | 12 | 20 | 12 | 5.13 | 85 Ohms | TOP=L2:L3=L2/L4:L6=L5/L7:BOTTOM=L7 |
| PE_TX1_DR11_P | PE_TX1_DR11-DIFF1 | PAIR | 2 | 6.5 | 5 | 10 | 5 | 50 | 20 | 25 | 12 | 12 | 20 | 12 | 7.5 | 85 Ohms | TOP=L2:L3=L2/L4:L6=L5/L7:BOTTOM=L7 |
| PE_TX1_DR11_P | PE_TX1_DR11-DIFF1 | PAIR | 3 | 6.5 | 5 | 10 | 5 | 50 | 20 | 25 | 12 | 12 | 20 | 12 | 7.5 | 85 Ohms | TOP=L2:L3=L2/L4:L6=L5/L7:BOTTOM=L7 |
| PE_TX1_DR11_P | PE_TX1_DR11-DIFF1 | PAIR | 4 | 6.5 | 5 | 10 | 5 | 50 | 20 | 25 | 12 | 12 | 20 | 12 | 7.5 | 85 Ohms | TOP=L2:L3=L2/L4:L6=L5/L7:BOTTOM=L7 |
| PE_TX1_DR11_P | PE_TX1_DR11-DIFF1 | PAIR | 5 | 6.5 | 5 | 10 | 5 | 50 | 20 | 25 | 12 | 12 | 20 | 12 | 7.5 | 85 Ohms | TOP=L2:L3=L2/L4:L6=L5/L7:BOTTOM=L7 |
| PE_TX1_DR11_P | PE_TX1_DR11-DIFF1 | PAIR | 6 | 6.5 | 5 | 10 | 5 | 50 | 20 | 25 | 12 | 12 | 20 | 12 | 7.5 | 85 Ohms | TOP=L2:L3=L2/L4:L6=L5/L7:BOTTOM=L7 |
| PE_TX1_DR11_P | PE_TX1_DR11-DIFF1 | PAIR | 7 | 6.5 | 5 | 10 | 5 | 50 | 20 | 25 | 12 | 12 | 20 | 12 | 7.5 | 85 Ohms | TOP=L2:L3=L2/L4:L6=L5/L7:BOTTOM=L7 |
| PE_TX1_DR11_P | PE_TX1_DR11-DIFF1 | PAIR | 8 | 6.88 | 5 | 10 | 5 | 50 | 20 | 36 | 12 | 12 | 20 | 12 | 5.13 | 85 Ohms | TOP=L2:L3=L2/L4:L6=L5/L7:BOTTOM=L7 |
| PE_TX1_DR12_N | PE_TX1_DR12-DIFF1 | PAIR | 1 | 6.88 | 5 | 10 | 5 | 50 | 20 | 36 | 12 | 12 | 20 | 12 | 5.13 | 85 Ohms | TOP=L2:L3=L2/L4:L6=L5/L7:BOTTOM=L7 |
| PE_TX1_DR12_N | PE_TX1_DR12-DIFF1 | PAIR | 2 | 6.5 | 5 | 10 | 5 | 50 | 20 | 25 | 12 | 12 | 20 | 12 | 7.5 | 85 Ohms | TOP=L2:L3=L2/L4:L6=L5/L7:BOTTOM=L7 |
| PE_TX1_DR12_N | PE_TX1_DR12-DIFF1 | PAIR | 3 | 6.5 | 5 | 10 | 5 | 50 | 20 | 25 | 12 | 12 | 20 | 12 | 7.5 | 85 Ohms | TOP=L2:L3=L2/L4:L6=L5/L7:BOTTOM=L7 |
| PE_TX1_DR12_N | PE_TX1_DR12-DIFF1 | PAIR | 4 | 6.5 | 5 | 10 | 5 | 50 | 20 | 25 | 12 | 12 | 20 | 12 | 7.5 | 85 Ohms | TOP=L2:L3=L2/L4:L6=L5/L7:BOTTOM=L7 |
| PE_TX1_DR12_N | PE_TX1_DR12-DIFF1 | PAIR | 5 | 6.5 | 5 | 10 | 5 | 50 | 20 | 25 | 12 | 12 | 20 | 12 | 7.5 | 85 Ohms | TOP=L2:L3=L2/L4:L6=L5/L7:BOTTOM=L7 |
| PE_TX1_DR12_N | PE_TX1_DR12-DIFF1 | PAIR | 6 | 6.5 | 5 | 10 | 5 | 50 | 20 | 25 | 12 | 12 | 20 | 12 | 7.5 | 85 Ohms | TOP=L2:L3=L2/L4:L6=L5/L7:BOTTOM=L7 |
| PE_TX1_DR12_N | PE_TX1_DR12-DIFF1 | PAIR | 7 | 6.5 | 5 | 10 | 5 | 50 | 20 | 25 | 12 | 12 | 20 | 12 | 7.5 | 85 Ohms | TOP=L2:L3=L2/L4:L6=L5/L7:BOTTOM=L7 |
| PE_TX1_DR12_N | PE_TX1_DR12-DIFF1 | PAIR | 8 | 6.88 | 5 | 10 | 5 | 50 | 20 | 36 | 12 | 12 | 20 | 12 | 5.13 | 85 Ohms | TOP=L2:L3=L2/L4:L6=L5/L7:BOTTOM=L7 |
| PE_TX1_DR12_P | PE_TX1_DR12-DIFF1 | PAIR | 1 | 6.88 | 5 | 10 | 5 | 50 | 20 | 36 | 12 | 12 | 20 | 12 | 5.13 | 85 Ohms | TOP=L2:L3=L2/L4:L6=L5/L7:BOTTOM=L7 |
| PE_TX1_DR12_P | PE_TX1_DR12-DIFF1 | PAIR | 2 | 6.5 | 5 | 10 | 5 | 50 | 20 | 25 | 12 | 12 | 20 | 12 | 7.5 | 85 Ohms | TOP=L2:L3=L2/L4:L6=L5/L7:BOTTOM=L7 |
| PE_TX1_DR12_P | PE_TX1_DR12-DIFF1 | PAIR | 3 | 6.5 | 5 | 10 | 5 | 50 | 20 | 25 | 12 | 12 | 20 | 12 | 7.5 | 85 Ohms | TOP=L2:L3=L2/L4:L6=L5/L7:BOTTOM=L7 |
| PE_TX1_DR12_P | PE_TX1_DR12-DIFF1 | PAIR | 4 | 6.5 | 5 | 10 | 5 | 50 | 20 | 25 | 12 | 12 | 20 | 12 | 7.5 | 85 Ohms | TOP=L2:L3=L2/L4:L6=L5/L7:BOTTOM=L7 |
| PE_TX1_DR12_P | PE_TX1_DR12-DIFF1 | PAIR | 5 | 6.5 | 5 | 10 | 5 | 50 | 20 | 25 | 12 | 12 | 20 | 12 | 7.5 | 85 Ohms | TOP=L2:L3=L2/L4:L6=L5/L7:BOTTOM=L7 |
| PE_TX1_DR12_P | PE_TX1_DR12-DIFF1 | PAIR | 6 | 6.5 | 5 | 10 | 5 | 50 | 20 | 25 | 12 | 12 | 20 | 12 | 7.5 | 85 Ohms | TOP=L2:L3=L2/L4:L6=L5/L7:BOTTOM=L7 |
| PE_TX1_DR12_P | PE_TX1_DR12-DIFF1 | PAIR | 7 | 6.5 | 5 | 10 | 5 | 50 | 20 | 25 | 12 | 12 | 20 | 12 | 7.5 | 85 Ohms | TOP=L2:L3=L2/L4:L6=L5/L7:BOTTOM=L7 |
| PE_TX1_DR12_P | PE_TX1_DR12-DIFF1 | PAIR | 8 | 6.88 | 5 | 10 | 5 | 50 | 20 | 36 | 12 | 12 | 20 | 12 | 5.13 | 85 Ohms | TOP=L2:L3=L2/L4:L6=L5/L7:BOTTOM=L7 |
| PE_TX1_DR13_N | PE_TX1_DR13-DIFF1 | PAIR | 1 | 6.88 | 5 | 10 | 5 | 50 | 20 | 36 | 12 | 12 | 20 | 12 | 5.13 | 85 Ohms | TOP=L2:L3=L2/L4:L6=L5/L7:BOTTOM=L7 |
| PE_TX1_DR13_N | PE_TX1_DR13-DIFF1 | PAIR | 2 | 6.5 | 5 | 10 | 5 | 50 | 20 | 25 | 12 | 12 | 20 | 12 | 7.5 | 85 Ohms | TOP=L2:L3=L2/L4:L6=L5/L7:BOTTOM=L7 |
| PE_TX1_DR13_N | PE_TX1_DR13-DIFF1 | PAIR | 3 | 6.5 | 5 | 10 | 5 | 50 | 20 | 25 | 12 | 12 | 20 | 12 | 7.5 | 85 Ohms | TOP=L2:L3=L2/L4:L6=L5/L7:BOTTOM=L7 |
| PE_TX1_DR13_N | PE_TX1_DR13-DIFF1 | PAIR | 4 | 6.5 | 5 | 10 | 5 | 50 | 20 | 25 | 12 | 12 | 20 | 12 | 7.5 | 85 Ohms | TOP=L2:L3=L2/L4:L6=L5/L7:BOTTOM=L7 |
| PE_TX1_DR13_N | PE_TX1_DR13-DIFF1 | PAIR | 5 | 6.5 | 5 | 10 | 5 | 50 | 20 | 25 | 12 | 12 | 20 | 12 | 7.5 | 85 Ohms | TOP=L2:L3=L2/L4:L6=L5/L7:BOTTOM=L7 |
| PE_TX1_DR13_N | PE_TX1_DR13-DIFF1 | PAIR | 6 | 6.5 | 5 | 10 | 5 | 50 | 20 | 25 | 12 | 12 | 20 | 12 | 7.5 | 85 Ohms | TOP=L2:L3=L2/L4:L6=L5/L7:BOTTOM=L7 |
| PE_TX1_DR13_N | PE_TX1_DR13-DIFF1 | PAIR | 7 | 6.5 | 5 | 10 | 5 | 50 | 20 | 25 | 12 | 12 | 20 | 12 | 7.5 | 85 Ohms | TOP=L2:L3=L2/L4:L6=L5/L7:BOTTOM=L7 |
| PE_TX1_DR13_N | PE_TX1_DR13-DIFF1 | PAIR | 8 | 6.88 | 5 | 10 | 5 | 50 | 20 | 36 | 12 | 12 | 20 | 12 | 5.13 | 85 Ohms | TOP=L2:L3=L2/L4:L6=L5/L7:BOTTOM=L7 |
| PE_TX1_DR13_P | PE_TX1_DR13-DIFF1 | PAIR | 1 | 6.88 | 5 | 10 | 5 | 50 | 20 | 36 | 12 | 12 | 20 | 12 | 5.13 | 85 Ohms | TOP=L2:L3=L2/L4:L6=L5/L7:BOTTOM=L7 |
| PE_TX1_DR13_P | PE_TX1_DR13-DIFF1 | PAIR | 2 | 6.5 | 5 | 10 | 5 | 50 | 20 | 25 | 12 | 12 | 20 | 12 | 7.5 | 85 Ohms | TOP=L2:L3=L2/L4:L6=L5/L7:BOTTOM=L7 |
| PE_TX1_DR13_P | PE_TX1_DR13-DIFF1 | PAIR | 3 | 6.5 | 5 | 10 | 5 | 50 | 20 | 25 | 12 | 12 | 20 | 12 | 7.5 | 85 Ohms | TOP=L2:L3=L2/L4:L6=L5/L7:BOTTOM=L7 |
| PE_TX1_DR13_P | PE_TX1_DR13-DIFF1 | PAIR | 4 | 6.5 | 5 | 10 | 5 | 50 | 20 | 25 | 12 | 12 | 20 | 12 | 7.5 | 85 Ohms | TOP=L2:L3=L2/L4:L6=L5/L7:BOTTOM=L7 |
| PE_TX1_DR13_P | PE_TX1_DR13-DIFF1 | PAIR | 5 | 6.5 | 5 | 10 | 5 | 50 | 20 | 25 | 12 | 12 | 20 | 12 | 7.5 | 85 Ohms | TOP=L2:L3=L2/L4:L6=L5/L7:BOTTOM=L7 |
| PE_TX1_DR13_P | PE_TX1_DR13-DIFF1 | PAIR | 6 | 6.5 | 5 | 10 | 5 | 50 | 20 | 25 | 12 | 12 | 20 | 12 | 7.5 | 85 Ohms | TOP=L2:L3=L2/L4:L6=L5/L7:BOTTOM=L7 |
| PE_TX1_DR13_P | PE_TX1_DR13-DIFF1 | PAIR | 7 | 6.5 | 5 | 10 | 5 | 50 | 20 | 25 | 12 | 12 | 20 | 12 | 7.5 | 85 Ohms | TOP=L2:L3=L2/L4:L6=L5/L7:BOTTOM=L7 |
| PE_TX1_DR13_P | PE_TX1_DR13-DIFF1 | PAIR | 8 | 6.88 | 5 | 10 | 5 | 50 | 20 | 36 | 12 | 12 | 20 | 12 | 5.13 | 85 Ohms | TOP=L2:L3=L2/L4:L6=L5/L7:BOTTOM=L7 |
| PE_TX1_DR14_N | PE_TX1_DR14-DIFF1 | PAIR | 1 | 6.88 | 5 | 10 | 5 | 50 | 20 | 36 | 12 | 12 | 20 | 12 | 5.13 | 85 Ohms | TOP=L2:L3=L2/L4:L6=L5/L7:BOTTOM=L7 |
| PE_TX1_DR14_N | PE_TX1_DR14-DIFF1 | PAIR | 2 | 6.5 | 5 | 10 | 5 | 50 | 20 | 25 | 12 | 12 | 20 | 12 | 7.5 | 85 Ohms | TOP=L2:L3=L2/L4:L6=L5/L7:BOTTOM=L7 |
| PE_TX1_DR14_N | PE_TX1_DR14-DIFF1 | PAIR | 3 | 6.5 | 5 | 10 | 5 | 50 | 20 | 25 | 12 | 12 | 20 | 12 | 7.5 | 85 Ohms | TOP=L2:L3=L2/L4:L6=L5/L7:BOTTOM=L7 |
| PE_TX1_DR14_N | PE_TX1_DR14-DIFF1 | PAIR | 4 | 6.5 | 5 | 10 | 5 | 50 | 20 | 25 | 12 | 12 | 20 | 12 | 7.5 | 85 Ohms | TOP=L2:L3=L2/L4:L6=L5/L7:BOTTOM=L7 |
| PE_TX1_DR14_N | PE_TX1_DR14-DIFF1 | PAIR | 5 | 6.5 | 5 | 10 | 5 | 50 | 20 | 25 | 12 | 12 | 20 | 12 | 7.5 | 85 Ohms | TOP=L2:L3=L2/L4:L6=L5/L7:BOTTOM=L7 |
| PE_TX1_DR14_N | PE_TX1_DR14-DIFF1 | PAIR | 6 | 6.5 | 5 | 10 | 5 | 50 | 20 | 25 | 12 | 12 | 20 | 12 | 7.5 | 85 Ohms | TOP=L2:L3=L2/L4:L6=L5/L7:BOTTOM=L7 |
| PE_TX1_DR14_N | PE_TX1_DR14-DIFF1 | PAIR | 7 | 6.5 | 5 | 10 | 5 | 50 | 20 | 25 | 12 | 12 | 20 | 12 | 7.5 | 85 Ohms | TOP=L2:L3=L2/L4:L6=L5/L7:BOTTOM=L7 |
| PE_TX1_DR14_N | PE_TX1_DR14-DIFF1 | PAIR | 8 | 6.88 | 5 | 10 | 5 | 50 | 20 | 36 | 12 | 12 | 20 | 12 | 5.13 | 85 Ohms | TOP=L2:L3=L2/L4:L6=L5/L7:BOTTOM=L7 |
| PE_TX1_DR14_P | PE_TX1_DR14-DIFF1 | PAIR | 1 | 6.88 | 5 | 10 | 5 | 50 | 20 | 36 | 12 | 12 | 20 | 12 | 5.13 | 85 Ohms | TOP=L2:L3=L2/L4:L6=L5/L7:BOTTOM=L7 |
| PE_TX1_DR14_P | PE_TX1_DR14-DIFF1 | PAIR | 2 | 6.5 | 5 | 10 | 5 | 50 | 20 | 25 | 12 | 12 | 20 | 12 | 7.5 | 85 Ohms | TOP=L2:L3=L2/L4:L6=L5/L7:BOTTOM=L7 |
| PE_TX1_DR14_P | PE_TX1_DR14-DIFF1 | PAIR | 3 | 6.5 | 5 | 10 | 5 | 50 | 20 | 25 | 12 | 12 | 20 | 12 | 7.5 | 85 Ohms | TOP=L2:L3=L2/L4:L6=L5/L7:BOTTOM=L7 |
| PE_TX1_DR14_P | PE_TX1_DR14-DIFF1 | PAIR | 4 | 6.5 | 5 | 10 | 5 | 50 | 20 | 25 | 12 | 12 | 20 | 12 | 7.5 | 85 Ohms | TOP=L2:L3=L2/L4:L6=L5/L7:BOTTOM=L7 |
| PE_TX1_DR14_P | PE_TX1_DR14-DIFF1 | PAIR | 5 | 6.5 | 5 | 10 | 5 | 50 | 20 | 25 | 12 | 12 | 20 | 12 | 7.5 | 85 Ohms | TOP=L2:L3=L2/L4:L6=L5/L7:BOTTOM=L7 |
| PE_TX1_DR14_P | PE_TX1_DR14-DIFF1 | PAIR | 6 | 6.5 | 5 | 10 | 5 | 50 | 20 | 25 | 12 | 12 | 20 | 12 | 7.5 | 85 Ohms | TOP=L2:L3=L2/L4:L6=L5/L7:BOTTOM=L7 |
| PE_TX1_DR14_P | PE_TX1_DR14-DIFF1 | PAIR | 7 | 6.5 | 5 | 10 | 5 | 50 | 20 | 25 | 12 | 12 | 20 | 12 | 7.5 | 85 Ohms | TOP=L2:L3=L2/L4:L6=L5/L7:BOTTOM=L7 |
| PE_TX1_DR14_P | PE_TX1_DR14-DIFF1 | PAIR | 8 | 6.88 | 5 | 10 | 5 | 50 | 20 | 36 | 12 | 12 | 20 | 12 | 5.13 | 85 Ohms | TOP=L2:L3=L2/L4:L6=L5/L7:BOTTOM=L7 |
| PE_TX1_DR1_N | PE_TX1_DR1-DIFF1 | PAIR | 1 | 6.88 | 5 | 10 | 5 | 50 | 20 | 36 | 12 | 12 | 20 | 12 | 5.13 | 85 Ohms | TOP=L2:L3=L2/L4:L6=L5/L7:BOTTOM=L7 |
| PE_TX1_DR1_N | PE_TX1_DR1-DIFF1 | PAIR | 2 | 6.5 | 5 | 10 | 5 | 50 | 20 | 25 | 12 | 12 | 20 | 12 | 7.5 | 85 Ohms | TOP=L2:L3=L2/L4:L6=L5/L7:BOTTOM=L7 |
| PE_TX1_DR1_N | PE_TX1_DR1-DIFF1 | PAIR | 3 | 6.5 | 5 | 10 | 5 | 50 | 20 | 25 | 12 | 12 | 20 | 12 | 7.5 | 85 Ohms | TOP=L2:L3=L2/L4:L6=L5/L7:BOTTOM=L7 |
| PE_TX1_DR1_N | PE_TX1_DR1-DIFF1 | PAIR | 4 | 6.5 | 5 | 10 | 5 | 50 | 20 | 25 | 12 | 12 | 20 | 12 | 7.5 | 85 Ohms | TOP=L2:L3=L2/L4:L6=L5/L7:BOTTOM=L7 |
| PE_TX1_DR1_N | PE_TX1_DR1-DIFF1 | PAIR | 5 | 6.5 | 5 | 10 | 5 | 50 | 20 | 25 | 12 | 12 | 20 | 12 | 7.5 | 85 Ohms | TOP=L2:L3=L2/L4:L6=L5/L7:BOTTOM=L7 |
| PE_TX1_DR1_N | PE_TX1_DR1-DIFF1 | PAIR | 6 | 6.5 | 5 | 10 | 5 | 50 | 20 | 25 | 12 | 12 | 20 | 12 | 7.5 | 85 Ohms | TOP=L2:L3=L2/L4:L6=L5/L7:BOTTOM=L7 |
| PE_TX1_DR1_N | PE_TX1_DR1-DIFF1 | PAIR | 7 | 6.5 | 5 | 10 | 5 | 50 | 20 | 25 | 12 | 12 | 20 | 12 | 7.5 | 85 Ohms | TOP=L2:L3=L2/L4:L6=L5/L7:BOTTOM=L7 |
| PE_TX1_DR1_N | PE_TX1_DR1-DIFF1 | PAIR | 8 | 6.88 | 5 | 10 | 5 | 50 | 20 | 36 | 12 | 12 | 20 | 12 | 5.13 | 85 Ohms | TOP=L2:L3=L2/L4:L6=L5/L7:BOTTOM=L7 |
| PE_TX1_DR1_P | PE_TX1_DR1-DIFF1 | PAIR | 1 | 6.88 | 5 | 10 | 5 | 50 | 20 | 36 | 12 | 12 | 20 | 12 | 5.13 | 85 Ohms | TOP=L2:L3=L2/L4:L6=L5/L7:BOTTOM=L7 |
| PE_TX1_DR1_P | PE_TX1_DR1-DIFF1 | PAIR | 2 | 6.5 | 5 | 10 | 5 | 50 | 20 | 25 | 12 | 12 | 20 | 12 | 7.5 | 85 Ohms | TOP=L2:L3=L2/L4:L6=L5/L7:BOTTOM=L7 |
| PE_TX1_DR1_P | PE_TX1_DR1-DIFF1 | PAIR | 3 | 6.5 | 5 | 10 | 5 | 50 | 20 | 25 | 12 | 12 | 20 | 12 | 7.5 | 85 Ohms | TOP=L2:L3=L2/L4:L6=L5/L7:BOTTOM=L7 |
| PE_TX1_DR1_P | PE_TX1_DR1-DIFF1 | PAIR | 4 | 6.5 | 5 | 10 | 5 | 50 | 20 | 25 | 12 | 12 | 20 | 12 | 7.5 | 85 Ohms | TOP=L2:L3=L2/L4:L6=L5/L7:BOTTOM=L7 |
| PE_TX1_DR1_P | PE_TX1_DR1-DIFF1 | PAIR | 5 | 6.5 | 5 | 10 | 5 | 50 | 20 | 25 | 12 | 12 | 20 | 12 | 7.5 | 85 Ohms | TOP=L2:L3=L2/L4:L6=L5/L7:BOTTOM=L7 |
| PE_TX1_DR1_P | PE_TX1_DR1-DIFF1 | PAIR | 6 | 6.5 | 5 | 10 | 5 | 50 | 20 | 25 | 12 | 12 | 20 | 12 | 7.5 | 85 Ohms | TOP=L2:L3=L2/L4:L6=L5/L7:BOTTOM=L7 |
| PE_TX1_DR1_P | PE_TX1_DR1-DIFF1 | PAIR | 7 | 6.5 | 5 | 10 | 5 | 50 | 20 | 25 | 12 | 12 | 20 | 12 | 7.5 | 85 Ohms | TOP=L2:L3=L2/L4:L6=L5/L7:BOTTOM=L7 |
| PE_TX1_DR1_P | PE_TX1_DR1-DIFF1 | PAIR | 8 | 6.88 | 5 | 10 | 5 | 50 | 20 | 36 | 12 | 12 | 20 | 12 | 5.13 | 85 Ohms | TOP=L2:L3=L2/L4:L6=L5/L7:BOTTOM=L7 |
| PE_TX1_DR2_N | PE_TX1_DR2-DIFF1 | PAIR | 1 | 6.88 | 5 | 10 | 5 | 50 | 20 | 36 | 12 | 12 | 20 | 12 | 5.13 | 85 Ohms | TOP=L2:L3=L2/L4:L6=L5/L7:BOTTOM=L7 |
| PE_TX1_DR2_N | PE_TX1_DR2-DIFF1 | PAIR | 2 | 6.5 | 5 | 10 | 5 | 50 | 20 | 25 | 12 | 12 | 20 | 12 | 7.5 | 85 Ohms | TOP=L2:L3=L2/L4:L6=L5/L7:BOTTOM=L7 |
| PE_TX1_DR2_N | PE_TX1_DR2-DIFF1 | PAIR | 3 | 6.5 | 5 | 10 | 5 | 50 | 20 | 25 | 12 | 12 | 20 | 12 | 7.5 | 85 Ohms | TOP=L2:L3=L2/L4:L6=L5/L7:BOTTOM=L7 |
| PE_TX1_DR2_N | PE_TX1_DR2-DIFF1 | PAIR | 4 | 6.5 | 5 | 10 | 5 | 50 | 20 | 25 | 12 | 12 | 20 | 12 | 7.5 | 85 Ohms | TOP=L2:L3=L2/L4:L6=L5/L7:BOTTOM=L7 |
| PE_TX1_DR2_N | PE_TX1_DR2-DIFF1 | PAIR | 5 | 6.5 | 5 | 10 | 5 | 50 | 20 | 25 | 12 | 12 | 20 | 12 | 7.5 | 85 Ohms | TOP=L2:L3=L2/L4:L6=L5/L7:BOTTOM=L7 |
| PE_TX1_DR2_N | PE_TX1_DR2-DIFF1 | PAIR | 6 | 6.5 | 5 | 10 | 5 | 50 | 20 | 25 | 12 | 12 | 20 | 12 | 7.5 | 85 Ohms | TOP=L2:L3=L2/L4:L6=L5/L7:BOTTOM=L7 |
| PE_TX1_DR2_N | PE_TX1_DR2-DIFF1 | PAIR | 7 | 6.5 | 5 | 10 | 5 | 50 | 20 | 25 | 12 | 12 | 20 | 12 | 7.5 | 85 Ohms | TOP=L2:L3=L2/L4:L6=L5/L7:BOTTOM=L7 |
| PE_TX1_DR2_N | PE_TX1_DR2-DIFF1 | PAIR | 8 | 6.88 | 5 | 10 | 5 | 50 | 20 | 36 | 12 | 12 | 20 | 12 | 5.13 | 85 Ohms | TOP=L2:L3=L2/L4:L6=L5/L7:BOTTOM=L7 |
| PE_TX1_DR2_P | PE_TX1_DR2-DIFF1 | PAIR | 1 | 6.88 | 5 | 10 | 5 | 50 | 20 | 36 | 12 | 12 | 20 | 12 | 5.13 | 85 Ohms | TOP=L2:L3=L2/L4:L6=L5/L7:BOTTOM=L7 |
| PE_TX1_DR2_P | PE_TX1_DR2-DIFF1 | PAIR | 2 | 6.5 | 5 | 10 | 5 | 50 | 20 | 25 | 12 | 12 | 20 | 12 | 7.5 | 85 Ohms | TOP=L2:L3=L2/L4:L6=L5/L7:BOTTOM=L7 |
| PE_TX1_DR2_P | PE_TX1_DR2-DIFF1 | PAIR | 3 | 6.5 | 5 | 10 | 5 | 50 | 20 | 25 | 12 | 12 | 20 | 12 | 7.5 | 85 Ohms | TOP=L2:L3=L2/L4:L6=L5/L7:BOTTOM=L7 |
| PE_TX1_DR2_P | PE_TX1_DR2-DIFF1 | PAIR | 4 | 6.5 | 5 | 10 | 5 | 50 | 20 | 25 | 12 | 12 | 20 | 12 | 7.5 | 85 Ohms | TOP=L2:L3=L2/L4:L6=L5/L7:BOTTOM=L7 |
| PE_TX1_DR2_P | PE_TX1_DR2-DIFF1 | PAIR | 5 | 6.5 | 5 | 10 | 5 | 50 | 20 | 25 | 12 | 12 | 20 | 12 | 7.5 | 85 Ohms | TOP=L2:L3=L2/L4:L6=L5/L7:BOTTOM=L7 |
| PE_TX1_DR2_P | PE_TX1_DR2-DIFF1 | PAIR | 6 | 6.5 | 5 | 10 | 5 | 50 | 20 | 25 | 12 | 12 | 20 | 12 | 7.5 | 85 Ohms | TOP=L2:L3=L2/L4:L6=L5/L7:BOTTOM=L7 |
| PE_TX1_DR2_P | PE_TX1_DR2-DIFF1 | PAIR | 7 | 6.5 | 5 | 10 | 5 | 50 | 20 | 25 | 12 | 12 | 20 | 12 | 7.5 | 85 Ohms | TOP=L2:L3=L2/L4:L6=L5/L7:BOTTOM=L7 |
| PE_TX1_DR2_P | PE_TX1_DR2-DIFF1 | PAIR | 8 | 6.88 | 5 | 10 | 5 | 50 | 20 | 36 | 12 | 12 | 20 | 12 | 5.13 | 85 Ohms | TOP=L2:L3=L2/L4:L6=L5/L7:BOTTOM=L7 |
| PE_TX1_DR3_N | PE_TX1_DR3-DIFF1 | PAIR | 1 | 6.88 | 5 | 10 | 5 | 50 | 20 | 36 | 12 | 12 | 20 | 12 | 5.13 | 85 Ohms | TOP=L2:L3=L2/L4:L6=L5/L7:BOTTOM=L7 |
| PE_TX1_DR3_N | PE_TX1_DR3-DIFF1 | PAIR | 2 | 6.5 | 5 | 10 | 5 | 50 | 20 | 25 | 12 | 12 | 20 | 12 | 7.5 | 85 Ohms | TOP=L2:L3=L2/L4:L6=L5/L7:BOTTOM=L7 |
| PE_TX1_DR3_N | PE_TX1_DR3-DIFF1 | PAIR | 3 | 6.5 | 5 | 10 | 5 | 50 | 20 | 25 | 12 | 12 | 20 | 12 | 7.5 | 85 Ohms | TOP=L2:L3=L2/L4:L6=L5/L7:BOTTOM=L7 |
| PE_TX1_DR3_N | PE_TX1_DR3-DIFF1 | PAIR | 4 | 6.5 | 5 | 10 | 5 | 50 | 20 | 25 | 12 | 12 | 20 | 12 | 7.5 | 85 Ohms | TOP=L2:L3=L2/L4:L6=L5/L7:BOTTOM=L7 |
| PE_TX1_DR3_N | PE_TX1_DR3-DIFF1 | PAIR | 5 | 6.5 | 5 | 10 | 5 | 50 | 20 | 25 | 12 | 12 | 20 | 12 | 7.5 | 85 Ohms | TOP=L2:L3=L2/L4:L6=L5/L7:BOTTOM=L7 |
| PE_TX1_DR3_N | PE_TX1_DR3-DIFF1 | PAIR | 6 | 6.5 | 5 | 10 | 5 | 50 | 20 | 25 | 12 | 12 | 20 | 12 | 7.5 | 85 Ohms | TOP=L2:L3=L2/L4:L6=L5/L7:BOTTOM=L7 |
| PE_TX1_DR3_N | PE_TX1_DR3-DIFF1 | PAIR | 7 | 6.5 | 5 | 10 | 5 | 50 | 20 | 25 | 12 | 12 | 20 | 12 | 7.5 | 85 Ohms | TOP=L2:L3=L2/L4:L6=L5/L7:BOTTOM=L7 |
| PE_TX1_DR3_N | PE_TX1_DR3-DIFF1 | PAIR | 8 | 6.88 | 5 | 10 | 5 | 50 | 20 | 36 | 12 | 12 | 20 | 12 | 5.13 | 85 Ohms | TOP=L2:L3=L2/L4:L6=L5/L7:BOTTOM=L7 |
| PE_TX1_DR3_P | PE_TX1_DR3-DIFF1 | PAIR | 1 | 6.88 | 5 | 10 | 5 | 50 | 20 | 36 | 12 | 12 | 20 | 12 | 5.13 | 85 Ohms | TOP=L2:L3=L2/L4:L6=L5/L7:BOTTOM=L7 |
| PE_TX1_DR3_P | PE_TX1_DR3-DIFF1 | PAIR | 2 | 6.5 | 5 | 10 | 5 | 50 | 20 | 25 | 12 | 12 | 20 | 12 | 7.5 | 85 Ohms | TOP=L2:L3=L2/L4:L6=L5/L7:BOTTOM=L7 |
| PE_TX1_DR3_P | PE_TX1_DR3-DIFF1 | PAIR | 3 | 6.5 | 5 | 10 | 5 | 50 | 20 | 25 | 12 | 12 | 20 | 12 | 7.5 | 85 Ohms | TOP=L2:L3=L2/L4:L6=L5/L7:BOTTOM=L7 |
| PE_TX1_DR3_P | PE_TX1_DR3-DIFF1 | PAIR | 4 | 6.5 | 5 | 10 | 5 | 50 | 20 | 25 | 12 | 12 | 20 | 12 | 7.5 | 85 Ohms | TOP=L2:L3=L2/L4:L6=L5/L7:BOTTOM=L7 |
| PE_TX1_DR3_P | PE_TX1_DR3-DIFF1 | PAIR | 5 | 6.5 | 5 | 10 | 5 | 50 | 20 | 25 | 12 | 12 | 20 | 12 | 7.5 | 85 Ohms | TOP=L2:L3=L2/L4:L6=L5/L7:BOTTOM=L7 |
| PE_TX1_DR3_P | PE_TX1_DR3-DIFF1 | PAIR | 6 | 6.5 | 5 | 10 | 5 | 50 | 20 | 25 | 12 | 12 | 20 | 12 | 7.5 | 85 Ohms | TOP=L2:L3=L2/L4:L6=L5/L7:BOTTOM=L7 |
| PE_TX1_DR3_P | PE_TX1_DR3-DIFF1 | PAIR | 7 | 6.5 | 5 | 10 | 5 | 50 | 20 | 25 | 12 | 12 | 20 | 12 | 7.5 | 85 Ohms | TOP=L2:L3=L2/L4:L6=L5/L7:BOTTOM=L7 |
| PE_TX1_DR3_P | PE_TX1_DR3-DIFF1 | PAIR | 8 | 6.88 | 5 | 10 | 5 | 50 | 20 | 36 | 12 | 12 | 20 | 12 | 5.13 | 85 Ohms | TOP=L2:L3=L2/L4:L6=L5/L7:BOTTOM=L7 |
| PE_TX1_DR4_N | PE_TX1_DR4-DIFF1 | PAIR | 1 | 6.88 | 5 | 10 | 5 | 50 | 20 | 36 | 12 | 12 | 20 | 12 | 5.13 | 85 Ohms | TOP=L2:L3=L2/L4:L6=L5/L7:BOTTOM=L7 |
| PE_TX1_DR4_N | PE_TX1_DR4-DIFF1 | PAIR | 2 | 6.5 | 5 | 10 | 5 | 50 | 20 | 25 | 12 | 12 | 20 | 12 | 7.5 | 85 Ohms | TOP=L2:L3=L2/L4:L6=L5/L7:BOTTOM=L7 |
| PE_TX1_DR4_N | PE_TX1_DR4-DIFF1 | PAIR | 3 | 6.5 | 5 | 10 | 5 | 50 | 20 | 25 | 12 | 12 | 20 | 12 | 7.5 | 85 Ohms | TOP=L2:L3=L2/L4:L6=L5/L7:BOTTOM=L7 |
| PE_TX1_DR4_N | PE_TX1_DR4-DIFF1 | PAIR | 4 | 6.5 | 5 | 10 | 5 | 50 | 20 | 25 | 12 | 12 | 20 | 12 | 7.5 | 85 Ohms | TOP=L2:L3=L2/L4:L6=L5/L7:BOTTOM=L7 |
| PE_TX1_DR4_N | PE_TX1_DR4-DIFF1 | PAIR | 5 | 6.5 | 5 | 10 | 5 | 50 | 20 | 25 | 12 | 12 | 20 | 12 | 7.5 | 85 Ohms | TOP=L2:L3=L2/L4:L6=L5/L7:BOTTOM=L7 |
| PE_TX1_DR4_N | PE_TX1_DR4-DIFF1 | PAIR | 6 | 6.5 | 5 | 10 | 5 | 50 | 20 | 25 | 12 | 12 | 20 | 12 | 7.5 | 85 Ohms | TOP=L2:L3=L2/L4:L6=L5/L7:BOTTOM=L7 |
| PE_TX1_DR4_N | PE_TX1_DR4-DIFF1 | PAIR | 7 | 6.5 | 5 | 10 | 5 | 50 | 20 | 25 | 12 | 12 | 20 | 12 | 7.5 | 85 Ohms | TOP=L2:L3=L2/L4:L6=L5/L7:BOTTOM=L7 |
| PE_TX1_DR4_N | PE_TX1_DR4-DIFF1 | PAIR | 8 | 6.88 | 5 | 10 | 5 | 50 | 20 | 36 | 12 | 12 | 20 | 12 | 5.13 | 85 Ohms | TOP=L2:L3=L2/L4:L6=L5/L7:BOTTOM=L7 |
| PE_TX1_DR4_P | PE_TX1_DR4-DIFF1 | PAIR | 1 | 6.88 | 5 | 10 | 5 | 50 | 20 | 36 | 12 | 12 | 20 | 12 | 5.13 | 85 Ohms | TOP=L2:L3=L2/L4:L6=L5/L7:BOTTOM=L7 |
| PE_TX1_DR4_P | PE_TX1_DR4-DIFF1 | PAIR | 2 | 6.5 | 5 | 10 | 5 | 50 | 20 | 25 | 12 | 12 | 20 | 12 | 7.5 | 85 Ohms | TOP=L2:L3=L2/L4:L6=L5/L7:BOTTOM=L7 |
| PE_TX1_DR4_P | PE_TX1_DR4-DIFF1 | PAIR | 3 | 6.5 | 5 | 10 | 5 | 50 | 20 | 25 | 12 | 12 | 20 | 12 | 7.5 | 85 Ohms | TOP=L2:L3=L2/L4:L6=L5/L7:BOTTOM=L7 |
| PE_TX1_DR4_P | PE_TX1_DR4-DIFF1 | PAIR | 4 | 6.5 | 5 | 10 | 5 | 50 | 20 | 25 | 12 | 12 | 20 | 12 | 7.5 | 85 Ohms | TOP=L2:L3=L2/L4:L6=L5/L7:BOTTOM=L7 |
| PE_TX1_DR4_P | PE_TX1_DR4-DIFF1 | PAIR | 5 | 6.5 | 5 | 10 | 5 | 50 | 20 | 25 | 12 | 12 | 20 | 12 | 7.5 | 85 Ohms | TOP=L2:L3=L2/L4:L6=L5/L7:BOTTOM=L7 |
| PE_TX1_DR4_P | PE_TX1_DR4-DIFF1 | PAIR | 6 | 6.5 | 5 | 10 | 5 | 50 | 20 | 25 | 12 | 12 | 20 | 12 | 7.5 | 85 Ohms | TOP=L2:L3=L2/L4:L6=L5/L7:BOTTOM=L7 |
| PE_TX1_DR4_P | PE_TX1_DR4-DIFF1 | PAIR | 7 | 6.5 | 5 | 10 | 5 | 50 | 20 | 25 | 12 | 12 | 20 | 12 | 7.5 | 85 Ohms | TOP=L2:L3=L2/L4:L6=L5/L7:BOTTOM=L7 |
| PE_TX1_DR4_P | PE_TX1_DR4-DIFF1 | PAIR | 8 | 6.88 | 5 | 10 | 5 | 50 | 20 | 36 | 12 | 12 | 20 | 12 | 5.13 | 85 Ohms | TOP=L2:L3=L2/L4:L6=L5/L7:BOTTOM=L7 |
| PE_TX1_DR5_N | PE_TX1_DR5-DIFF1 | PAIR | 1 | 6.88 | 5 | 10 | 5 | 50 | 20 | 36 | 12 | 12 | 20 | 12 | 5.13 | 85 Ohms | TOP=L2:L3=L2/L4:L6=L5/L7:BOTTOM=L7 |
| PE_TX1_DR5_N | PE_TX1_DR5-DIFF1 | PAIR | 2 | 6.5 | 5 | 10 | 5 | 50 | 20 | 25 | 12 | 12 | 20 | 12 | 7.5 | 85 Ohms | TOP=L2:L3=L2/L4:L6=L5/L7:BOTTOM=L7 |
| PE_TX1_DR5_N | PE_TX1_DR5-DIFF1 | PAIR | 3 | 6.5 | 5 | 10 | 5 | 50 | 20 | 25 | 12 | 12 | 20 | 12 | 7.5 | 85 Ohms | TOP=L2:L3=L2/L4:L6=L5/L7:BOTTOM=L7 |
| PE_TX1_DR5_N | PE_TX1_DR5-DIFF1 | PAIR | 4 | 6.5 | 5 | 10 | 5 | 50 | 20 | 25 | 12 | 12 | 20 | 12 | 7.5 | 85 Ohms | TOP=L2:L3=L2/L4:L6=L5/L7:BOTTOM=L7 |
| PE_TX1_DR5_N | PE_TX1_DR5-DIFF1 | PAIR | 5 | 6.5 | 5 | 10 | 5 | 50 | 20 | 25 | 12 | 12 | 20 | 12 | 7.5 | 85 Ohms | TOP=L2:L3=L2/L4:L6=L5/L7:BOTTOM=L7 |
| PE_TX1_DR5_N | PE_TX1_DR5-DIFF1 | PAIR | 6 | 6.5 | 5 | 10 | 5 | 50 | 20 | 25 | 12 | 12 | 20 | 12 | 7.5 | 85 Ohms | TOP=L2:L3=L2/L4:L6=L5/L7:BOTTOM=L7 |
| PE_TX1_DR5_N | PE_TX1_DR5-DIFF1 | PAIR | 7 | 6.5 | 5 | 10 | 5 | 50 | 20 | 25 | 12 | 12 | 20 | 12 | 7.5 | 85 Ohms | TOP=L2:L3=L2/L4:L6=L5/L7:BOTTOM=L7 |
| PE_TX1_DR5_N | PE_TX1_DR5-DIFF1 | PAIR | 8 | 6.88 | 5 | 10 | 5 | 50 | 20 | 36 | 12 | 12 | 20 | 12 | 5.13 | 85 Ohms | TOP=L2:L3=L2/L4:L6=L5/L7:BOTTOM=L7 |
| PE_TX1_DR5_P | PE_TX1_DR5-DIFF1 | PAIR | 1 | 6.88 | 5 | 10 | 5 | 50 | 20 | 36 | 12 | 12 | 20 | 12 | 5.13 | 85 Ohms | TOP=L2:L3=L2/L4:L6=L5/L7:BOTTOM=L7 |
| PE_TX1_DR5_P | PE_TX1_DR5-DIFF1 | PAIR | 2 | 6.5 | 5 | 10 | 5 | 50 | 20 | 25 | 12 | 12 | 20 | 12 | 7.5 | 85 Ohms | TOP=L2:L3=L2/L4:L6=L5/L7:BOTTOM=L7 |
| PE_TX1_DR5_P | PE_TX1_DR5-DIFF1 | PAIR | 3 | 6.5 | 5 | 10 | 5 | 50 | 20 | 25 | 12 | 12 | 20 | 12 | 7.5 | 85 Ohms | TOP=L2:L3=L2/L4:L6=L5/L7:BOTTOM=L7 |
| PE_TX1_DR5_P | PE_TX1_DR5-DIFF1 | PAIR | 4 | 6.5 | 5 | 10 | 5 | 50 | 20 | 25 | 12 | 12 | 20 | 12 | 7.5 | 85 Ohms | TOP=L2:L3=L2/L4:L6=L5/L7:BOTTOM=L7 |
| PE_TX1_DR5_P | PE_TX1_DR5-DIFF1 | PAIR | 5 | 6.5 | 5 | 10 | 5 | 50 | 20 | 25 | 12 | 12 | 20 | 12 | 7.5 | 85 Ohms | TOP=L2:L3=L2/L4:L6=L5/L7:BOTTOM=L7 |
| PE_TX1_DR5_P | PE_TX1_DR5-DIFF1 | PAIR | 6 | 6.5 | 5 | 10 | 5 | 50 | 20 | 25 | 12 | 12 | 20 | 12 | 7.5 | 85 Ohms | TOP=L2:L3=L2/L4:L6=L5/L7:BOTTOM=L7 |
| PE_TX1_DR5_P | PE_TX1_DR5-DIFF1 | PAIR | 7 | 6.5 | 5 | 10 | 5 | 50 | 20 | 25 | 12 | 12 | 20 | 12 | 7.5 | 85 Ohms | TOP=L2:L3=L2/L4:L6=L5/L7:BOTTOM=L7 |
| PE_TX1_DR5_P | PE_TX1_DR5-DIFF1 | PAIR | 8 | 6.88 | 5 | 10 | 5 | 50 | 20 | 36 | 12 | 12 | 20 | 12 | 5.13 | 85 Ohms | TOP=L2:L3=L2/L4:L6=L5/L7:BOTTOM=L7 |
| PE_TX1_DR6_N | PE_TX1_DR6-DIFF1 | PAIR | 1 | 6.88 | 5 | 10 | 5 | 50 | 20 | 36 | 12 | 12 | 20 | 12 | 5.13 | 85 Ohms | TOP=L2:L3=L2/L4:L6=L5/L7:BOTTOM=L7 |
| PE_TX1_DR6_N | PE_TX1_DR6-DIFF1 | PAIR | 2 | 6.5 | 5 | 10 | 5 | 50 | 20 | 25 | 12 | 12 | 20 | 12 | 7.5 | 85 Ohms | TOP=L2:L3=L2/L4:L6=L5/L7:BOTTOM=L7 |
| PE_TX1_DR6_N | PE_TX1_DR6-DIFF1 | PAIR | 3 | 6.5 | 5 | 10 | 5 | 50 | 20 | 25 | 12 | 12 | 20 | 12 | 7.5 | 85 Ohms | TOP=L2:L3=L2/L4:L6=L5/L7:BOTTOM=L7 |
| PE_TX1_DR6_N | PE_TX1_DR6-DIFF1 | PAIR | 4 | 6.5 | 5 | 10 | 5 | 50 | 20 | 25 | 12 | 12 | 20 | 12 | 7.5 | 85 Ohms | TOP=L2:L3=L2/L4:L6=L5/L7:BOTTOM=L7 |
| PE_TX1_DR6_N | PE_TX1_DR6-DIFF1 | PAIR | 5 | 6.5 | 5 | 10 | 5 | 50 | 20 | 25 | 12 | 12 | 20 | 12 | 7.5 | 85 Ohms | TOP=L2:L3=L2/L4:L6=L5/L7:BOTTOM=L7 |
| PE_TX1_DR6_N | PE_TX1_DR6-DIFF1 | PAIR | 6 | 6.5 | 5 | 10 | 5 | 50 | 20 | 25 | 12 | 12 | 20 | 12 | 7.5 | 85 Ohms | TOP=L2:L3=L2/L4:L6=L5/L7:BOTTOM=L7 |
| PE_TX1_DR6_N | PE_TX1_DR6-DIFF1 | PAIR | 7 | 6.5 | 5 | 10 | 5 | 50 | 20 | 25 | 12 | 12 | 20 | 12 | 7.5 | 85 Ohms | TOP=L2:L3=L2/L4:L6=L5/L7:BOTTOM=L7 |
| PE_TX1_DR6_N | PE_TX1_DR6-DIFF1 | PAIR | 8 | 6.88 | 5 | 10 | 5 | 50 | 20 | 36 | 12 | 12 | 20 | 12 | 5.13 | 85 Ohms | TOP=L2:L3=L2/L4:L6=L5/L7:BOTTOM=L7 |
| PE_TX1_DR6_P | PE_TX1_DR6-DIFF1 | PAIR | 1 | 6.88 | 5 | 10 | 5 | 50 | 20 | 36 | 12 | 12 | 20 | 12 | 5.13 | 85 Ohms | TOP=L2:L3=L2/L4:L6=L5/L7:BOTTOM=L7 |
| PE_TX1_DR6_P | PE_TX1_DR6-DIFF1 | PAIR | 2 | 6.5 | 5 | 10 | 5 | 50 | 20 | 25 | 12 | 12 | 20 | 12 | 7.5 | 85 Ohms | TOP=L2:L3=L2/L4:L6=L5/L7:BOTTOM=L7 |
| PE_TX1_DR6_P | PE_TX1_DR6-DIFF1 | PAIR | 3 | 6.5 | 5 | 10 | 5 | 50 | 20 | 25 | 12 | 12 | 20 | 12 | 7.5 | 85 Ohms | TOP=L2:L3=L2/L4:L6=L5/L7:BOTTOM=L7 |
| PE_TX1_DR6_P | PE_TX1_DR6-DIFF1 | PAIR | 4 | 6.5 | 5 | 10 | 5 | 50 | 20 | 25 | 12 | 12 | 20 | 12 | 7.5 | 85 Ohms | TOP=L2:L3=L2/L4:L6=L5/L7:BOTTOM=L7 |
| PE_TX1_DR6_P | PE_TX1_DR6-DIFF1 | PAIR | 5 | 6.5 | 5 | 10 | 5 | 50 | 20 | 25 | 12 | 12 | 20 | 12 | 7.5 | 85 Ohms | TOP=L2:L3=L2/L4:L6=L5/L7:BOTTOM=L7 |
| PE_TX1_DR6_P | PE_TX1_DR6-DIFF1 | PAIR | 6 | 6.5 | 5 | 10 | 5 | 50 | 20 | 25 | 12 | 12 | 20 | 12 | 7.5 | 85 Ohms | TOP=L2:L3=L2/L4:L6=L5/L7:BOTTOM=L7 |
| PE_TX1_DR6_P | PE_TX1_DR6-DIFF1 | PAIR | 7 | 6.5 | 5 | 10 | 5 | 50 | 20 | 25 | 12 | 12 | 20 | 12 | 7.5 | 85 Ohms | TOP=L2:L3=L2/L4:L6=L5/L7:BOTTOM=L7 |
| PE_TX1_DR6_P | PE_TX1_DR6-DIFF1 | PAIR | 8 | 6.88 | 5 | 10 | 5 | 50 | 20 | 36 | 12 | 12 | 20 | 12 | 5.13 | 85 Ohms | TOP=L2:L3=L2/L4:L6=L5/L7:BOTTOM=L7 |
| PE_TX1_DR7_N | PE_TX1_DR7-DIFF1 | PAIR | 1 | 6.88 | 5 | 10 | 5 | 50 | 20 | 36 | 12 | 12 | 20 | 12 | 5.13 | 85 Ohms | TOP=L2:L3=L2/L4:L6=L5/L7:BOTTOM=L7 |
| PE_TX1_DR7_N | PE_TX1_DR7-DIFF1 | PAIR | 2 | 6.5 | 5 | 10 | 5 | 50 | 20 | 25 | 12 | 12 | 20 | 12 | 7.5 | 85 Ohms | TOP=L2:L3=L2/L4:L6=L5/L7:BOTTOM=L7 |
| PE_TX1_DR7_N | PE_TX1_DR7-DIFF1 | PAIR | 3 | 6.5 | 5 | 10 | 5 | 50 | 20 | 25 | 12 | 12 | 20 | 12 | 7.5 | 85 Ohms | TOP=L2:L3=L2/L4:L6=L5/L7:BOTTOM=L7 |
| PE_TX1_DR7_N | PE_TX1_DR7-DIFF1 | PAIR | 4 | 6.5 | 5 | 10 | 5 | 50 | 20 | 25 | 12 | 12 | 20 | 12 | 7.5 | 85 Ohms | TOP=L2:L3=L2/L4:L6=L5/L7:BOTTOM=L7 |
| PE_TX1_DR7_N | PE_TX1_DR7-DIFF1 | PAIR | 5 | 6.5 | 5 | 10 | 5 | 50 | 20 | 25 | 12 | 12 | 20 | 12 | 7.5 | 85 Ohms | TOP=L2:L3=L2/L4:L6=L5/L7:BOTTOM=L7 |
| PE_TX1_DR7_N | PE_TX1_DR7-DIFF1 | PAIR | 6 | 6.5 | 5 | 10 | 5 | 50 | 20 | 25 | 12 | 12 | 20 | 12 | 7.5 | 85 Ohms | TOP=L2:L3=L2/L4:L6=L5/L7:BOTTOM=L7 |
| PE_TX1_DR7_N | PE_TX1_DR7-DIFF1 | PAIR | 7 | 6.5 | 5 | 10 | 5 | 50 | 20 | 25 | 12 | 12 | 20 | 12 | 7.5 | 85 Ohms | TOP=L2:L3=L2/L4:L6=L5/L7:BOTTOM=L7 |
| PE_TX1_DR7_N | PE_TX1_DR7-DIFF1 | PAIR | 8 | 6.88 | 5 | 10 | 5 | 50 | 20 | 36 | 12 | 12 | 20 | 12 | 5.13 | 85 Ohms | TOP=L2:L3=L2/L4:L6=L5/L7:BOTTOM=L7 |
| PE_TX1_DR7_P | PE_TX1_DR7-DIFF1 | PAIR | 1 | 6.88 | 5 | 10 | 5 | 50 | 20 | 36 | 12 | 12 | 20 | 12 | 5.13 | 85 Ohms | TOP=L2:L3=L2/L4:L6=L5/L7:BOTTOM=L7 |
| PE_TX1_DR7_P | PE_TX1_DR7-DIFF1 | PAIR | 2 | 6.5 | 5 | 10 | 5 | 50 | 20 | 25 | 12 | 12 | 20 | 12 | 7.5 | 85 Ohms | TOP=L2:L3=L2/L4:L6=L5/L7:BOTTOM=L7 |
| PE_TX1_DR7_P | PE_TX1_DR7-DIFF1 | PAIR | 3 | 6.5 | 5 | 10 | 5 | 50 | 20 | 25 | 12 | 12 | 20 | 12 | 7.5 | 85 Ohms | TOP=L2:L3=L2/L4:L6=L5/L7:BOTTOM=L7 |
| PE_TX1_DR7_P | PE_TX1_DR7-DIFF1 | PAIR | 4 | 6.5 | 5 | 10 | 5 | 50 | 20 | 25 | 12 | 12 | 20 | 12 | 7.5 | 85 Ohms | TOP=L2:L3=L2/L4:L6=L5/L7:BOTTOM=L7 |
| PE_TX1_DR7_P | PE_TX1_DR7-DIFF1 | PAIR | 5 | 6.5 | 5 | 10 | 5 | 50 | 20 | 25 | 12 | 12 | 20 | 12 | 7.5 | 85 Ohms | TOP=L2:L3=L2/L4:L6=L5/L7:BOTTOM=L7 |
| PE_TX1_DR7_P | PE_TX1_DR7-DIFF1 | PAIR | 6 | 6.5 | 5 | 10 | 5 | 50 | 20 | 25 | 12 | 12 | 20 | 12 | 7.5 | 85 Ohms | TOP=L2:L3=L2/L4:L6=L5/L7:BOTTOM=L7 |
| PE_TX1_DR7_P | PE_TX1_DR7-DIFF1 | PAIR | 7 | 6.5 | 5 | 10 | 5 | 50 | 20 | 25 | 12 | 12 | 20 | 12 | 7.5 | 85 Ohms | TOP=L2:L3=L2/L4:L6=L5/L7:BOTTOM=L7 |
| PE_TX1_DR7_P | PE_TX1_DR7-DIFF1 | PAIR | 8 | 6.88 | 5 | 10 | 5 | 50 | 20 | 36 | 12 | 12 | 20 | 12 | 5.13 | 85 Ohms | TOP=L2:L3=L2/L4:L6=L5/L7:BOTTOM=L7 |
| PE_TX1_DR8_N | PE_TX1_DR8-DIFF1 | PAIR | 1 | 6.88 | 5 | 10 | 5 | 50 | 20 | 36 | 12 | 12 | 20 | 12 | 5.13 | 85 Ohms | TOP=L2:L3=L2/L4:L6=L5/L7:BOTTOM=L7 |
| PE_TX1_DR8_N | PE_TX1_DR8-DIFF1 | PAIR | 2 | 6.5 | 5 | 10 | 5 | 50 | 20 | 25 | 12 | 12 | 20 | 12 | 7.5 | 85 Ohms | TOP=L2:L3=L2/L4:L6=L5/L7:BOTTOM=L7 |
| PE_TX1_DR8_N | PE_TX1_DR8-DIFF1 | PAIR | 3 | 6.5 | 5 | 10 | 5 | 50 | 20 | 25 | 12 | 12 | 20 | 12 | 7.5 | 85 Ohms | TOP=L2:L3=L2/L4:L6=L5/L7:BOTTOM=L7 |
| PE_TX1_DR8_N | PE_TX1_DR8-DIFF1 | PAIR | 4 | 6.5 | 5 | 10 | 5 | 50 | 20 | 25 | 12 | 12 | 20 | 12 | 7.5 | 85 Ohms | TOP=L2:L3=L2/L4:L6=L5/L7:BOTTOM=L7 |
| PE_TX1_DR8_N | PE_TX1_DR8-DIFF1 | PAIR | 5 | 6.5 | 5 | 10 | 5 | 50 | 20 | 25 | 12 | 12 | 20 | 12 | 7.5 | 85 Ohms | TOP=L2:L3=L2/L4:L6=L5/L7:BOTTOM=L7 |
| PE_TX1_DR8_N | PE_TX1_DR8-DIFF1 | PAIR | 6 | 6.5 | 5 | 10 | 5 | 50 | 20 | 25 | 12 | 12 | 20 | 12 | 7.5 | 85 Ohms | TOP=L2:L3=L2/L4:L6=L5/L7:BOTTOM=L7 |
| PE_TX1_DR8_N | PE_TX1_DR8-DIFF1 | PAIR | 7 | 6.5 | 5 | 10 | 5 | 50 | 20 | 25 | 12 | 12 | 20 | 12 | 7.5 | 85 Ohms | TOP=L2:L3=L2/L4:L6=L5/L7:BOTTOM=L7 |
| PE_TX1_DR8_N | PE_TX1_DR8-DIFF1 | PAIR | 8 | 6.88 | 5 | 10 | 5 | 50 | 20 | 36 | 12 | 12 | 20 | 12 | 5.13 | 85 Ohms | TOP=L2:L3=L2/L4:L6=L5/L7:BOTTOM=L7 |
| PE_TX1_DR8_P | PE_TX1_DR8-DIFF1 | PAIR | 1 | 6.88 | 5 | 10 | 5 | 50 | 20 | 36 | 12 | 12 | 20 | 12 | 5.13 | 85 Ohms | TOP=L2:L3=L2/L4:L6=L5/L7:BOTTOM=L7 |
| PE_TX1_DR8_P | PE_TX1_DR8-DIFF1 | PAIR | 2 | 6.5 | 5 | 10 | 5 | 50 | 20 | 25 | 12 | 12 | 20 | 12 | 7.5 | 85 Ohms | TOP=L2:L3=L2/L4:L6=L5/L7:BOTTOM=L7 |
| PE_TX1_DR8_P | PE_TX1_DR8-DIFF1 | PAIR | 3 | 6.5 | 5 | 10 | 5 | 50 | 20 | 25 | 12 | 12 | 20 | 12 | 7.5 | 85 Ohms | TOP=L2:L3=L2/L4:L6=L5/L7:BOTTOM=L7 |
| PE_TX1_DR8_P | PE_TX1_DR8-DIFF1 | PAIR | 4 | 6.5 | 5 | 10 | 5 | 50 | 20 | 25 | 12 | 12 | 20 | 12 | 7.5 | 85 Ohms | TOP=L2:L3=L2/L4:L6=L5/L7:BOTTOM=L7 |
| PE_TX1_DR8_P | PE_TX1_DR8-DIFF1 | PAIR | 5 | 6.5 | 5 | 10 | 5 | 50 | 20 | 25 | 12 | 12 | 20 | 12 | 7.5 | 85 Ohms | TOP=L2:L3=L2/L4:L6=L5/L7:BOTTOM=L7 |
| PE_TX1_DR8_P | PE_TX1_DR8-DIFF1 | PAIR | 6 | 6.5 | 5 | 10 | 5 | 50 | 20 | 25 | 12 | 12 | 20 | 12 | 7.5 | 85 Ohms | TOP=L2:L3=L2/L4:L6=L5/L7:BOTTOM=L7 |
| PE_TX1_DR8_P | PE_TX1_DR8-DIFF1 | PAIR | 7 | 6.5 | 5 | 10 | 5 | 50 | 20 | 25 | 12 | 12 | 20 | 12 | 7.5 | 85 Ohms | TOP=L2:L3=L2/L4:L6=L5/L7:BOTTOM=L7 |
| PE_TX1_DR8_P | PE_TX1_DR8-DIFF1 | PAIR | 8 | 6.88 | 5 | 10 | 5 | 50 | 20 | 36 | 12 | 12 | 20 | 12 | 5.13 | 85 Ohms | TOP=L2:L3=L2/L4:L6=L5/L7:BOTTOM=L7 |
| PE_TX1_DR9_N | PE_TX1_DR9-DIFF1 | PAIR | 1 | 6.88 | 5 | 10 | 5 | 50 | 20 | 36 | 12 | 12 | 20 | 12 | 5.13 | 85 Ohms | TOP=L2:L3=L2/L4:L6=L5/L7:BOTTOM=L7 |
| PE_TX1_DR9_N | PE_TX1_DR9-DIFF1 | PAIR | 2 | 6.5 | 5 | 10 | 5 | 50 | 20 | 25 | 12 | 12 | 20 | 12 | 7.5 | 85 Ohms | TOP=L2:L3=L2/L4:L6=L5/L7:BOTTOM=L7 |
| PE_TX1_DR9_N | PE_TX1_DR9-DIFF1 | PAIR | 3 | 6.5 | 5 | 10 | 5 | 50 | 20 | 25 | 12 | 12 | 20 | 12 | 7.5 | 85 Ohms | TOP=L2:L3=L2/L4:L6=L5/L7:BOTTOM=L7 |
| PE_TX1_DR9_N | PE_TX1_DR9-DIFF1 | PAIR | 4 | 6.5 | 5 | 10 | 5 | 50 | 20 | 25 | 12 | 12 | 20 | 12 | 7.5 | 85 Ohms | TOP=L2:L3=L2/L4:L6=L5/L7:BOTTOM=L7 |
| PE_TX1_DR9_N | PE_TX1_DR9-DIFF1 | PAIR | 5 | 6.5 | 5 | 10 | 5 | 50 | 20 | 25 | 12 | 12 | 20 | 12 | 7.5 | 85 Ohms | TOP=L2:L3=L2/L4:L6=L5/L7:BOTTOM=L7 |
| PE_TX1_DR9_N | PE_TX1_DR9-DIFF1 | PAIR | 6 | 6.5 | 5 | 10 | 5 | 50 | 20 | 25 | 12 | 12 | 20 | 12 | 7.5 | 85 Ohms | TOP=L2:L3=L2/L4:L6=L5/L7:BOTTOM=L7 |
| PE_TX1_DR9_N | PE_TX1_DR9-DIFF1 | PAIR | 7 | 6.5 | 5 | 10 | 5 | 50 | 20 | 25 | 12 | 12 | 20 | 12 | 7.5 | 85 Ohms | TOP=L2:L3=L2/L4:L6=L5/L7:BOTTOM=L7 |
| PE_TX1_DR9_N | PE_TX1_DR9-DIFF1 | PAIR | 8 | 6.88 | 5 | 10 | 5 | 50 | 20 | 36 | 12 | 12 | 20 | 12 | 5.13 | 85 Ohms | TOP=L2:L3=L2/L4:L6=L5/L7:BOTTOM=L7 |
| PE_TX1_DR9_P | PE_TX1_DR9-DIFF1 | PAIR | 1 | 6.88 | 5 | 10 | 5 | 50 | 20 | 36 | 12 | 12 | 20 | 12 | 5.13 | 85 Ohms | TOP=L2:L3=L2/L4:L6=L5/L7:BOTTOM=L7 |
| PE_TX1_DR9_P | PE_TX1_DR9-DIFF1 | PAIR | 2 | 6.5 | 5 | 10 | 5 | 50 | 20 | 25 | 12 | 12 | 20 | 12 | 7.5 | 85 Ohms | TOP=L2:L3=L2/L4:L6=L5/L7:BOTTOM=L7 |
| PE_TX1_DR9_P | PE_TX1_DR9-DIFF1 | PAIR | 3 | 6.5 | 5 | 10 | 5 | 50 | 20 | 25 | 12 | 12 | 20 | 12 | 7.5 | 85 Ohms | TOP=L2:L3=L2/L4:L6=L5/L7:BOTTOM=L7 |
| PE_TX1_DR9_P | PE_TX1_DR9-DIFF1 | PAIR | 4 | 6.5 | 5 | 10 | 5 | 50 | 20 | 25 | 12 | 12 | 20 | 12 | 7.5 | 85 Ohms | TOP=L2:L3=L2/L4:L6=L5/L7:BOTTOM=L7 |
| PE_TX1_DR9_P | PE_TX1_DR9-DIFF1 | PAIR | 5 | 6.5 | 5 | 10 | 5 | 50 | 20 | 25 | 12 | 12 | 20 | 12 | 7.5 | 85 Ohms | TOP=L2:L3=L2/L4:L6=L5/L7:BOTTOM=L7 |
| PE_TX1_DR9_P | PE_TX1_DR9-DIFF1 | PAIR | 6 | 6.5 | 5 | 10 | 5 | 50 | 20 | 25 | 12 | 12 | 20 | 12 | 7.5 | 85 Ohms | TOP=L2:L3=L2/L4:L6=L5/L7:BOTTOM=L7 |
| PE_TX1_DR9_P | PE_TX1_DR9-DIFF1 | PAIR | 7 | 6.5 | 5 | 10 | 5 | 50 | 20 | 25 | 12 | 12 | 20 | 12 | 7.5 | 85 Ohms | TOP=L2:L3=L2/L4:L6=L5/L7:BOTTOM=L7 |
| PE_TX1_DR9_P | PE_TX1_DR9-DIFF1 | PAIR | 8 | 6.88 | 5 | 10 | 5 | 50 | 20 | 36 | 12 | 12 | 20 | 12 | 5.13 | 85 Ohms | TOP=L2:L3=L2/L4:L6=L5/L7:BOTTOM=L7 |
| PE_TX2_DR0_N | PE_TX2_DR0-DIFF1 | PAIR | 1 | 6.88 | 5 | 10 | 5 | 50 | 20 | 36 | 12 | 12 | 20 | 12 | 5.13 | 85 Ohms | TOP=L2:L3=L2/L4:L6=L5/L7:BOTTOM=L7 |
| PE_TX2_DR0_N | PE_TX2_DR0-DIFF1 | PAIR | 2 | 6.5 | 5 | 10 | 5 | 50 | 20 | 25 | 12 | 12 | 20 | 12 | 7.5 | 85 Ohms | TOP=L2:L3=L2/L4:L6=L5/L7:BOTTOM=L7 |
| PE_TX2_DR0_N | PE_TX2_DR0-DIFF1 | PAIR | 3 | 6.5 | 5 | 10 | 5 | 50 | 20 | 25 | 12 | 12 | 20 | 12 | 7.5 | 85 Ohms | TOP=L2:L3=L2/L4:L6=L5/L7:BOTTOM=L7 |
| PE_TX2_DR0_N | PE_TX2_DR0-DIFF1 | PAIR | 4 | 6.5 | 5 | 10 | 5 | 50 | 20 | 25 | 12 | 12 | 20 | 12 | 7.5 | 85 Ohms | TOP=L2:L3=L2/L4:L6=L5/L7:BOTTOM=L7 |
| PE_TX2_DR0_N | PE_TX2_DR0-DIFF1 | PAIR | 5 | 6.5 | 5 | 10 | 5 | 50 | 20 | 25 | 12 | 12 | 20 | 12 | 7.5 | 85 Ohms | TOP=L2:L3=L2/L4:L6=L5/L7:BOTTOM=L7 |
| PE_TX2_DR0_N | PE_TX2_DR0-DIFF1 | PAIR | 6 | 6.5 | 5 | 10 | 5 | 50 | 20 | 25 | 12 | 12 | 20 | 12 | 7.5 | 85 Ohms | TOP=L2:L3=L2/L4:L6=L5/L7:BOTTOM=L7 |
| PE_TX2_DR0_N | PE_TX2_DR0-DIFF1 | PAIR | 7 | 6.5 | 5 | 10 | 5 | 50 | 20 | 25 | 12 | 12 | 20 | 12 | 7.5 | 85 Ohms | TOP=L2:L3=L2/L4:L6=L5/L7:BOTTOM=L7 |
| PE_TX2_DR0_N | PE_TX2_DR0-DIFF1 | PAIR | 8 | 6.88 | 5 | 10 | 5 | 50 | 20 | 36 | 12 | 12 | 20 | 12 | 5.13 | 85 Ohms | TOP=L2:L3=L2/L4:L6=L5/L7:BOTTOM=L7 |
| PE_TX2_DR0_P | PE_TX2_DR0-DIFF1 | PAIR | 1 | 6.88 | 5 | 10 | 5 | 50 | 20 | 36 | 12 | 12 | 20 | 12 | 5.13 | 85 Ohms | TOP=L2:L3=L2/L4:L6=L5/L7:BOTTOM=L7 |
| PE_TX2_DR0_P | PE_TX2_DR0-DIFF1 | PAIR | 2 | 6.5 | 5 | 10 | 5 | 50 | 20 | 25 | 12 | 12 | 20 | 12 | 7.5 | 85 Ohms | TOP=L2:L3=L2/L4:L6=L5/L7:BOTTOM=L7 |
| PE_TX2_DR0_P | PE_TX2_DR0-DIFF1 | PAIR | 3 | 6.5 | 5 | 10 | 5 | 50 | 20 | 25 | 12 | 12 | 20 | 12 | 7.5 | 85 Ohms | TOP=L2:L3=L2/L4:L6=L5/L7:BOTTOM=L7 |
| PE_TX2_DR0_P | PE_TX2_DR0-DIFF1 | PAIR | 4 | 6.5 | 5 | 10 | 5 | 50 | 20 | 25 | 12 | 12 | 20 | 12 | 7.5 | 85 Ohms | TOP=L2:L3=L2/L4:L6=L5/L7:BOTTOM=L7 |
| PE_TX2_DR0_P | PE_TX2_DR0-DIFF1 | PAIR | 5 | 6.5 | 5 | 10 | 5 | 50 | 20 | 25 | 12 | 12 | 20 | 12 | 7.5 | 85 Ohms | TOP=L2:L3=L2/L4:L6=L5/L7:BOTTOM=L7 |
| PE_TX2_DR0_P | PE_TX2_DR0-DIFF1 | PAIR | 6 | 6.5 | 5 | 10 | 5 | 50 | 20 | 25 | 12 | 12 | 20 | 12 | 7.5 | 85 Ohms | TOP=L2:L3=L2/L4:L6=L5/L7:BOTTOM=L7 |
| PE_TX2_DR0_P | PE_TX2_DR0-DIFF1 | PAIR | 7 | 6.5 | 5 | 10 | 5 | 50 | 20 | 25 | 12 | 12 | 20 | 12 | 7.5 | 85 Ohms | TOP=L2:L3=L2/L4:L6=L5/L7:BOTTOM=L7 |
| PE_TX2_DR0_P | PE_TX2_DR0-DIFF1 | PAIR | 8 | 6.88 | 5 | 10 | 5 | 50 | 20 | 36 | 12 | 12 | 20 | 12 | 5.13 | 85 Ohms | TOP=L2:L3=L2/L4:L6=L5/L7:BOTTOM=L7 |
| PE_TX2_DR10_N | PE_TX2_DR10-DIFF1 | PAIR | 1 | 6.88 | 5 | 10 | 5 | 50 | 20 | 36 | 12 | 12 | 20 | 12 | 5.13 | 85 Ohms | TOP=L2:L3=L2/L4:L6=L5/L7:BOTTOM=L7 |
| PE_TX2_DR10_N | PE_TX2_DR10-DIFF1 | PAIR | 2 | 6.5 | 5 | 10 | 5 | 50 | 20 | 25 | 12 | 12 | 20 | 12 | 7.5 | 85 Ohms | TOP=L2:L3=L2/L4:L6=L5/L7:BOTTOM=L7 |
| PE_TX2_DR10_N | PE_TX2_DR10-DIFF1 | PAIR | 3 | 6.5 | 5 | 10 | 5 | 50 | 20 | 25 | 12 | 12 | 20 | 12 | 7.5 | 85 Ohms | TOP=L2:L3=L2/L4:L6=L5/L7:BOTTOM=L7 |
| PE_TX2_DR10_N | PE_TX2_DR10-DIFF1 | PAIR | 4 | 6.5 | 5 | 10 | 5 | 50 | 20 | 25 | 12 | 12 | 20 | 12 | 7.5 | 85 Ohms | TOP=L2:L3=L2/L4:L6=L5/L7:BOTTOM=L7 |
| PE_TX2_DR10_N | PE_TX2_DR10-DIFF1 | PAIR | 5 | 6.5 | 5 | 10 | 5 | 50 | 20 | 25 | 12 | 12 | 20 | 12 | 7.5 | 85 Ohms | TOP=L2:L3=L2/L4:L6=L5/L7:BOTTOM=L7 |
| PE_TX2_DR10_N | PE_TX2_DR10-DIFF1 | PAIR | 6 | 6.5 | 5 | 10 | 5 | 50 | 20 | 25 | 12 | 12 | 20 | 12 | 7.5 | 85 Ohms | TOP=L2:L3=L2/L4:L6=L5/L7:BOTTOM=L7 |
| PE_TX2_DR10_N | PE_TX2_DR10-DIFF1 | PAIR | 7 | 6.5 | 5 | 10 | 5 | 50 | 20 | 25 | 12 | 12 | 20 | 12 | 7.5 | 85 Ohms | TOP=L2:L3=L2/L4:L6=L5/L7:BOTTOM=L7 |
| PE_TX2_DR10_N | PE_TX2_DR10-DIFF1 | PAIR | 8 | 6.88 | 5 | 10 | 5 | 50 | 20 | 36 | 12 | 12 | 20 | 12 | 5.13 | 85 Ohms | TOP=L2:L3=L2/L4:L6=L5/L7:BOTTOM=L7 |
| PE_TX2_DR10_P | PE_TX2_DR10-DIFF1 | PAIR | 1 | 6.88 | 5 | 10 | 5 | 50 | 20 | 36 | 12 | 12 | 20 | 12 | 5.13 | 85 Ohms | TOP=L2:L3=L2/L4:L6=L5/L7:BOTTOM=L7 |
| PE_TX2_DR10_P | PE_TX2_DR10-DIFF1 | PAIR | 2 | 6.5 | 5 | 10 | 5 | 50 | 20 | 25 | 12 | 12 | 20 | 12 | 7.5 | 85 Ohms | TOP=L2:L3=L2/L4:L6=L5/L7:BOTTOM=L7 |
| PE_TX2_DR10_P | PE_TX2_DR10-DIFF1 | PAIR | 3 | 6.5 | 5 | 10 | 5 | 50 | 20 | 25 | 12 | 12 | 20 | 12 | 7.5 | 85 Ohms | TOP=L2:L3=L2/L4:L6=L5/L7:BOTTOM=L7 |
| PE_TX2_DR10_P | PE_TX2_DR10-DIFF1 | PAIR | 4 | 6.5 | 5 | 10 | 5 | 50 | 20 | 25 | 12 | 12 | 20 | 12 | 7.5 | 85 Ohms | TOP=L2:L3=L2/L4:L6=L5/L7:BOTTOM=L7 |
| PE_TX2_DR10_P | PE_TX2_DR10-DIFF1 | PAIR | 5 | 6.5 | 5 | 10 | 5 | 50 | 20 | 25 | 12 | 12 | 20 | 12 | 7.5 | 85 Ohms | TOP=L2:L3=L2/L4:L6=L5/L7:BOTTOM=L7 |
| PE_TX2_DR10_P | PE_TX2_DR10-DIFF1 | PAIR | 6 | 6.5 | 5 | 10 | 5 | 50 | 20 | 25 | 12 | 12 | 20 | 12 | 7.5 | 85 Ohms | TOP=L2:L3=L2/L4:L6=L5/L7:BOTTOM=L7 |
| PE_TX2_DR10_P | PE_TX2_DR10-DIFF1 | PAIR | 7 | 6.5 | 5 | 10 | 5 | 50 | 20 | 25 | 12 | 12 | 20 | 12 | 7.5 | 85 Ohms | TOP=L2:L3=L2/L4:L6=L5/L7:BOTTOM=L7 |
| PE_TX2_DR10_P | PE_TX2_DR10-DIFF1 | PAIR | 8 | 6.88 | 5 | 10 | 5 | 50 | 20 | 36 | 12 | 12 | 20 | 12 | 5.13 | 85 Ohms | TOP=L2:L3=L2/L4:L6=L5/L7:BOTTOM=L7 |
| PE_TX2_DR11_N | PE_TX2_DR11-DIFF1 | PAIR | 1 | 6.88 | 5 | 10 | 5 | 50 | 20 | 36 | 12 | 12 | 20 | 12 | 5.13 | 85 Ohms | TOP=L2:L3=L2/L4:L6=L5/L7:BOTTOM=L7 |
| PE_TX2_DR11_N | PE_TX2_DR11-DIFF1 | PAIR | 2 | 6.5 | 5 | 10 | 5 | 50 | 20 | 25 | 12 | 12 | 20 | 12 | 7.5 | 85 Ohms | TOP=L2:L3=L2/L4:L6=L5/L7:BOTTOM=L7 |
| PE_TX2_DR11_N | PE_TX2_DR11-DIFF1 | PAIR | 3 | 6.5 | 5 | 10 | 5 | 50 | 20 | 25 | 12 | 12 | 20 | 12 | 7.5 | 85 Ohms | TOP=L2:L3=L2/L4:L6=L5/L7:BOTTOM=L7 |
| PE_TX2_DR11_N | PE_TX2_DR11-DIFF1 | PAIR | 4 | 6.5 | 5 | 10 | 5 | 50 | 20 | 25 | 12 | 12 | 20 | 12 | 7.5 | 85 Ohms | TOP=L2:L3=L2/L4:L6=L5/L7:BOTTOM=L7 |
| PE_TX2_DR11_N | PE_TX2_DR11-DIFF1 | PAIR | 5 | 6.5 | 5 | 10 | 5 | 50 | 20 | 25 | 12 | 12 | 20 | 12 | 7.5 | 85 Ohms | TOP=L2:L3=L2/L4:L6=L5/L7:BOTTOM=L7 |
| PE_TX2_DR11_N | PE_TX2_DR11-DIFF1 | PAIR | 6 | 6.5 | 5 | 10 | 5 | 50 | 20 | 25 | 12 | 12 | 20 | 12 | 7.5 | 85 Ohms | TOP=L2:L3=L2/L4:L6=L5/L7:BOTTOM=L7 |
| PE_TX2_DR11_N | PE_TX2_DR11-DIFF1 | PAIR | 7 | 6.5 | 5 | 10 | 5 | 50 | 20 | 25 | 12 | 12 | 20 | 12 | 7.5 | 85 Ohms | TOP=L2:L3=L2/L4:L6=L5/L7:BOTTOM=L7 |
| PE_TX2_DR11_N | PE_TX2_DR11-DIFF1 | PAIR | 8 | 6.88 | 5 | 10 | 5 | 50 | 20 | 36 | 12 | 12 | 20 | 12 | 5.13 | 85 Ohms | TOP=L2:L3=L2/L4:L6=L5/L7:BOTTOM=L7 |
| PE_TX2_DR11_P | PE_TX2_DR11-DIFF1 | PAIR | 1 | 6.88 | 5 | 10 | 5 | 50 | 20 | 36 | 12 | 12 | 20 | 12 | 5.13 | 85 Ohms | TOP=L2:L3=L2/L4:L6=L5/L7:BOTTOM=L7 |
| PE_TX2_DR11_P | PE_TX2_DR11-DIFF1 | PAIR | 2 | 6.5 | 5 | 10 | 5 | 50 | 20 | 25 | 12 | 12 | 20 | 12 | 7.5 | 85 Ohms | TOP=L2:L3=L2/L4:L6=L5/L7:BOTTOM=L7 |
| PE_TX2_DR11_P | PE_TX2_DR11-DIFF1 | PAIR | 3 | 6.5 | 5 | 10 | 5 | 50 | 20 | 25 | 12 | 12 | 20 | 12 | 7.5 | 85 Ohms | TOP=L2:L3=L2/L4:L6=L5/L7:BOTTOM=L7 |
| PE_TX2_DR11_P | PE_TX2_DR11-DIFF1 | PAIR | 4 | 6.5 | 5 | 10 | 5 | 50 | 20 | 25 | 12 | 12 | 20 | 12 | 7.5 | 85 Ohms | TOP=L2:L3=L2/L4:L6=L5/L7:BOTTOM=L7 |
| PE_TX2_DR11_P | PE_TX2_DR11-DIFF1 | PAIR | 5 | 6.5 | 5 | 10 | 5 | 50 | 20 | 25 | 12 | 12 | 20 | 12 | 7.5 | 85 Ohms | TOP=L2:L3=L2/L4:L6=L5/L7:BOTTOM=L7 |
| PE_TX2_DR11_P | PE_TX2_DR11-DIFF1 | PAIR | 6 | 6.5 | 5 | 10 | 5 | 50 | 20 | 25 | 12 | 12 | 20 | 12 | 7.5 | 85 Ohms | TOP=L2:L3=L2/L4:L6=L5/L7:BOTTOM=L7 |
| PE_TX2_DR11_P | PE_TX2_DR11-DIFF1 | PAIR | 7 | 6.5 | 5 | 10 | 5 | 50 | 20 | 25 | 12 | 12 | 20 | 12 | 7.5 | 85 Ohms | TOP=L2:L3=L2/L4:L6=L5/L7:BOTTOM=L7 |
| PE_TX2_DR11_P | PE_TX2_DR11-DIFF1 | PAIR | 8 | 6.88 | 5 | 10 | 5 | 50 | 20 | 36 | 12 | 12 | 20 | 12 | 5.13 | 85 Ohms | TOP=L2:L3=L2/L4:L6=L5/L7:BOTTOM=L7 |
| PE_TX2_DR12_N | PE_TX2_DR12-DIFF1 | PAIR | 1 | 6.88 | 5 | 10 | 5 | 50 | 20 | 36 | 12 | 12 | 20 | 12 | 5.13 | 85 Ohms | TOP=L2:L3=L2/L4:L6=L5/L7:BOTTOM=L7 |
| PE_TX2_DR12_N | PE_TX2_DR12-DIFF1 | PAIR | 2 | 6.5 | 5 | 10 | 5 | 50 | 20 | 25 | 12 | 12 | 20 | 12 | 7.5 | 85 Ohms | TOP=L2:L3=L2/L4:L6=L5/L7:BOTTOM=L7 |
| PE_TX2_DR12_N | PE_TX2_DR12-DIFF1 | PAIR | 3 | 6.5 | 5 | 10 | 5 | 50 | 20 | 25 | 12 | 12 | 20 | 12 | 7.5 | 85 Ohms | TOP=L2:L3=L2/L4:L6=L5/L7:BOTTOM=L7 |
| PE_TX2_DR12_N | PE_TX2_DR12-DIFF1 | PAIR | 4 | 6.5 | 5 | 10 | 5 | 50 | 20 | 25 | 12 | 12 | 20 | 12 | 7.5 | 85 Ohms | TOP=L2:L3=L2/L4:L6=L5/L7:BOTTOM=L7 |
| PE_TX2_DR12_N | PE_TX2_DR12-DIFF1 | PAIR | 5 | 6.5 | 5 | 10 | 5 | 50 | 20 | 25 | 12 | 12 | 20 | 12 | 7.5 | 85 Ohms | TOP=L2:L3=L2/L4:L6=L5/L7:BOTTOM=L7 |
| PE_TX2_DR12_N | PE_TX2_DR12-DIFF1 | PAIR | 6 | 6.5 | 5 | 10 | 5 | 50 | 20 | 25 | 12 | 12 | 20 | 12 | 7.5 | 85 Ohms | TOP=L2:L3=L2/L4:L6=L5/L7:BOTTOM=L7 |
| PE_TX2_DR12_N | PE_TX2_DR12-DIFF1 | PAIR | 7 | 6.5 | 5 | 10 | 5 | 50 | 20 | 25 | 12 | 12 | 20 | 12 | 7.5 | 85 Ohms | TOP=L2:L3=L2/L4:L6=L5/L7:BOTTOM=L7 |
| PE_TX2_DR12_N | PE_TX2_DR12-DIFF1 | PAIR | 8 | 6.88 | 5 | 10 | 5 | 50 | 20 | 36 | 12 | 12 | 20 | 12 | 5.13 | 85 Ohms | TOP=L2:L3=L2/L4:L6=L5/L7:BOTTOM=L7 |
| PE_TX2_DR12_P | PE_TX2_DR12-DIFF1 | PAIR | 1 | 6.88 | 5 | 10 | 5 | 50 | 20 | 36 | 12 | 12 | 20 | 12 | 5.13 | 85 Ohms | TOP=L2:L3=L2/L4:L6=L5/L7:BOTTOM=L7 |
| PE_TX2_DR12_P | PE_TX2_DR12-DIFF1 | PAIR | 2 | 6.5 | 5 | 10 | 5 | 50 | 20 | 25 | 12 | 12 | 20 | 12 | 7.5 | 85 Ohms | TOP=L2:L3=L2/L4:L6=L5/L7:BOTTOM=L7 |
| PE_TX2_DR12_P | PE_TX2_DR12-DIFF1 | PAIR | 3 | 6.5 | 5 | 10 | 5 | 50 | 20 | 25 | 12 | 12 | 20 | 12 | 7.5 | 85 Ohms | TOP=L2:L3=L2/L4:L6=L5/L7:BOTTOM=L7 |
| PE_TX2_DR12_P | PE_TX2_DR12-DIFF1 | PAIR | 4 | 6.5 | 5 | 10 | 5 | 50 | 20 | 25 | 12 | 12 | 20 | 12 | 7.5 | 85 Ohms | TOP=L2:L3=L2/L4:L6=L5/L7:BOTTOM=L7 |
| PE_TX2_DR12_P | PE_TX2_DR12-DIFF1 | PAIR | 5 | 6.5 | 5 | 10 | 5 | 50 | 20 | 25 | 12 | 12 | 20 | 12 | 7.5 | 85 Ohms | TOP=L2:L3=L2/L4:L6=L5/L7:BOTTOM=L7 |
| PE_TX2_DR12_P | PE_TX2_DR12-DIFF1 | PAIR | 6 | 6.5 | 5 | 10 | 5 | 50 | 20 | 25 | 12 | 12 | 20 | 12 | 7.5 | 85 Ohms | TOP=L2:L3=L2/L4:L6=L5/L7:BOTTOM=L7 |
| PE_TX2_DR12_P | PE_TX2_DR12-DIFF1 | PAIR | 7 | 6.5 | 5 | 10 | 5 | 50 | 20 | 25 | 12 | 12 | 20 | 12 | 7.5 | 85 Ohms | TOP=L2:L3=L2/L4:L6=L5/L7:BOTTOM=L7 |
| PE_TX2_DR12_P | PE_TX2_DR12-DIFF1 | PAIR | 8 | 6.88 | 5 | 10 | 5 | 50 | 20 | 36 | 12 | 12 | 20 | 12 | 5.13 | 85 Ohms | TOP=L2:L3=L2/L4:L6=L5/L7:BOTTOM=L7 |
| PE_TX2_DR13_N | PE_TX2_DR13-DIFF1 | PAIR | 1 | 6.88 | 5 | 10 | 5 | 50 | 20 | 36 | 12 | 12 | 20 | 12 | 5.13 | 85 Ohms | TOP=L2:L3=L2/L4:L6=L5/L7:BOTTOM=L7 |
| PE_TX2_DR13_N | PE_TX2_DR13-DIFF1 | PAIR | 2 | 6.5 | 5 | 10 | 5 | 50 | 20 | 25 | 12 | 12 | 20 | 12 | 7.5 | 85 Ohms | TOP=L2:L3=L2/L4:L6=L5/L7:BOTTOM=L7 |
| PE_TX2_DR13_N | PE_TX2_DR13-DIFF1 | PAIR | 3 | 6.5 | 5 | 10 | 5 | 50 | 20 | 25 | 12 | 12 | 20 | 12 | 7.5 | 85 Ohms | TOP=L2:L3=L2/L4:L6=L5/L7:BOTTOM=L7 |
| PE_TX2_DR13_N | PE_TX2_DR13-DIFF1 | PAIR | 4 | 6.5 | 5 | 10 | 5 | 50 | 20 | 25 | 12 | 12 | 20 | 12 | 7.5 | 85 Ohms | TOP=L2:L3=L2/L4:L6=L5/L7:BOTTOM=L7 |
| PE_TX2_DR13_N | PE_TX2_DR13-DIFF1 | PAIR | 5 | 6.5 | 5 | 10 | 5 | 50 | 20 | 25 | 12 | 12 | 20 | 12 | 7.5 | 85 Ohms | TOP=L2:L3=L2/L4:L6=L5/L7:BOTTOM=L7 |
| PE_TX2_DR13_N | PE_TX2_DR13-DIFF1 | PAIR | 6 | 6.5 | 5 | 10 | 5 | 50 | 20 | 25 | 12 | 12 | 20 | 12 | 7.5 | 85 Ohms | TOP=L2:L3=L2/L4:L6=L5/L7:BOTTOM=L7 |
| PE_TX2_DR13_N | PE_TX2_DR13-DIFF1 | PAIR | 7 | 6.5 | 5 | 10 | 5 | 50 | 20 | 25 | 12 | 12 | 20 | 12 | 7.5 | 85 Ohms | TOP=L2:L3=L2/L4:L6=L5/L7:BOTTOM=L7 |
| PE_TX2_DR13_N | PE_TX2_DR13-DIFF1 | PAIR | 8 | 6.88 | 5 | 10 | 5 | 50 | 20 | 36 | 12 | 12 | 20 | 12 | 5.13 | 85 Ohms | TOP=L2:L3=L2/L4:L6=L5/L7:BOTTOM=L7 |
| PE_TX2_DR13_P | PE_TX2_DR13-DIFF1 | PAIR | 1 | 6.88 | 5 | 10 | 5 | 50 | 20 | 36 | 12 | 12 | 20 | 12 | 5.13 | 85 Ohms | TOP=L2:L3=L2/L4:L6=L5/L7:BOTTOM=L7 |
| PE_TX2_DR13_P | PE_TX2_DR13-DIFF1 | PAIR | 2 | 6.5 | 5 | 10 | 5 | 50 | 20 | 25 | 12 | 12 | 20 | 12 | 7.5 | 85 Ohms | TOP=L2:L3=L2/L4:L6=L5/L7:BOTTOM=L7 |
| PE_TX2_DR13_P | PE_TX2_DR13-DIFF1 | PAIR | 3 | 6.5 | 5 | 10 | 5 | 50 | 20 | 25 | 12 | 12 | 20 | 12 | 7.5 | 85 Ohms | TOP=L2:L3=L2/L4:L6=L5/L7:BOTTOM=L7 |
| PE_TX2_DR13_P | PE_TX2_DR13-DIFF1 | PAIR | 4 | 6.5 | 5 | 10 | 5 | 50 | 20 | 25 | 12 | 12 | 20 | 12 | 7.5 | 85 Ohms | TOP=L2:L3=L2/L4:L6=L5/L7:BOTTOM=L7 |
| PE_TX2_DR13_P | PE_TX2_DR13-DIFF1 | PAIR | 5 | 6.5 | 5 | 10 | 5 | 50 | 20 | 25 | 12 | 12 | 20 | 12 | 7.5 | 85 Ohms | TOP=L2:L3=L2/L4:L6=L5/L7:BOTTOM=L7 |
| PE_TX2_DR13_P | PE_TX2_DR13-DIFF1 | PAIR | 6 | 6.5 | 5 | 10 | 5 | 50 | 20 | 25 | 12 | 12 | 20 | 12 | 7.5 | 85 Ohms | TOP=L2:L3=L2/L4:L6=L5/L7:BOTTOM=L7 |
| PE_TX2_DR13_P | PE_TX2_DR13-DIFF1 | PAIR | 7 | 6.5 | 5 | 10 | 5 | 50 | 20 | 25 | 12 | 12 | 20 | 12 | 7.5 | 85 Ohms | TOP=L2:L3=L2/L4:L6=L5/L7:BOTTOM=L7 |
| PE_TX2_DR13_P | PE_TX2_DR13-DIFF1 | PAIR | 8 | 6.88 | 5 | 10 | 5 | 50 | 20 | 36 | 12 | 12 | 20 | 12 | 5.13 | 85 Ohms | TOP=L2:L3=L2/L4:L6=L5/L7:BOTTOM=L7 |
| PE_TX2_DR14_N | PE_TX2_DR14-DIFF1 | PAIR | 1 | 6.88 | 5 | 10 | 5 | 50 | 20 | 36 | 12 | 12 | 20 | 12 | 5.13 | 85 Ohms | TOP=L2:L3=L2/L4:L6=L5/L7:BOTTOM=L7 |
| PE_TX2_DR14_N | PE_TX2_DR14-DIFF1 | PAIR | 2 | 6.5 | 5 | 10 | 5 | 50 | 20 | 25 | 12 | 12 | 20 | 12 | 7.5 | 85 Ohms | TOP=L2:L3=L2/L4:L6=L5/L7:BOTTOM=L7 |
| PE_TX2_DR14_N | PE_TX2_DR14-DIFF1 | PAIR | 3 | 6.5 | 5 | 10 | 5 | 50 | 20 | 25 | 12 | 12 | 20 | 12 | 7.5 | 85 Ohms | TOP=L2:L3=L2/L4:L6=L5/L7:BOTTOM=L7 |
| PE_TX2_DR14_N | PE_TX2_DR14-DIFF1 | PAIR | 4 | 6.5 | 5 | 10 | 5 | 50 | 20 | 25 | 12 | 12 | 20 | 12 | 7.5 | 85 Ohms | TOP=L2:L3=L2/L4:L6=L5/L7:BOTTOM=L7 |
| PE_TX2_DR14_N | PE_TX2_DR14-DIFF1 | PAIR | 5 | 6.5 | 5 | 10 | 5 | 50 | 20 | 25 | 12 | 12 | 20 | 12 | 7.5 | 85 Ohms | TOP=L2:L3=L2/L4:L6=L5/L7:BOTTOM=L7 |
| PE_TX2_DR14_N | PE_TX2_DR14-DIFF1 | PAIR | 6 | 6.5 | 5 | 10 | 5 | 50 | 20 | 25 | 12 | 12 | 20 | 12 | 7.5 | 85 Ohms | TOP=L2:L3=L2/L4:L6=L5/L7:BOTTOM=L7 |
| PE_TX2_DR14_N | PE_TX2_DR14-DIFF1 | PAIR | 7 | 6.5 | 5 | 10 | 5 | 50 | 20 | 25 | 12 | 12 | 20 | 12 | 7.5 | 85 Ohms | TOP=L2:L3=L2/L4:L6=L5/L7:BOTTOM=L7 |
| PE_TX2_DR14_N | PE_TX2_DR14-DIFF1 | PAIR | 8 | 6.88 | 5 | 10 | 5 | 50 | 20 | 36 | 12 | 12 | 20 | 12 | 5.13 | 85 Ohms | TOP=L2:L3=L2/L4:L6=L5/L7:BOTTOM=L7 |
| PE_TX2_DR14_P | PE_TX2_DR14-DIFF1 | PAIR | 1 | 6.88 | 5 | 10 | 5 | 50 | 20 | 36 | 12 | 12 | 20 | 12 | 5.13 | 85 Ohms | TOP=L2:L3=L2/L4:L6=L5/L7:BOTTOM=L7 |
| PE_TX2_DR14_P | PE_TX2_DR14-DIFF1 | PAIR | 2 | 6.5 | 5 | 10 | 5 | 50 | 20 | 25 | 12 | 12 | 20 | 12 | 7.5 | 85 Ohms | TOP=L2:L3=L2/L4:L6=L5/L7:BOTTOM=L7 |
| PE_TX2_DR14_P | PE_TX2_DR14-DIFF1 | PAIR | 3 | 6.5 | 5 | 10 | 5 | 50 | 20 | 25 | 12 | 12 | 20 | 12 | 7.5 | 85 Ohms | TOP=L2:L3=L2/L4:L6=L5/L7:BOTTOM=L7 |
| PE_TX2_DR14_P | PE_TX2_DR14-DIFF1 | PAIR | 4 | 6.5 | 5 | 10 | 5 | 50 | 20 | 25 | 12 | 12 | 20 | 12 | 7.5 | 85 Ohms | TOP=L2:L3=L2/L4:L6=L5/L7:BOTTOM=L7 |
| PE_TX2_DR14_P | PE_TX2_DR14-DIFF1 | PAIR | 5 | 6.5 | 5 | 10 | 5 | 50 | 20 | 25 | 12 | 12 | 20 | 12 | 7.5 | 85 Ohms | TOP=L2:L3=L2/L4:L6=L5/L7:BOTTOM=L7 |
| PE_TX2_DR14_P | PE_TX2_DR14-DIFF1 | PAIR | 6 | 6.5 | 5 | 10 | 5 | 50 | 20 | 25 | 12 | 12 | 20 | 12 | 7.5 | 85 Ohms | TOP=L2:L3=L2/L4:L6=L5/L7:BOTTOM=L7 |
| PE_TX2_DR14_P | PE_TX2_DR14-DIFF1 | PAIR | 7 | 6.5 | 5 | 10 | 5 | 50 | 20 | 25 | 12 | 12 | 20 | 12 | 7.5 | 85 Ohms | TOP=L2:L3=L2/L4:L6=L5/L7:BOTTOM=L7 |
| PE_TX2_DR14_P | PE_TX2_DR14-DIFF1 | PAIR | 8 | 6.88 | 5 | 10 | 5 | 50 | 20 | 36 | 12 | 12 | 20 | 12 | 5.13 | 85 Ohms | TOP=L2:L3=L2/L4:L6=L5/L7:BOTTOM=L7 |
| PE_TX2_DR1_N | PE_TX2_DR1-DIFF1 | PAIR | 1 | 6.88 | 5 | 10 | 5 | 50 | 20 | 36 | 12 | 12 | 20 | 12 | 5.13 | 85 Ohms | TOP=L2:L3=L2/L4:L6=L5/L7:BOTTOM=L7 |
| PE_TX2_DR1_N | PE_TX2_DR1-DIFF1 | PAIR | 2 | 6.5 | 5 | 10 | 5 | 50 | 20 | 25 | 12 | 12 | 20 | 12 | 7.5 | 85 Ohms | TOP=L2:L3=L2/L4:L6=L5/L7:BOTTOM=L7 |
| PE_TX2_DR1_N | PE_TX2_DR1-DIFF1 | PAIR | 3 | 6.5 | 5 | 10 | 5 | 50 | 20 | 25 | 12 | 12 | 20 | 12 | 7.5 | 85 Ohms | TOP=L2:L3=L2/L4:L6=L5/L7:BOTTOM=L7 |
| PE_TX2_DR1_N | PE_TX2_DR1-DIFF1 | PAIR | 4 | 6.5 | 5 | 10 | 5 | 50 | 20 | 25 | 12 | 12 | 20 | 12 | 7.5 | 85 Ohms | TOP=L2:L3=L2/L4:L6=L5/L7:BOTTOM=L7 |
| PE_TX2_DR1_N | PE_TX2_DR1-DIFF1 | PAIR | 5 | 6.5 | 5 | 10 | 5 | 50 | 20 | 25 | 12 | 12 | 20 | 12 | 7.5 | 85 Ohms | TOP=L2:L3=L2/L4:L6=L5/L7:BOTTOM=L7 |
| PE_TX2_DR1_N | PE_TX2_DR1-DIFF1 | PAIR | 6 | 6.5 | 5 | 10 | 5 | 50 | 20 | 25 | 12 | 12 | 20 | 12 | 7.5 | 85 Ohms | TOP=L2:L3=L2/L4:L6=L5/L7:BOTTOM=L7 |
| PE_TX2_DR1_N | PE_TX2_DR1-DIFF1 | PAIR | 7 | 6.5 | 5 | 10 | 5 | 50 | 20 | 25 | 12 | 12 | 20 | 12 | 7.5 | 85 Ohms | TOP=L2:L3=L2/L4:L6=L5/L7:BOTTOM=L7 |
| PE_TX2_DR1_N | PE_TX2_DR1-DIFF1 | PAIR | 8 | 6.88 | 5 | 10 | 5 | 50 | 20 | 36 | 12 | 12 | 20 | 12 | 5.13 | 85 Ohms | TOP=L2:L3=L2/L4:L6=L5/L7:BOTTOM=L7 |
| PE_TX2_DR1_P | PE_TX2_DR1-DIFF1 | PAIR | 1 | 6.88 | 5 | 10 | 5 | 50 | 20 | 36 | 12 | 12 | 20 | 12 | 5.13 | 85 Ohms | TOP=L2:L3=L2/L4:L6=L5/L7:BOTTOM=L7 |
| PE_TX2_DR1_P | PE_TX2_DR1-DIFF1 | PAIR | 2 | 6.5 | 5 | 10 | 5 | 50 | 20 | 25 | 12 | 12 | 20 | 12 | 7.5 | 85 Ohms | TOP=L2:L3=L2/L4:L6=L5/L7:BOTTOM=L7 |
| PE_TX2_DR1_P | PE_TX2_DR1-DIFF1 | PAIR | 3 | 6.5 | 5 | 10 | 5 | 50 | 20 | 25 | 12 | 12 | 20 | 12 | 7.5 | 85 Ohms | TOP=L2:L3=L2/L4:L6=L5/L7:BOTTOM=L7 |
| PE_TX2_DR1_P | PE_TX2_DR1-DIFF1 | PAIR | 4 | 6.5 | 5 | 10 | 5 | 50 | 20 | 25 | 12 | 12 | 20 | 12 | 7.5 | 85 Ohms | TOP=L2:L3=L2/L4:L6=L5/L7:BOTTOM=L7 |
| PE_TX2_DR1_P | PE_TX2_DR1-DIFF1 | PAIR | 5 | 6.5 | 5 | 10 | 5 | 50 | 20 | 25 | 12 | 12 | 20 | 12 | 7.5 | 85 Ohms | TOP=L2:L3=L2/L4:L6=L5/L7:BOTTOM=L7 |
| PE_TX2_DR1_P | PE_TX2_DR1-DIFF1 | PAIR | 6 | 6.5 | 5 | 10 | 5 | 50 | 20 | 25 | 12 | 12 | 20 | 12 | 7.5 | 85 Ohms | TOP=L2:L3=L2/L4:L6=L5/L7:BOTTOM=L7 |
| PE_TX2_DR1_P | PE_TX2_DR1-DIFF1 | PAIR | 7 | 6.5 | 5 | 10 | 5 | 50 | 20 | 25 | 12 | 12 | 20 | 12 | 7.5 | 85 Ohms | TOP=L2:L3=L2/L4:L6=L5/L7:BOTTOM=L7 |
| PE_TX2_DR1_P | PE_TX2_DR1-DIFF1 | PAIR | 8 | 6.88 | 5 | 10 | 5 | 50 | 20 | 36 | 12 | 12 | 20 | 12 | 5.13 | 85 Ohms | TOP=L2:L3=L2/L4:L6=L5/L7:BOTTOM=L7 |
| PE_TX2_DR2_N | PE_TX2_DR2-DIFF1 | PAIR | 1 | 6.88 | 5 | 10 | 5 | 50 | 20 | 36 | 12 | 12 | 20 | 12 | 5.13 | 85 Ohms | TOP=L2:L3=L2/L4:L6=L5/L7:BOTTOM=L7 |
| PE_TX2_DR2_N | PE_TX2_DR2-DIFF1 | PAIR | 2 | 6.5 | 5 | 10 | 5 | 50 | 20 | 25 | 12 | 12 | 20 | 12 | 7.5 | 85 Ohms | TOP=L2:L3=L2/L4:L6=L5/L7:BOTTOM=L7 |
| PE_TX2_DR2_N | PE_TX2_DR2-DIFF1 | PAIR | 3 | 6.5 | 5 | 10 | 5 | 50 | 20 | 25 | 12 | 12 | 20 | 12 | 7.5 | 85 Ohms | TOP=L2:L3=L2/L4:L6=L5/L7:BOTTOM=L7 |
| PE_TX2_DR2_N | PE_TX2_DR2-DIFF1 | PAIR | 4 | 6.5 | 5 | 10 | 5 | 50 | 20 | 25 | 12 | 12 | 20 | 12 | 7.5 | 85 Ohms | TOP=L2:L3=L2/L4:L6=L5/L7:BOTTOM=L7 |
| PE_TX2_DR2_N | PE_TX2_DR2-DIFF1 | PAIR | 5 | 6.5 | 5 | 10 | 5 | 50 | 20 | 25 | 12 | 12 | 20 | 12 | 7.5 | 85 Ohms | TOP=L2:L3=L2/L4:L6=L5/L7:BOTTOM=L7 |
| PE_TX2_DR2_N | PE_TX2_DR2-DIFF1 | PAIR | 6 | 6.5 | 5 | 10 | 5 | 50 | 20 | 25 | 12 | 12 | 20 | 12 | 7.5 | 85 Ohms | TOP=L2:L3=L2/L4:L6=L5/L7:BOTTOM=L7 |
| PE_TX2_DR2_N | PE_TX2_DR2-DIFF1 | PAIR | 7 | 6.5 | 5 | 10 | 5 | 50 | 20 | 25 | 12 | 12 | 20 | 12 | 7.5 | 85 Ohms | TOP=L2:L3=L2/L4:L6=L5/L7:BOTTOM=L7 |
| PE_TX2_DR2_N | PE_TX2_DR2-DIFF1 | PAIR | 8 | 6.88 | 5 | 10 | 5 | 50 | 20 | 36 | 12 | 12 | 20 | 12 | 5.13 | 85 Ohms | TOP=L2:L3=L2/L4:L6=L5/L7:BOTTOM=L7 |
| PE_TX2_DR2_P | PE_TX2_DR2-DIFF1 | PAIR | 1 | 6.88 | 5 | 10 | 5 | 50 | 20 | 36 | 12 | 12 | 20 | 12 | 5.13 | 85 Ohms | TOP=L2:L3=L2/L4:L6=L5/L7:BOTTOM=L7 |
| PE_TX2_DR2_P | PE_TX2_DR2-DIFF1 | PAIR | 2 | 6.5 | 5 | 10 | 5 | 50 | 20 | 25 | 12 | 12 | 20 | 12 | 7.5 | 85 Ohms | TOP=L2:L3=L2/L4:L6=L5/L7:BOTTOM=L7 |
| PE_TX2_DR2_P | PE_TX2_DR2-DIFF1 | PAIR | 3 | 6.5 | 5 | 10 | 5 | 50 | 20 | 25 | 12 | 12 | 20 | 12 | 7.5 | 85 Ohms | TOP=L2:L3=L2/L4:L6=L5/L7:BOTTOM=L7 |
| PE_TX2_DR2_P | PE_TX2_DR2-DIFF1 | PAIR | 4 | 6.5 | 5 | 10 | 5 | 50 | 20 | 25 | 12 | 12 | 20 | 12 | 7.5 | 85 Ohms | TOP=L2:L3=L2/L4:L6=L5/L7:BOTTOM=L7 |
| PE_TX2_DR2_P | PE_TX2_DR2-DIFF1 | PAIR | 5 | 6.5 | 5 | 10 | 5 | 50 | 20 | 25 | 12 | 12 | 20 | 12 | 7.5 | 85 Ohms | TOP=L2:L3=L2/L4:L6=L5/L7:BOTTOM=L7 |
| PE_TX2_DR2_P | PE_TX2_DR2-DIFF1 | PAIR | 6 | 6.5 | 5 | 10 | 5 | 50 | 20 | 25 | 12 | 12 | 20 | 12 | 7.5 | 85 Ohms | TOP=L2:L3=L2/L4:L6=L5/L7:BOTTOM=L7 |
| PE_TX2_DR2_P | PE_TX2_DR2-DIFF1 | PAIR | 7 | 6.5 | 5 | 10 | 5 | 50 | 20 | 25 | 12 | 12 | 20 | 12 | 7.5 | 85 Ohms | TOP=L2:L3=L2/L4:L6=L5/L7:BOTTOM=L7 |
| PE_TX2_DR2_P | PE_TX2_DR2-DIFF1 | PAIR | 8 | 6.88 | 5 | 10 | 5 | 50 | 20 | 36 | 12 | 12 | 20 | 12 | 5.13 | 85 Ohms | TOP=L2:L3=L2/L4:L6=L5/L7:BOTTOM=L7 |
| PE_TX2_DR3_N | PE_TX2_DR3-DIFF1 | PAIR | 1 | 6.88 | 5 | 10 | 5 | 50 | 20 | 36 | 12 | 12 | 20 | 12 | 5.13 | 85 Ohms | TOP=L2:L3=L2/L4:L6=L5/L7:BOTTOM=L7 |
| PE_TX2_DR3_N | PE_TX2_DR3-DIFF1 | PAIR | 2 | 6.5 | 5 | 10 | 5 | 50 | 20 | 25 | 12 | 12 | 20 | 12 | 7.5 | 85 Ohms | TOP=L2:L3=L2/L4:L6=L5/L7:BOTTOM=L7 |
| PE_TX2_DR3_N | PE_TX2_DR3-DIFF1 | PAIR | 3 | 6.5 | 5 | 10 | 5 | 50 | 20 | 25 | 12 | 12 | 20 | 12 | 7.5 | 85 Ohms | TOP=L2:L3=L2/L4:L6=L5/L7:BOTTOM=L7 |
| PE_TX2_DR3_N | PE_TX2_DR3-DIFF1 | PAIR | 4 | 6.5 | 5 | 10 | 5 | 50 | 20 | 25 | 12 | 12 | 20 | 12 | 7.5 | 85 Ohms | TOP=L2:L3=L2/L4:L6=L5/L7:BOTTOM=L7 |
| PE_TX2_DR3_N | PE_TX2_DR3-DIFF1 | PAIR | 5 | 6.5 | 5 | 10 | 5 | 50 | 20 | 25 | 12 | 12 | 20 | 12 | 7.5 | 85 Ohms | TOP=L2:L3=L2/L4:L6=L5/L7:BOTTOM=L7 |
| PE_TX2_DR3_N | PE_TX2_DR3-DIFF1 | PAIR | 6 | 6.5 | 5 | 10 | 5 | 50 | 20 | 25 | 12 | 12 | 20 | 12 | 7.5 | 85 Ohms | TOP=L2:L3=L2/L4:L6=L5/L7:BOTTOM=L7 |
| PE_TX2_DR3_N | PE_TX2_DR3-DIFF1 | PAIR | 7 | 6.5 | 5 | 10 | 5 | 50 | 20 | 25 | 12 | 12 | 20 | 12 | 7.5 | 85 Ohms | TOP=L2:L3=L2/L4:L6=L5/L7:BOTTOM=L7 |
| PE_TX2_DR3_N | PE_TX2_DR3-DIFF1 | PAIR | 8 | 6.88 | 5 | 10 | 5 | 50 | 20 | 36 | 12 | 12 | 20 | 12 | 5.13 | 85 Ohms | TOP=L2:L3=L2/L4:L6=L5/L7:BOTTOM=L7 |
| PE_TX2_DR3_P | PE_TX2_DR3-DIFF1 | PAIR | 1 | 6.88 | 5 | 10 | 5 | 50 | 20 | 36 | 12 | 12 | 20 | 12 | 5.13 | 85 Ohms | TOP=L2:L3=L2/L4:L6=L5/L7:BOTTOM=L7 |
| PE_TX2_DR3_P | PE_TX2_DR3-DIFF1 | PAIR | 2 | 6.5 | 5 | 10 | 5 | 50 | 20 | 25 | 12 | 12 | 20 | 12 | 7.5 | 85 Ohms | TOP=L2:L3=L2/L4:L6=L5/L7:BOTTOM=L7 |
| PE_TX2_DR3_P | PE_TX2_DR3-DIFF1 | PAIR | 3 | 6.5 | 5 | 10 | 5 | 50 | 20 | 25 | 12 | 12 | 20 | 12 | 7.5 | 85 Ohms | TOP=L2:L3=L2/L4:L6=L5/L7:BOTTOM=L7 |
| PE_TX2_DR3_P | PE_TX2_DR3-DIFF1 | PAIR | 4 | 6.5 | 5 | 10 | 5 | 50 | 20 | 25 | 12 | 12 | 20 | 12 | 7.5 | 85 Ohms | TOP=L2:L3=L2/L4:L6=L5/L7:BOTTOM=L7 |
| PE_TX2_DR3_P | PE_TX2_DR3-DIFF1 | PAIR | 5 | 6.5 | 5 | 10 | 5 | 50 | 20 | 25 | 12 | 12 | 20 | 12 | 7.5 | 85 Ohms | TOP=L2:L3=L2/L4:L6=L5/L7:BOTTOM=L7 |
| PE_TX2_DR3_P | PE_TX2_DR3-DIFF1 | PAIR | 6 | 6.5 | 5 | 10 | 5 | 50 | 20 | 25 | 12 | 12 | 20 | 12 | 7.5 | 85 Ohms | TOP=L2:L3=L2/L4:L6=L5/L7:BOTTOM=L7 |
| PE_TX2_DR3_P | PE_TX2_DR3-DIFF1 | PAIR | 7 | 6.5 | 5 | 10 | 5 | 50 | 20 | 25 | 12 | 12 | 20 | 12 | 7.5 | 85 Ohms | TOP=L2:L3=L2/L4:L6=L5/L7:BOTTOM=L7 |
| PE_TX2_DR3_P | PE_TX2_DR3-DIFF1 | PAIR | 8 | 6.88 | 5 | 10 | 5 | 50 | 20 | 36 | 12 | 12 | 20 | 12 | 5.13 | 85 Ohms | TOP=L2:L3=L2/L4:L6=L5/L7:BOTTOM=L7 |
| PE_TX2_DR4_N | PE_TX2_DR4-DIFF1 | PAIR | 1 | 6.88 | 5 | 10 | 5 | 50 | 20 | 36 | 12 | 12 | 20 | 12 | 5.13 | 85 Ohms | TOP=L2:L3=L2/L4:L6=L5/L7:BOTTOM=L7 |
| PE_TX2_DR4_N | PE_TX2_DR4-DIFF1 | PAIR | 2 | 6.5 | 5 | 10 | 5 | 50 | 20 | 25 | 12 | 12 | 20 | 12 | 7.5 | 85 Ohms | TOP=L2:L3=L2/L4:L6=L5/L7:BOTTOM=L7 |
| PE_TX2_DR4_N | PE_TX2_DR4-DIFF1 | PAIR | 3 | 6.5 | 5 | 10 | 5 | 50 | 20 | 25 | 12 | 12 | 20 | 12 | 7.5 | 85 Ohms | TOP=L2:L3=L2/L4:L6=L5/L7:BOTTOM=L7 |
| PE_TX2_DR4_N | PE_TX2_DR4-DIFF1 | PAIR | 4 | 6.5 | 5 | 10 | 5 | 50 | 20 | 25 | 12 | 12 | 20 | 12 | 7.5 | 85 Ohms | TOP=L2:L3=L2/L4:L6=L5/L7:BOTTOM=L7 |
| PE_TX2_DR4_N | PE_TX2_DR4-DIFF1 | PAIR | 5 | 6.5 | 5 | 10 | 5 | 50 | 20 | 25 | 12 | 12 | 20 | 12 | 7.5 | 85 Ohms | TOP=L2:L3=L2/L4:L6=L5/L7:BOTTOM=L7 |
| PE_TX2_DR4_N | PE_TX2_DR4-DIFF1 | PAIR | 6 | 6.5 | 5 | 10 | 5 | 50 | 20 | 25 | 12 | 12 | 20 | 12 | 7.5 | 85 Ohms | TOP=L2:L3=L2/L4:L6=L5/L7:BOTTOM=L7 |
| PE_TX2_DR4_N | PE_TX2_DR4-DIFF1 | PAIR | 7 | 6.5 | 5 | 10 | 5 | 50 | 20 | 25 | 12 | 12 | 20 | 12 | 7.5 | 85 Ohms | TOP=L2:L3=L2/L4:L6=L5/L7:BOTTOM=L7 |
| PE_TX2_DR4_N | PE_TX2_DR4-DIFF1 | PAIR | 8 | 6.88 | 5 | 10 | 5 | 50 | 20 | 36 | 12 | 12 | 20 | 12 | 5.13 | 85 Ohms | TOP=L2:L3=L2/L4:L6=L5/L7:BOTTOM=L7 |
| PE_TX2_DR4_P | PE_TX2_DR4-DIFF1 | PAIR | 1 | 6.88 | 5 | 10 | 5 | 50 | 20 | 36 | 12 | 12 | 20 | 12 | 5.13 | 85 Ohms | TOP=L2:L3=L2/L4:L6=L5/L7:BOTTOM=L7 |
| PE_TX2_DR4_P | PE_TX2_DR4-DIFF1 | PAIR | 2 | 6.5 | 5 | 10 | 5 | 50 | 20 | 25 | 12 | 12 | 20 | 12 | 7.5 | 85 Ohms | TOP=L2:L3=L2/L4:L6=L5/L7:BOTTOM=L7 |
| PE_TX2_DR4_P | PE_TX2_DR4-DIFF1 | PAIR | 3 | 6.5 | 5 | 10 | 5 | 50 | 20 | 25 | 12 | 12 | 20 | 12 | 7.5 | 85 Ohms | TOP=L2:L3=L2/L4:L6=L5/L7:BOTTOM=L7 |
| PE_TX2_DR4_P | PE_TX2_DR4-DIFF1 | PAIR | 4 | 6.5 | 5 | 10 | 5 | 50 | 20 | 25 | 12 | 12 | 20 | 12 | 7.5 | 85 Ohms | TOP=L2:L3=L2/L4:L6=L5/L7:BOTTOM=L7 |
| PE_TX2_DR4_P | PE_TX2_DR4-DIFF1 | PAIR | 5 | 6.5 | 5 | 10 | 5 | 50 | 20 | 25 | 12 | 12 | 20 | 12 | 7.5 | 85 Ohms | TOP=L2:L3=L2/L4:L6=L5/L7:BOTTOM=L7 |
| PE_TX2_DR4_P | PE_TX2_DR4-DIFF1 | PAIR | 6 | 6.5 | 5 | 10 | 5 | 50 | 20 | 25 | 12 | 12 | 20 | 12 | 7.5 | 85 Ohms | TOP=L2:L3=L2/L4:L6=L5/L7:BOTTOM=L7 |
| PE_TX2_DR4_P | PE_TX2_DR4-DIFF1 | PAIR | 7 | 6.5 | 5 | 10 | 5 | 50 | 20 | 25 | 12 | 12 | 20 | 12 | 7.5 | 85 Ohms | TOP=L2:L3=L2/L4:L6=L5/L7:BOTTOM=L7 |
| PE_TX2_DR4_P | PE_TX2_DR4-DIFF1 | PAIR | 8 | 6.88 | 5 | 10 | 5 | 50 | 20 | 36 | 12 | 12 | 20 | 12 | 5.13 | 85 Ohms | TOP=L2:L3=L2/L4:L6=L5/L7:BOTTOM=L7 |
| PE_TX2_DR5_N | PE_TX2_DR5-DIFF1 | PAIR | 1 | 6.88 | 5 | 10 | 5 | 50 | 20 | 36 | 12 | 12 | 20 | 12 | 5.13 | 85 Ohms | TOP=L2:L3=L2/L4:L6=L5/L7:BOTTOM=L7 |
| PE_TX2_DR5_N | PE_TX2_DR5-DIFF1 | PAIR | 2 | 6.5 | 5 | 10 | 5 | 50 | 20 | 25 | 12 | 12 | 20 | 12 | 7.5 | 85 Ohms | TOP=L2:L3=L2/L4:L6=L5/L7:BOTTOM=L7 |
| PE_TX2_DR5_N | PE_TX2_DR5-DIFF1 | PAIR | 3 | 6.5 | 5 | 10 | 5 | 50 | 20 | 25 | 12 | 12 | 20 | 12 | 7.5 | 85 Ohms | TOP=L2:L3=L2/L4:L6=L5/L7:BOTTOM=L7 |
| PE_TX2_DR5_N | PE_TX2_DR5-DIFF1 | PAIR | 4 | 6.5 | 5 | 10 | 5 | 50 | 20 | 25 | 12 | 12 | 20 | 12 | 7.5 | 85 Ohms | TOP=L2:L3=L2/L4:L6=L5/L7:BOTTOM=L7 |
| PE_TX2_DR5_N | PE_TX2_DR5-DIFF1 | PAIR | 5 | 6.5 | 5 | 10 | 5 | 50 | 20 | 25 | 12 | 12 | 20 | 12 | 7.5 | 85 Ohms | TOP=L2:L3=L2/L4:L6=L5/L7:BOTTOM=L7 |
| PE_TX2_DR5_N | PE_TX2_DR5-DIFF1 | PAIR | 6 | 6.5 | 5 | 10 | 5 | 50 | 20 | 25 | 12 | 12 | 20 | 12 | 7.5 | 85 Ohms | TOP=L2:L3=L2/L4:L6=L5/L7:BOTTOM=L7 |
| PE_TX2_DR5_N | PE_TX2_DR5-DIFF1 | PAIR | 7 | 6.5 | 5 | 10 | 5 | 50 | 20 | 25 | 12 | 12 | 20 | 12 | 7.5 | 85 Ohms | TOP=L2:L3=L2/L4:L6=L5/L7:BOTTOM=L7 |
| PE_TX2_DR5_N | PE_TX2_DR5-DIFF1 | PAIR | 8 | 6.88 | 5 | 10 | 5 | 50 | 20 | 36 | 12 | 12 | 20 | 12 | 5.13 | 85 Ohms | TOP=L2:L3=L2/L4:L6=L5/L7:BOTTOM=L7 |
| PE_TX2_DR5_P | PE_TX2_DR5-DIFF1 | PAIR | 1 | 6.88 | 5 | 10 | 5 | 50 | 20 | 36 | 12 | 12 | 20 | 12 | 5.13 | 85 Ohms | TOP=L2:L3=L2/L4:L6=L5/L7:BOTTOM=L7 |
| PE_TX2_DR5_P | PE_TX2_DR5-DIFF1 | PAIR | 2 | 6.5 | 5 | 10 | 5 | 50 | 20 | 25 | 12 | 12 | 20 | 12 | 7.5 | 85 Ohms | TOP=L2:L3=L2/L4:L6=L5/L7:BOTTOM=L7 |
| PE_TX2_DR5_P | PE_TX2_DR5-DIFF1 | PAIR | 3 | 6.5 | 5 | 10 | 5 | 50 | 20 | 25 | 12 | 12 | 20 | 12 | 7.5 | 85 Ohms | TOP=L2:L3=L2/L4:L6=L5/L7:BOTTOM=L7 |
| PE_TX2_DR5_P | PE_TX2_DR5-DIFF1 | PAIR | 4 | 6.5 | 5 | 10 | 5 | 50 | 20 | 25 | 12 | 12 | 20 | 12 | 7.5 | 85 Ohms | TOP=L2:L3=L2/L4:L6=L5/L7:BOTTOM=L7 |
| PE_TX2_DR5_P | PE_TX2_DR5-DIFF1 | PAIR | 5 | 6.5 | 5 | 10 | 5 | 50 | 20 | 25 | 12 | 12 | 20 | 12 | 7.5 | 85 Ohms | TOP=L2:L3=L2/L4:L6=L5/L7:BOTTOM=L7 |
| PE_TX2_DR5_P | PE_TX2_DR5-DIFF1 | PAIR | 6 | 6.5 | 5 | 10 | 5 | 50 | 20 | 25 | 12 | 12 | 20 | 12 | 7.5 | 85 Ohms | TOP=L2:L3=L2/L4:L6=L5/L7:BOTTOM=L7 |
| PE_TX2_DR5_P | PE_TX2_DR5-DIFF1 | PAIR | 7 | 6.5 | 5 | 10 | 5 | 50 | 20 | 25 | 12 | 12 | 20 | 12 | 7.5 | 85 Ohms | TOP=L2:L3=L2/L4:L6=L5/L7:BOTTOM=L7 |
| PE_TX2_DR5_P | PE_TX2_DR5-DIFF1 | PAIR | 8 | 6.88 | 5 | 10 | 5 | 50 | 20 | 36 | 12 | 12 | 20 | 12 | 5.13 | 85 Ohms | TOP=L2:L3=L2/L4:L6=L5/L7:BOTTOM=L7 |
| PE_TX2_DR6_N | PE_TX2_DR6-DIFF1 | PAIR | 1 | 6.88 | 5 | 10 | 5 | 50 | 20 | 36 | 12 | 12 | 20 | 12 | 5.13 | 85 Ohms | TOP=L2:L3=L2/L4:L6=L5/L7:BOTTOM=L7 |
| PE_TX2_DR6_N | PE_TX2_DR6-DIFF1 | PAIR | 2 | 6.5 | 5 | 10 | 5 | 50 | 20 | 25 | 12 | 12 | 20 | 12 | 7.5 | 85 Ohms | TOP=L2:L3=L2/L4:L6=L5/L7:BOTTOM=L7 |
| PE_TX2_DR6_N | PE_TX2_DR6-DIFF1 | PAIR | 3 | 6.5 | 5 | 10 | 5 | 50 | 20 | 25 | 12 | 12 | 20 | 12 | 7.5 | 85 Ohms | TOP=L2:L3=L2/L4:L6=L5/L7:BOTTOM=L7 |
| PE_TX2_DR6_N | PE_TX2_DR6-DIFF1 | PAIR | 4 | 6.5 | 5 | 10 | 5 | 50 | 20 | 25 | 12 | 12 | 20 | 12 | 7.5 | 85 Ohms | TOP=L2:L3=L2/L4:L6=L5/L7:BOTTOM=L7 |
| PE_TX2_DR6_N | PE_TX2_DR6-DIFF1 | PAIR | 5 | 6.5 | 5 | 10 | 5 | 50 | 20 | 25 | 12 | 12 | 20 | 12 | 7.5 | 85 Ohms | TOP=L2:L3=L2/L4:L6=L5/L7:BOTTOM=L7 |
| PE_TX2_DR6_N | PE_TX2_DR6-DIFF1 | PAIR | 6 | 6.5 | 5 | 10 | 5 | 50 | 20 | 25 | 12 | 12 | 20 | 12 | 7.5 | 85 Ohms | TOP=L2:L3=L2/L4:L6=L5/L7:BOTTOM=L7 |
| PE_TX2_DR6_N | PE_TX2_DR6-DIFF1 | PAIR | 7 | 6.5 | 5 | 10 | 5 | 50 | 20 | 25 | 12 | 12 | 20 | 12 | 7.5 | 85 Ohms | TOP=L2:L3=L2/L4:L6=L5/L7:BOTTOM=L7 |
| PE_TX2_DR6_N | PE_TX2_DR6-DIFF1 | PAIR | 8 | 6.88 | 5 | 10 | 5 | 50 | 20 | 36 | 12 | 12 | 20 | 12 | 5.13 | 85 Ohms | TOP=L2:L3=L2/L4:L6=L5/L7:BOTTOM=L7 |
| PE_TX2_DR6_P | PE_TX2_DR6-DIFF1 | PAIR | 1 | 6.88 | 5 | 10 | 5 | 50 | 20 | 36 | 12 | 12 | 20 | 12 | 5.13 | 85 Ohms | TOP=L2:L3=L2/L4:L6=L5/L7:BOTTOM=L7 |
| PE_TX2_DR6_P | PE_TX2_DR6-DIFF1 | PAIR | 2 | 6.5 | 5 | 10 | 5 | 50 | 20 | 25 | 12 | 12 | 20 | 12 | 7.5 | 85 Ohms | TOP=L2:L3=L2/L4:L6=L5/L7:BOTTOM=L7 |
| PE_TX2_DR6_P | PE_TX2_DR6-DIFF1 | PAIR | 3 | 6.5 | 5 | 10 | 5 | 50 | 20 | 25 | 12 | 12 | 20 | 12 | 7.5 | 85 Ohms | TOP=L2:L3=L2/L4:L6=L5/L7:BOTTOM=L7 |
| PE_TX2_DR6_P | PE_TX2_DR6-DIFF1 | PAIR | 4 | 6.5 | 5 | 10 | 5 | 50 | 20 | 25 | 12 | 12 | 20 | 12 | 7.5 | 85 Ohms | TOP=L2:L3=L2/L4:L6=L5/L7:BOTTOM=L7 |
| PE_TX2_DR6_P | PE_TX2_DR6-DIFF1 | PAIR | 5 | 6.5 | 5 | 10 | 5 | 50 | 20 | 25 | 12 | 12 | 20 | 12 | 7.5 | 85 Ohms | TOP=L2:L3=L2/L4:L6=L5/L7:BOTTOM=L7 |
| PE_TX2_DR6_P | PE_TX2_DR6-DIFF1 | PAIR | 6 | 6.5 | 5 | 10 | 5 | 50 | 20 | 25 | 12 | 12 | 20 | 12 | 7.5 | 85 Ohms | TOP=L2:L3=L2/L4:L6=L5/L7:BOTTOM=L7 |
| PE_TX2_DR6_P | PE_TX2_DR6-DIFF1 | PAIR | 7 | 6.5 | 5 | 10 | 5 | 50 | 20 | 25 | 12 | 12 | 20 | 12 | 7.5 | 85 Ohms | TOP=L2:L3=L2/L4:L6=L5/L7:BOTTOM=L7 |
| PE_TX2_DR6_P | PE_TX2_DR6-DIFF1 | PAIR | 8 | 6.88 | 5 | 10 | 5 | 50 | 20 | 36 | 12 | 12 | 20 | 12 | 5.13 | 85 Ohms | TOP=L2:L3=L2/L4:L6=L5/L7:BOTTOM=L7 |
| PE_TX2_DR7_N | PE_TX2_DR7-DIFF1 | PAIR | 1 | 6.88 | 5 | 10 | 5 | 50 | 20 | 36 | 12 | 12 | 20 | 12 | 5.13 | 85 Ohms | TOP=L2:L3=L2/L4:L6=L5/L7:BOTTOM=L7 |
| PE_TX2_DR7_N | PE_TX2_DR7-DIFF1 | PAIR | 2 | 6.5 | 5 | 10 | 5 | 50 | 20 | 25 | 12 | 12 | 20 | 12 | 7.5 | 85 Ohms | TOP=L2:L3=L2/L4:L6=L5/L7:BOTTOM=L7 |
| PE_TX2_DR7_N | PE_TX2_DR7-DIFF1 | PAIR | 3 | 6.5 | 5 | 10 | 5 | 50 | 20 | 25 | 12 | 12 | 20 | 12 | 7.5 | 85 Ohms | TOP=L2:L3=L2/L4:L6=L5/L7:BOTTOM=L7 |
| PE_TX2_DR7_N | PE_TX2_DR7-DIFF1 | PAIR | 4 | 6.5 | 5 | 10 | 5 | 50 | 20 | 25 | 12 | 12 | 20 | 12 | 7.5 | 85 Ohms | TOP=L2:L3=L2/L4:L6=L5/L7:BOTTOM=L7 |
| PE_TX2_DR7_N | PE_TX2_DR7-DIFF1 | PAIR | 5 | 6.5 | 5 | 10 | 5 | 50 | 20 | 25 | 12 | 12 | 20 | 12 | 7.5 | 85 Ohms | TOP=L2:L3=L2/L4:L6=L5/L7:BOTTOM=L7 |
| PE_TX2_DR7_N | PE_TX2_DR7-DIFF1 | PAIR | 6 | 6.5 | 5 | 10 | 5 | 50 | 20 | 25 | 12 | 12 | 20 | 12 | 7.5 | 85 Ohms | TOP=L2:L3=L2/L4:L6=L5/L7:BOTTOM=L7 |
| PE_TX2_DR7_N | PE_TX2_DR7-DIFF1 | PAIR | 7 | 6.5 | 5 | 10 | 5 | 50 | 20 | 25 | 12 | 12 | 20 | 12 | 7.5 | 85 Ohms | TOP=L2:L3=L2/L4:L6=L5/L7:BOTTOM=L7 |
| PE_TX2_DR7_N | PE_TX2_DR7-DIFF1 | PAIR | 8 | 6.88 | 5 | 10 | 5 | 50 | 20 | 36 | 12 | 12 | 20 | 12 | 5.13 | 85 Ohms | TOP=L2:L3=L2/L4:L6=L5/L7:BOTTOM=L7 |
| PE_TX2_DR7_P | PE_TX2_DR7-DIFF1 | PAIR | 1 | 6.88 | 5 | 10 | 5 | 50 | 20 | 36 | 12 | 12 | 20 | 12 | 5.13 | 85 Ohms | TOP=L2:L3=L2/L4:L6=L5/L7:BOTTOM=L7 |
| PE_TX2_DR7_P | PE_TX2_DR7-DIFF1 | PAIR | 2 | 6.5 | 5 | 10 | 5 | 50 | 20 | 25 | 12 | 12 | 20 | 12 | 7.5 | 85 Ohms | TOP=L2:L3=L2/L4:L6=L5/L7:BOTTOM=L7 |
| PE_TX2_DR7_P | PE_TX2_DR7-DIFF1 | PAIR | 3 | 6.5 | 5 | 10 | 5 | 50 | 20 | 25 | 12 | 12 | 20 | 12 | 7.5 | 85 Ohms | TOP=L2:L3=L2/L4:L6=L5/L7:BOTTOM=L7 |
| PE_TX2_DR7_P | PE_TX2_DR7-DIFF1 | PAIR | 4 | 6.5 | 5 | 10 | 5 | 50 | 20 | 25 | 12 | 12 | 20 | 12 | 7.5 | 85 Ohms | TOP=L2:L3=L2/L4:L6=L5/L7:BOTTOM=L7 |
| PE_TX2_DR7_P | PE_TX2_DR7-DIFF1 | PAIR | 5 | 6.5 | 5 | 10 | 5 | 50 | 20 | 25 | 12 | 12 | 20 | 12 | 7.5 | 85 Ohms | TOP=L2:L3=L2/L4:L6=L5/L7:BOTTOM=L7 |
| PE_TX2_DR7_P | PE_TX2_DR7-DIFF1 | PAIR | 6 | 6.5 | 5 | 10 | 5 | 50 | 20 | 25 | 12 | 12 | 20 | 12 | 7.5 | 85 Ohms | TOP=L2:L3=L2/L4:L6=L5/L7:BOTTOM=L7 |
| PE_TX2_DR7_P | PE_TX2_DR7-DIFF1 | PAIR | 7 | 6.5 | 5 | 10 | 5 | 50 | 20 | 25 | 12 | 12 | 20 | 12 | 7.5 | 85 Ohms | TOP=L2:L3=L2/L4:L6=L5/L7:BOTTOM=L7 |
| PE_TX2_DR7_P | PE_TX2_DR7-DIFF1 | PAIR | 8 | 6.88 | 5 | 10 | 5 | 50 | 20 | 36 | 12 | 12 | 20 | 12 | 5.13 | 85 Ohms | TOP=L2:L3=L2/L4:L6=L5/L7:BOTTOM=L7 |
| PE_TX2_DR8_N | PE_TX2_DR8-DIFF1 | PAIR | 1 | 6.88 | 5 | 10 | 5 | 50 | 20 | 36 | 12 | 12 | 20 | 12 | 5.13 | 85 Ohms | TOP=L2:L3=L2/L4:L6=L5/L7:BOTTOM=L7 |
| PE_TX2_DR8_N | PE_TX2_DR8-DIFF1 | PAIR | 2 | 6.5 | 5 | 10 | 5 | 50 | 20 | 25 | 12 | 12 | 20 | 12 | 7.5 | 85 Ohms | TOP=L2:L3=L2/L4:L6=L5/L7:BOTTOM=L7 |
| PE_TX2_DR8_N | PE_TX2_DR8-DIFF1 | PAIR | 3 | 6.5 | 5 | 10 | 5 | 50 | 20 | 25 | 12 | 12 | 20 | 12 | 7.5 | 85 Ohms | TOP=L2:L3=L2/L4:L6=L5/L7:BOTTOM=L7 |
| PE_TX2_DR8_N | PE_TX2_DR8-DIFF1 | PAIR | 4 | 6.5 | 5 | 10 | 5 | 50 | 20 | 25 | 12 | 12 | 20 | 12 | 7.5 | 85 Ohms | TOP=L2:L3=L2/L4:L6=L5/L7:BOTTOM=L7 |
| PE_TX2_DR8_N | PE_TX2_DR8-DIFF1 | PAIR | 5 | 6.5 | 5 | 10 | 5 | 50 | 20 | 25 | 12 | 12 | 20 | 12 | 7.5 | 85 Ohms | TOP=L2:L3=L2/L4:L6=L5/L7:BOTTOM=L7 |
| PE_TX2_DR8_N | PE_TX2_DR8-DIFF1 | PAIR | 6 | 6.5 | 5 | 10 | 5 | 50 | 20 | 25 | 12 | 12 | 20 | 12 | 7.5 | 85 Ohms | TOP=L2:L3=L2/L4:L6=L5/L7:BOTTOM=L7 |
| PE_TX2_DR8_N | PE_TX2_DR8-DIFF1 | PAIR | 7 | 6.5 | 5 | 10 | 5 | 50 | 20 | 25 | 12 | 12 | 20 | 12 | 7.5 | 85 Ohms | TOP=L2:L3=L2/L4:L6=L5/L7:BOTTOM=L7 |
| PE_TX2_DR8_N | PE_TX2_DR8-DIFF1 | PAIR | 8 | 6.88 | 5 | 10 | 5 | 50 | 20 | 36 | 12 | 12 | 20 | 12 | 5.13 | 85 Ohms | TOP=L2:L3=L2/L4:L6=L5/L7:BOTTOM=L7 |
| PE_TX2_DR8_P | PE_TX2_DR8-DIFF1 | PAIR | 1 | 6.88 | 5 | 10 | 5 | 50 | 20 | 36 | 12 | 12 | 20 | 12 | 5.13 | 85 Ohms | TOP=L2:L3=L2/L4:L6=L5/L7:BOTTOM=L7 |
| PE_TX2_DR8_P | PE_TX2_DR8-DIFF1 | PAIR | 2 | 6.5 | 5 | 10 | 5 | 50 | 20 | 25 | 12 | 12 | 20 | 12 | 7.5 | 85 Ohms | TOP=L2:L3=L2/L4:L6=L5/L7:BOTTOM=L7 |
| PE_TX2_DR8_P | PE_TX2_DR8-DIFF1 | PAIR | 3 | 6.5 | 5 | 10 | 5 | 50 | 20 | 25 | 12 | 12 | 20 | 12 | 7.5 | 85 Ohms | TOP=L2:L3=L2/L4:L6=L5/L7:BOTTOM=L7 |
| PE_TX2_DR8_P | PE_TX2_DR8-DIFF1 | PAIR | 4 | 6.5 | 5 | 10 | 5 | 50 | 20 | 25 | 12 | 12 | 20 | 12 | 7.5 | 85 Ohms | TOP=L2:L3=L2/L4:L6=L5/L7:BOTTOM=L7 |
| PE_TX2_DR8_P | PE_TX2_DR8-DIFF1 | PAIR | 5 | 6.5 | 5 | 10 | 5 | 50 | 20 | 25 | 12 | 12 | 20 | 12 | 7.5 | 85 Ohms | TOP=L2:L3=L2/L4:L6=L5/L7:BOTTOM=L7 |
| PE_TX2_DR8_P | PE_TX2_DR8-DIFF1 | PAIR | 6 | 6.5 | 5 | 10 | 5 | 50 | 20 | 25 | 12 | 12 | 20 | 12 | 7.5 | 85 Ohms | TOP=L2:L3=L2/L4:L6=L5/L7:BOTTOM=L7 |
| PE_TX2_DR8_P | PE_TX2_DR8-DIFF1 | PAIR | 7 | 6.5 | 5 | 10 | 5 | 50 | 20 | 25 | 12 | 12 | 20 | 12 | 7.5 | 85 Ohms | TOP=L2:L3=L2/L4:L6=L5/L7:BOTTOM=L7 |
| PE_TX2_DR8_P | PE_TX2_DR8-DIFF1 | PAIR | 8 | 6.88 | 5 | 10 | 5 | 50 | 20 | 36 | 12 | 12 | 20 | 12 | 5.13 | 85 Ohms | TOP=L2:L3=L2/L4:L6=L5/L7:BOTTOM=L7 |
| PE_TX2_DR9_N | PE_TX2_DR9-DIFF1 | PAIR | 1 | 6.88 | 5 | 10 | 5 | 50 | 20 | 36 | 12 | 12 | 20 | 12 | 5.13 | 85 Ohms | TOP=L2:L3=L2/L4:L6=L5/L7:BOTTOM=L7 |
| PE_TX2_DR9_N | PE_TX2_DR9-DIFF1 | PAIR | 2 | 6.5 | 5 | 10 | 5 | 50 | 20 | 25 | 12 | 12 | 20 | 12 | 7.5 | 85 Ohms | TOP=L2:L3=L2/L4:L6=L5/L7:BOTTOM=L7 |
| PE_TX2_DR9_N | PE_TX2_DR9-DIFF1 | PAIR | 3 | 6.5 | 5 | 10 | 5 | 50 | 20 | 25 | 12 | 12 | 20 | 12 | 7.5 | 85 Ohms | TOP=L2:L3=L2/L4:L6=L5/L7:BOTTOM=L7 |
| PE_TX2_DR9_N | PE_TX2_DR9-DIFF1 | PAIR | 4 | 6.5 | 5 | 10 | 5 | 50 | 20 | 25 | 12 | 12 | 20 | 12 | 7.5 | 85 Ohms | TOP=L2:L3=L2/L4:L6=L5/L7:BOTTOM=L7 |
| PE_TX2_DR9_N | PE_TX2_DR9-DIFF1 | PAIR | 5 | 6.5 | 5 | 10 | 5 | 50 | 20 | 25 | 12 | 12 | 20 | 12 | 7.5 | 85 Ohms | TOP=L2:L3=L2/L4:L6=L5/L7:BOTTOM=L7 |
| PE_TX2_DR9_N | PE_TX2_DR9-DIFF1 | PAIR | 6 | 6.5 | 5 | 10 | 5 | 50 | 20 | 25 | 12 | 12 | 20 | 12 | 7.5 | 85 Ohms | TOP=L2:L3=L2/L4:L6=L5/L7:BOTTOM=L7 |
| PE_TX2_DR9_N | PE_TX2_DR9-DIFF1 | PAIR | 7 | 6.5 | 5 | 10 | 5 | 50 | 20 | 25 | 12 | 12 | 20 | 12 | 7.5 | 85 Ohms | TOP=L2:L3=L2/L4:L6=L5/L7:BOTTOM=L7 |
| PE_TX2_DR9_N | PE_TX2_DR9-DIFF1 | PAIR | 8 | 6.88 | 5 | 10 | 5 | 50 | 20 | 36 | 12 | 12 | 20 | 12 | 5.13 | 85 Ohms | TOP=L2:L3=L2/L4:L6=L5/L7:BOTTOM=L7 |
| PE_TX2_DR9_P | PE_TX2_DR9-DIFF1 | PAIR | 1 | 6.88 | 5 | 10 | 5 | 50 | 20 | 36 | 12 | 12 | 20 | 12 | 5.13 | 85 Ohms | TOP=L2:L3=L2/L4:L6=L5/L7:BOTTOM=L7 |
| PE_TX2_DR9_P | PE_TX2_DR9-DIFF1 | PAIR | 2 | 6.5 | 5 | 10 | 5 | 50 | 20 | 25 | 12 | 12 | 20 | 12 | 7.5 | 85 Ohms | TOP=L2:L3=L2/L4:L6=L5/L7:BOTTOM=L7 |
| PE_TX2_DR9_P | PE_TX2_DR9-DIFF1 | PAIR | 3 | 6.5 | 5 | 10 | 5 | 50 | 20 | 25 | 12 | 12 | 20 | 12 | 7.5 | 85 Ohms | TOP=L2:L3=L2/L4:L6=L5/L7:BOTTOM=L7 |
| PE_TX2_DR9_P | PE_TX2_DR9-DIFF1 | PAIR | 4 | 6.5 | 5 | 10 | 5 | 50 | 20 | 25 | 12 | 12 | 20 | 12 | 7.5 | 85 Ohms | TOP=L2:L3=L2/L4:L6=L5/L7:BOTTOM=L7 |
| PE_TX2_DR9_P | PE_TX2_DR9-DIFF1 | PAIR | 5 | 6.5 | 5 | 10 | 5 | 50 | 20 | 25 | 12 | 12 | 20 | 12 | 7.5 | 85 Ohms | TOP=L2:L3=L2/L4:L6=L5/L7:BOTTOM=L7 |
| PE_TX2_DR9_P | PE_TX2_DR9-DIFF1 | PAIR | 6 | 6.5 | 5 | 10 | 5 | 50 | 20 | 25 | 12 | 12 | 20 | 12 | 7.5 | 85 Ohms | TOP=L2:L3=L2/L4:L6=L5/L7:BOTTOM=L7 |
| PE_TX2_DR9_P | PE_TX2_DR9-DIFF1 | PAIR | 7 | 6.5 | 5 | 10 | 5 | 50 | 20 | 25 | 12 | 12 | 20 | 12 | 7.5 | 85 Ohms | TOP=L2:L3=L2/L4:L6=L5/L7:BOTTOM=L7 |
| PE_TX2_DR9_P | PE_TX2_DR9-DIFF1 | PAIR | 8 | 6.88 | 5 | 10 | 5 | 50 | 20 | 36 | 12 | 12 | 20 | 12 | 5.13 | 85 Ohms | TOP=L2:L3=L2/L4:L6=L5/L7:BOTTOM=L7 |
| PE_TX3_DR0_N | PE_TX3_DR0-DIFF1 | PAIR | 1 | 6.88 | 5 | 10 | 5 | 50 | 20 | 36 | 12 | 12 | 20 | 12 | 5.13 | 85 Ohms | TOP=L2:L3=L2/L4:L6=L5/L7:BOTTOM=L7 |
| PE_TX3_DR0_N | PE_TX3_DR0-DIFF1 | PAIR | 2 | 6.5 | 5 | 10 | 5 | 50 | 20 | 25 | 12 | 12 | 20 | 12 | 7.5 | 85 Ohms | TOP=L2:L3=L2/L4:L6=L5/L7:BOTTOM=L7 |
| PE_TX3_DR0_N | PE_TX3_DR0-DIFF1 | PAIR | 3 | 6.5 | 5 | 10 | 5 | 50 | 20 | 25 | 12 | 12 | 20 | 12 | 7.5 | 85 Ohms | TOP=L2:L3=L2/L4:L6=L5/L7:BOTTOM=L7 |
| PE_TX3_DR0_N | PE_TX3_DR0-DIFF1 | PAIR | 4 | 6.5 | 5 | 10 | 5 | 50 | 20 | 25 | 12 | 12 | 20 | 12 | 7.5 | 85 Ohms | TOP=L2:L3=L2/L4:L6=L5/L7:BOTTOM=L7 |
| PE_TX3_DR0_N | PE_TX3_DR0-DIFF1 | PAIR | 5 | 6.5 | 5 | 10 | 5 | 50 | 20 | 25 | 12 | 12 | 20 | 12 | 7.5 | 85 Ohms | TOP=L2:L3=L2/L4:L6=L5/L7:BOTTOM=L7 |
| PE_TX3_DR0_N | PE_TX3_DR0-DIFF1 | PAIR | 6 | 6.5 | 5 | 10 | 5 | 50 | 20 | 25 | 12 | 12 | 20 | 12 | 7.5 | 85 Ohms | TOP=L2:L3=L2/L4:L6=L5/L7:BOTTOM=L7 |
| PE_TX3_DR0_N | PE_TX3_DR0-DIFF1 | PAIR | 7 | 6.5 | 5 | 10 | 5 | 50 | 20 | 25 | 12 | 12 | 20 | 12 | 7.5 | 85 Ohms | TOP=L2:L3=L2/L4:L6=L5/L7:BOTTOM=L7 |
| PE_TX3_DR0_N | PE_TX3_DR0-DIFF1 | PAIR | 8 | 6.88 | 5 | 10 | 5 | 50 | 20 | 36 | 12 | 12 | 20 | 12 | 5.13 | 85 Ohms | TOP=L2:L3=L2/L4:L6=L5/L7:BOTTOM=L7 |
| PE_TX3_DR0_P | PE_TX3_DR0-DIFF1 | PAIR | 1 | 6.88 | 5 | 10 | 5 | 50 | 20 | 36 | 12 | 12 | 20 | 12 | 5.13 | 85 Ohms | TOP=L2:L3=L2/L4:L6=L5/L7:BOTTOM=L7 |
| PE_TX3_DR0_P | PE_TX3_DR0-DIFF1 | PAIR | 2 | 6.5 | 5 | 10 | 5 | 50 | 20 | 25 | 12 | 12 | 20 | 12 | 7.5 | 85 Ohms | TOP=L2:L3=L2/L4:L6=L5/L7:BOTTOM=L7 |
| PE_TX3_DR0_P | PE_TX3_DR0-DIFF1 | PAIR | 3 | 6.5 | 5 | 10 | 5 | 50 | 20 | 25 | 12 | 12 | 20 | 12 | 7.5 | 85 Ohms | TOP=L2:L3=L2/L4:L6=L5/L7:BOTTOM=L7 |
| PE_TX3_DR0_P | PE_TX3_DR0-DIFF1 | PAIR | 4 | 6.5 | 5 | 10 | 5 | 50 | 20 | 25 | 12 | 12 | 20 | 12 | 7.5 | 85 Ohms | TOP=L2:L3=L2/L4:L6=L5/L7:BOTTOM=L7 |
| PE_TX3_DR0_P | PE_TX3_DR0-DIFF1 | PAIR | 5 | 6.5 | 5 | 10 | 5 | 50 | 20 | 25 | 12 | 12 | 20 | 12 | 7.5 | 85 Ohms | TOP=L2:L3=L2/L4:L6=L5/L7:BOTTOM=L7 |
| PE_TX3_DR0_P | PE_TX3_DR0-DIFF1 | PAIR | 6 | 6.5 | 5 | 10 | 5 | 50 | 20 | 25 | 12 | 12 | 20 | 12 | 7.5 | 85 Ohms | TOP=L2:L3=L2/L4:L6=L5/L7:BOTTOM=L7 |
| PE_TX3_DR0_P | PE_TX3_DR0-DIFF1 | PAIR | 7 | 6.5 | 5 | 10 | 5 | 50 | 20 | 25 | 12 | 12 | 20 | 12 | 7.5 | 85 Ohms | TOP=L2:L3=L2/L4:L6=L5/L7:BOTTOM=L7 |
| PE_TX3_DR0_P | PE_TX3_DR0-DIFF1 | PAIR | 8 | 6.88 | 5 | 10 | 5 | 50 | 20 | 36 | 12 | 12 | 20 | 12 | 5.13 | 85 Ohms | TOP=L2:L3=L2/L4:L6=L5/L7:BOTTOM=L7 |
| PE_TX3_DR10_N | PE_TX3_DR10-DIFF1 | PAIR | 1 | 6.88 | 5 | 10 | 5 | 50 | 20 | 36 | 12 | 12 | 20 | 12 | 5.13 | 85 Ohms | TOP=L2:L3=L2/L4:L6=L5/L7:BOTTOM=L7 |
| PE_TX3_DR10_N | PE_TX3_DR10-DIFF1 | PAIR | 2 | 6.5 | 5 | 10 | 5 | 50 | 20 | 25 | 12 | 12 | 20 | 12 | 7.5 | 85 Ohms | TOP=L2:L3=L2/L4:L6=L5/L7:BOTTOM=L7 |
| PE_TX3_DR10_N | PE_TX3_DR10-DIFF1 | PAIR | 3 | 6.5 | 5 | 10 | 5 | 50 | 20 | 25 | 12 | 12 | 20 | 12 | 7.5 | 85 Ohms | TOP=L2:L3=L2/L4:L6=L5/L7:BOTTOM=L7 |
| PE_TX3_DR10_N | PE_TX3_DR10-DIFF1 | PAIR | 4 | 6.5 | 5 | 10 | 5 | 50 | 20 | 25 | 12 | 12 | 20 | 12 | 7.5 | 85 Ohms | TOP=L2:L3=L2/L4:L6=L5/L7:BOTTOM=L7 |
| PE_TX3_DR10_N | PE_TX3_DR10-DIFF1 | PAIR | 5 | 6.5 | 5 | 10 | 5 | 50 | 20 | 25 | 12 | 12 | 20 | 12 | 7.5 | 85 Ohms | TOP=L2:L3=L2/L4:L6=L5/L7:BOTTOM=L7 |
| PE_TX3_DR10_N | PE_TX3_DR10-DIFF1 | PAIR | 6 | 6.5 | 5 | 10 | 5 | 50 | 20 | 25 | 12 | 12 | 20 | 12 | 7.5 | 85 Ohms | TOP=L2:L3=L2/L4:L6=L5/L7:BOTTOM=L7 |
| PE_TX3_DR10_N | PE_TX3_DR10-DIFF1 | PAIR | 7 | 6.5 | 5 | 10 | 5 | 50 | 20 | 25 | 12 | 12 | 20 | 12 | 7.5 | 85 Ohms | TOP=L2:L3=L2/L4:L6=L5/L7:BOTTOM=L7 |
| PE_TX3_DR10_N | PE_TX3_DR10-DIFF1 | PAIR | 8 | 6.88 | 5 | 10 | 5 | 50 | 20 | 36 | 12 | 12 | 20 | 12 | 5.13 | 85 Ohms | TOP=L2:L3=L2/L4:L6=L5/L7:BOTTOM=L7 |
| PE_TX3_DR10_P | PE_TX3_DR10-DIFF1 | PAIR | 1 | 6.88 | 5 | 10 | 5 | 50 | 20 | 36 | 12 | 12 | 20 | 12 | 5.13 | 85 Ohms | TOP=L2:L3=L2/L4:L6=L5/L7:BOTTOM=L7 |
| PE_TX3_DR10_P | PE_TX3_DR10-DIFF1 | PAIR | 2 | 6.5 | 5 | 10 | 5 | 50 | 20 | 25 | 12 | 12 | 20 | 12 | 7.5 | 85 Ohms | TOP=L2:L3=L2/L4:L6=L5/L7:BOTTOM=L7 |
| PE_TX3_DR10_P | PE_TX3_DR10-DIFF1 | PAIR | 3 | 6.5 | 5 | 10 | 5 | 50 | 20 | 25 | 12 | 12 | 20 | 12 | 7.5 | 85 Ohms | TOP=L2:L3=L2/L4:L6=L5/L7:BOTTOM=L7 |
| PE_TX3_DR10_P | PE_TX3_DR10-DIFF1 | PAIR | 4 | 6.5 | 5 | 10 | 5 | 50 | 20 | 25 | 12 | 12 | 20 | 12 | 7.5 | 85 Ohms | TOP=L2:L3=L2/L4:L6=L5/L7:BOTTOM=L7 |
| PE_TX3_DR10_P | PE_TX3_DR10-DIFF1 | PAIR | 5 | 6.5 | 5 | 10 | 5 | 50 | 20 | 25 | 12 | 12 | 20 | 12 | 7.5 | 85 Ohms | TOP=L2:L3=L2/L4:L6=L5/L7:BOTTOM=L7 |
| PE_TX3_DR10_P | PE_TX3_DR10-DIFF1 | PAIR | 6 | 6.5 | 5 | 10 | 5 | 50 | 20 | 25 | 12 | 12 | 20 | 12 | 7.5 | 85 Ohms | TOP=L2:L3=L2/L4:L6=L5/L7:BOTTOM=L7 |
| PE_TX3_DR10_P | PE_TX3_DR10-DIFF1 | PAIR | 7 | 6.5 | 5 | 10 | 5 | 50 | 20 | 25 | 12 | 12 | 20 | 12 | 7.5 | 85 Ohms | TOP=L2:L3=L2/L4:L6=L5/L7:BOTTOM=L7 |
| PE_TX3_DR10_P | PE_TX3_DR10-DIFF1 | PAIR | 8 | 6.88 | 5 | 10 | 5 | 50 | 20 | 36 | 12 | 12 | 20 | 12 | 5.13 | 85 Ohms | TOP=L2:L3=L2/L4:L6=L5/L7:BOTTOM=L7 |
| PE_TX3_DR11_N | PE_TX3_DR11-DIFF1 | PAIR | 1 | 6.88 | 5 | 10 | 5 | 50 | 20 | 36 | 12 | 12 | 20 | 12 | 5.13 | 85 Ohms | TOP=L2:L3=L2/L4:L6=L5/L7:BOTTOM=L7 |
| PE_TX3_DR11_N | PE_TX3_DR11-DIFF1 | PAIR | 2 | 6.5 | 5 | 10 | 5 | 50 | 20 | 25 | 12 | 12 | 20 | 12 | 7.5 | 85 Ohms | TOP=L2:L3=L2/L4:L6=L5/L7:BOTTOM=L7 |
| PE_TX3_DR11_N | PE_TX3_DR11-DIFF1 | PAIR | 3 | 6.5 | 5 | 10 | 5 | 50 | 20 | 25 | 12 | 12 | 20 | 12 | 7.5 | 85 Ohms | TOP=L2:L3=L2/L4:L6=L5/L7:BOTTOM=L7 |
| PE_TX3_DR11_N | PE_TX3_DR11-DIFF1 | PAIR | 4 | 6.5 | 5 | 10 | 5 | 50 | 20 | 25 | 12 | 12 | 20 | 12 | 7.5 | 85 Ohms | TOP=L2:L3=L2/L4:L6=L5/L7:BOTTOM=L7 |
| PE_TX3_DR11_N | PE_TX3_DR11-DIFF1 | PAIR | 5 | 6.5 | 5 | 10 | 5 | 50 | 20 | 25 | 12 | 12 | 20 | 12 | 7.5 | 85 Ohms | TOP=L2:L3=L2/L4:L6=L5/L7:BOTTOM=L7 |
| PE_TX3_DR11_N | PE_TX3_DR11-DIFF1 | PAIR | 6 | 6.5 | 5 | 10 | 5 | 50 | 20 | 25 | 12 | 12 | 20 | 12 | 7.5 | 85 Ohms | TOP=L2:L3=L2/L4:L6=L5/L7:BOTTOM=L7 |
| PE_TX3_DR11_N | PE_TX3_DR11-DIFF1 | PAIR | 7 | 6.5 | 5 | 10 | 5 | 50 | 20 | 25 | 12 | 12 | 20 | 12 | 7.5 | 85 Ohms | TOP=L2:L3=L2/L4:L6=L5/L7:BOTTOM=L7 |
| PE_TX3_DR11_N | PE_TX3_DR11-DIFF1 | PAIR | 8 | 6.88 | 5 | 10 | 5 | 50 | 20 | 36 | 12 | 12 | 20 | 12 | 5.13 | 85 Ohms | TOP=L2:L3=L2/L4:L6=L5/L7:BOTTOM=L7 |
| PE_TX3_DR11_P | PE_TX3_DR11-DIFF1 | PAIR | 1 | 6.88 | 5 | 10 | 5 | 50 | 20 | 36 | 12 | 12 | 20 | 12 | 5.13 | 85 Ohms | TOP=L2:L3=L2/L4:L6=L5/L7:BOTTOM=L7 |
| PE_TX3_DR11_P | PE_TX3_DR11-DIFF1 | PAIR | 2 | 6.5 | 5 | 10 | 5 | 50 | 20 | 25 | 12 | 12 | 20 | 12 | 7.5 | 85 Ohms | TOP=L2:L3=L2/L4:L6=L5/L7:BOTTOM=L7 |
| PE_TX3_DR11_P | PE_TX3_DR11-DIFF1 | PAIR | 3 | 6.5 | 5 | 10 | 5 | 50 | 20 | 25 | 12 | 12 | 20 | 12 | 7.5 | 85 Ohms | TOP=L2:L3=L2/L4:L6=L5/L7:BOTTOM=L7 |
| PE_TX3_DR11_P | PE_TX3_DR11-DIFF1 | PAIR | 4 | 6.5 | 5 | 10 | 5 | 50 | 20 | 25 | 12 | 12 | 20 | 12 | 7.5 | 85 Ohms | TOP=L2:L3=L2/L4:L6=L5/L7:BOTTOM=L7 |
| PE_TX3_DR11_P | PE_TX3_DR11-DIFF1 | PAIR | 5 | 6.5 | 5 | 10 | 5 | 50 | 20 | 25 | 12 | 12 | 20 | 12 | 7.5 | 85 Ohms | TOP=L2:L3=L2/L4:L6=L5/L7:BOTTOM=L7 |
| PE_TX3_DR11_P | PE_TX3_DR11-DIFF1 | PAIR | 6 | 6.5 | 5 | 10 | 5 | 50 | 20 | 25 | 12 | 12 | 20 | 12 | 7.5 | 85 Ohms | TOP=L2:L3=L2/L4:L6=L5/L7:BOTTOM=L7 |
| PE_TX3_DR11_P | PE_TX3_DR11-DIFF1 | PAIR | 7 | 6.5 | 5 | 10 | 5 | 50 | 20 | 25 | 12 | 12 | 20 | 12 | 7.5 | 85 Ohms | TOP=L2:L3=L2/L4:L6=L5/L7:BOTTOM=L7 |
| PE_TX3_DR11_P | PE_TX3_DR11-DIFF1 | PAIR | 8 | 6.88 | 5 | 10 | 5 | 50 | 20 | 36 | 12 | 12 | 20 | 12 | 5.13 | 85 Ohms | TOP=L2:L3=L2/L4:L6=L5/L7:BOTTOM=L7 |
| PE_TX3_DR12_N | PE_TX3_DR12-DIFF1 | PAIR | 1 | 6.88 | 5 | 10 | 5 | 50 | 20 | 36 | 12 | 12 | 20 | 12 | 5.13 | 85 Ohms | TOP=L2:L3=L2/L4:L6=L5/L7:BOTTOM=L7 |
| PE_TX3_DR12_N | PE_TX3_DR12-DIFF1 | PAIR | 2 | 6.5 | 5 | 10 | 5 | 50 | 20 | 25 | 12 | 12 | 20 | 12 | 7.5 | 85 Ohms | TOP=L2:L3=L2/L4:L6=L5/L7:BOTTOM=L7 |
| PE_TX3_DR12_N | PE_TX3_DR12-DIFF1 | PAIR | 3 | 6.5 | 5 | 10 | 5 | 50 | 20 | 25 | 12 | 12 | 20 | 12 | 7.5 | 85 Ohms | TOP=L2:L3=L2/L4:L6=L5/L7:BOTTOM=L7 |
| PE_TX3_DR12_N | PE_TX3_DR12-DIFF1 | PAIR | 4 | 6.5 | 5 | 10 | 5 | 50 | 20 | 25 | 12 | 12 | 20 | 12 | 7.5 | 85 Ohms | TOP=L2:L3=L2/L4:L6=L5/L7:BOTTOM=L7 |
| PE_TX3_DR12_N | PE_TX3_DR12-DIFF1 | PAIR | 5 | 6.5 | 5 | 10 | 5 | 50 | 20 | 25 | 12 | 12 | 20 | 12 | 7.5 | 85 Ohms | TOP=L2:L3=L2/L4:L6=L5/L7:BOTTOM=L7 |
| PE_TX3_DR12_N | PE_TX3_DR12-DIFF1 | PAIR | 6 | 6.5 | 5 | 10 | 5 | 50 | 20 | 25 | 12 | 12 | 20 | 12 | 7.5 | 85 Ohms | TOP=L2:L3=L2/L4:L6=L5/L7:BOTTOM=L7 |
| PE_TX3_DR12_N | PE_TX3_DR12-DIFF1 | PAIR | 7 | 6.5 | 5 | 10 | 5 | 50 | 20 | 25 | 12 | 12 | 20 | 12 | 7.5 | 85 Ohms | TOP=L2:L3=L2/L4:L6=L5/L7:BOTTOM=L7 |
| PE_TX3_DR12_N | PE_TX3_DR12-DIFF1 | PAIR | 8 | 6.88 | 5 | 10 | 5 | 50 | 20 | 36 | 12 | 12 | 20 | 12 | 5.13 | 85 Ohms | TOP=L2:L3=L2/L4:L6=L5/L7:BOTTOM=L7 |
| PE_TX3_DR12_P | PE_TX3_DR12-DIFF1 | PAIR | 1 | 6.88 | 5 | 10 | 5 | 50 | 20 | 36 | 12 | 12 | 20 | 12 | 5.13 | 85 Ohms | TOP=L2:L3=L2/L4:L6=L5/L7:BOTTOM=L7 |
| PE_TX3_DR12_P | PE_TX3_DR12-DIFF1 | PAIR | 2 | 6.5 | 5 | 10 | 5 | 50 | 20 | 25 | 12 | 12 | 20 | 12 | 7.5 | 85 Ohms | TOP=L2:L3=L2/L4:L6=L5/L7:BOTTOM=L7 |
| PE_TX3_DR12_P | PE_TX3_DR12-DIFF1 | PAIR | 3 | 6.5 | 5 | 10 | 5 | 50 | 20 | 25 | 12 | 12 | 20 | 12 | 7.5 | 85 Ohms | TOP=L2:L3=L2/L4:L6=L5/L7:BOTTOM=L7 |
| PE_TX3_DR12_P | PE_TX3_DR12-DIFF1 | PAIR | 4 | 6.5 | 5 | 10 | 5 | 50 | 20 | 25 | 12 | 12 | 20 | 12 | 7.5 | 85 Ohms | TOP=L2:L3=L2/L4:L6=L5/L7:BOTTOM=L7 |
| PE_TX3_DR12_P | PE_TX3_DR12-DIFF1 | PAIR | 5 | 6.5 | 5 | 10 | 5 | 50 | 20 | 25 | 12 | 12 | 20 | 12 | 7.5 | 85 Ohms | TOP=L2:L3=L2/L4:L6=L5/L7:BOTTOM=L7 |
| PE_TX3_DR12_P | PE_TX3_DR12-DIFF1 | PAIR | 6 | 6.5 | 5 | 10 | 5 | 50 | 20 | 25 | 12 | 12 | 20 | 12 | 7.5 | 85 Ohms | TOP=L2:L3=L2/L4:L6=L5/L7:BOTTOM=L7 |
| PE_TX3_DR12_P | PE_TX3_DR12-DIFF1 | PAIR | 7 | 6.5 | 5 | 10 | 5 | 50 | 20 | 25 | 12 | 12 | 20 | 12 | 7.5 | 85 Ohms | TOP=L2:L3=L2/L4:L6=L5/L7:BOTTOM=L7 |
| PE_TX3_DR12_P | PE_TX3_DR12-DIFF1 | PAIR | 8 | 6.88 | 5 | 10 | 5 | 50 | 20 | 36 | 12 | 12 | 20 | 12 | 5.13 | 85 Ohms | TOP=L2:L3=L2/L4:L6=L5/L7:BOTTOM=L7 |
| PE_TX3_DR13_N | PE_TX3_DR13-DIFF1 | PAIR | 1 | 6.88 | 5 | 10 | 5 | 50 | 20 | 36 | 12 | 12 | 20 | 12 | 5.13 | 85 Ohms | TOP=L2:L3=L2/L4:L6=L5/L7:BOTTOM=L7 |
| PE_TX3_DR13_N | PE_TX3_DR13-DIFF1 | PAIR | 2 | 6.5 | 5 | 10 | 5 | 50 | 20 | 25 | 12 | 12 | 20 | 12 | 7.5 | 85 Ohms | TOP=L2:L3=L2/L4:L6=L5/L7:BOTTOM=L7 |
| PE_TX3_DR13_N | PE_TX3_DR13-DIFF1 | PAIR | 3 | 6.5 | 5 | 10 | 5 | 50 | 20 | 25 | 12 | 12 | 20 | 12 | 7.5 | 85 Ohms | TOP=L2:L3=L2/L4:L6=L5/L7:BOTTOM=L7 |
| PE_TX3_DR13_N | PE_TX3_DR13-DIFF1 | PAIR | 4 | 6.5 | 5 | 10 | 5 | 50 | 20 | 25 | 12 | 12 | 20 | 12 | 7.5 | 85 Ohms | TOP=L2:L3=L2/L4:L6=L5/L7:BOTTOM=L7 |
| PE_TX3_DR13_N | PE_TX3_DR13-DIFF1 | PAIR | 5 | 6.5 | 5 | 10 | 5 | 50 | 20 | 25 | 12 | 12 | 20 | 12 | 7.5 | 85 Ohms | TOP=L2:L3=L2/L4:L6=L5/L7:BOTTOM=L7 |
| PE_TX3_DR13_N | PE_TX3_DR13-DIFF1 | PAIR | 6 | 6.5 | 5 | 10 | 5 | 50 | 20 | 25 | 12 | 12 | 20 | 12 | 7.5 | 85 Ohms | TOP=L2:L3=L2/L4:L6=L5/L7:BOTTOM=L7 |
| PE_TX3_DR13_N | PE_TX3_DR13-DIFF1 | PAIR | 7 | 6.5 | 5 | 10 | 5 | 50 | 20 | 25 | 12 | 12 | 20 | 12 | 7.5 | 85 Ohms | TOP=L2:L3=L2/L4:L6=L5/L7:BOTTOM=L7 |
| PE_TX3_DR13_N | PE_TX3_DR13-DIFF1 | PAIR | 8 | 6.88 | 5 | 10 | 5 | 50 | 20 | 36 | 12 | 12 | 20 | 12 | 5.13 | 85 Ohms | TOP=L2:L3=L2/L4:L6=L5/L7:BOTTOM=L7 |
| PE_TX3_DR13_P | PE_TX3_DR13-DIFF1 | PAIR | 1 | 6.88 | 5 | 10 | 5 | 50 | 20 | 36 | 12 | 12 | 20 | 12 | 5.13 | 85 Ohms | TOP=L2:L3=L2/L4:L6=L5/L7:BOTTOM=L7 |
| PE_TX3_DR13_P | PE_TX3_DR13-DIFF1 | PAIR | 2 | 6.5 | 5 | 10 | 5 | 50 | 20 | 25 | 12 | 12 | 20 | 12 | 7.5 | 85 Ohms | TOP=L2:L3=L2/L4:L6=L5/L7:BOTTOM=L7 |
| PE_TX3_DR13_P | PE_TX3_DR13-DIFF1 | PAIR | 3 | 6.5 | 5 | 10 | 5 | 50 | 20 | 25 | 12 | 12 | 20 | 12 | 7.5 | 85 Ohms | TOP=L2:L3=L2/L4:L6=L5/L7:BOTTOM=L7 |
| PE_TX3_DR13_P | PE_TX3_DR13-DIFF1 | PAIR | 4 | 6.5 | 5 | 10 | 5 | 50 | 20 | 25 | 12 | 12 | 20 | 12 | 7.5 | 85 Ohms | TOP=L2:L3=L2/L4:L6=L5/L7:BOTTOM=L7 |
| PE_TX3_DR13_P | PE_TX3_DR13-DIFF1 | PAIR | 5 | 6.5 | 5 | 10 | 5 | 50 | 20 | 25 | 12 | 12 | 20 | 12 | 7.5 | 85 Ohms | TOP=L2:L3=L2/L4:L6=L5/L7:BOTTOM=L7 |
| PE_TX3_DR13_P | PE_TX3_DR13-DIFF1 | PAIR | 6 | 6.5 | 5 | 10 | 5 | 50 | 20 | 25 | 12 | 12 | 20 | 12 | 7.5 | 85 Ohms | TOP=L2:L3=L2/L4:L6=L5/L7:BOTTOM=L7 |
| PE_TX3_DR13_P | PE_TX3_DR13-DIFF1 | PAIR | 7 | 6.5 | 5 | 10 | 5 | 50 | 20 | 25 | 12 | 12 | 20 | 12 | 7.5 | 85 Ohms | TOP=L2:L3=L2/L4:L6=L5/L7:BOTTOM=L7 |
| PE_TX3_DR13_P | PE_TX3_DR13-DIFF1 | PAIR | 8 | 6.88 | 5 | 10 | 5 | 50 | 20 | 36 | 12 | 12 | 20 | 12 | 5.13 | 85 Ohms | TOP=L2:L3=L2/L4:L6=L5/L7:BOTTOM=L7 |
| PE_TX3_DR14_N | PE_TX3_DR14-DIFF1 | PAIR | 1 | 6.88 | 5 | 10 | 5 | 50 | 20 | 36 | 12 | 12 | 20 | 12 | 5.13 | 85 Ohms | TOP=L2:L3=L2/L4:L6=L5/L7:BOTTOM=L7 |
| PE_TX3_DR14_N | PE_TX3_DR14-DIFF1 | PAIR | 2 | 6.5 | 5 | 10 | 5 | 50 | 20 | 25 | 12 | 12 | 20 | 12 | 7.5 | 85 Ohms | TOP=L2:L3=L2/L4:L6=L5/L7:BOTTOM=L7 |
| PE_TX3_DR14_N | PE_TX3_DR14-DIFF1 | PAIR | 3 | 6.5 | 5 | 10 | 5 | 50 | 20 | 25 | 12 | 12 | 20 | 12 | 7.5 | 85 Ohms | TOP=L2:L3=L2/L4:L6=L5/L7:BOTTOM=L7 |
| PE_TX3_DR14_N | PE_TX3_DR14-DIFF1 | PAIR | 4 | 6.5 | 5 | 10 | 5 | 50 | 20 | 25 | 12 | 12 | 20 | 12 | 7.5 | 85 Ohms | TOP=L2:L3=L2/L4:L6=L5/L7:BOTTOM=L7 |
| PE_TX3_DR14_N | PE_TX3_DR14-DIFF1 | PAIR | 5 | 6.5 | 5 | 10 | 5 | 50 | 20 | 25 | 12 | 12 | 20 | 12 | 7.5 | 85 Ohms | TOP=L2:L3=L2/L4:L6=L5/L7:BOTTOM=L7 |
| PE_TX3_DR14_N | PE_TX3_DR14-DIFF1 | PAIR | 6 | 6.5 | 5 | 10 | 5 | 50 | 20 | 25 | 12 | 12 | 20 | 12 | 7.5 | 85 Ohms | TOP=L2:L3=L2/L4:L6=L5/L7:BOTTOM=L7 |
| PE_TX3_DR14_N | PE_TX3_DR14-DIFF1 | PAIR | 7 | 6.5 | 5 | 10 | 5 | 50 | 20 | 25 | 12 | 12 | 20 | 12 | 7.5 | 85 Ohms | TOP=L2:L3=L2/L4:L6=L5/L7:BOTTOM=L7 |
| PE_TX3_DR14_N | PE_TX3_DR14-DIFF1 | PAIR | 8 | 6.88 | 5 | 10 | 5 | 50 | 20 | 36 | 12 | 12 | 20 | 12 | 5.13 | 85 Ohms | TOP=L2:L3=L2/L4:L6=L5/L7:BOTTOM=L7 |
| PE_TX3_DR14_P | PE_TX3_DR14-DIFF1 | PAIR | 1 | 6.88 | 5 | 10 | 5 | 50 | 20 | 36 | 12 | 12 | 20 | 12 | 5.13 | 85 Ohms | TOP=L2:L3=L2/L4:L6=L5/L7:BOTTOM=L7 |
| PE_TX3_DR14_P | PE_TX3_DR14-DIFF1 | PAIR | 2 | 6.5 | 5 | 10 | 5 | 50 | 20 | 25 | 12 | 12 | 20 | 12 | 7.5 | 85 Ohms | TOP=L2:L3=L2/L4:L6=L5/L7:BOTTOM=L7 |
| PE_TX3_DR14_P | PE_TX3_DR14-DIFF1 | PAIR | 3 | 6.5 | 5 | 10 | 5 | 50 | 20 | 25 | 12 | 12 | 20 | 12 | 7.5 | 85 Ohms | TOP=L2:L3=L2/L4:L6=L5/L7:BOTTOM=L7 |
| PE_TX3_DR14_P | PE_TX3_DR14-DIFF1 | PAIR | 4 | 6.5 | 5 | 10 | 5 | 50 | 20 | 25 | 12 | 12 | 20 | 12 | 7.5 | 85 Ohms | TOP=L2:L3=L2/L4:L6=L5/L7:BOTTOM=L7 |
| PE_TX3_DR14_P | PE_TX3_DR14-DIFF1 | PAIR | 5 | 6.5 | 5 | 10 | 5 | 50 | 20 | 25 | 12 | 12 | 20 | 12 | 7.5 | 85 Ohms | TOP=L2:L3=L2/L4:L6=L5/L7:BOTTOM=L7 |
| PE_TX3_DR14_P | PE_TX3_DR14-DIFF1 | PAIR | 6 | 6.5 | 5 | 10 | 5 | 50 | 20 | 25 | 12 | 12 | 20 | 12 | 7.5 | 85 Ohms | TOP=L2:L3=L2/L4:L6=L5/L7:BOTTOM=L7 |
| PE_TX3_DR14_P | PE_TX3_DR14-DIFF1 | PAIR | 7 | 6.5 | 5 | 10 | 5 | 50 | 20 | 25 | 12 | 12 | 20 | 12 | 7.5 | 85 Ohms | TOP=L2:L3=L2/L4:L6=L5/L7:BOTTOM=L7 |
| PE_TX3_DR14_P | PE_TX3_DR14-DIFF1 | PAIR | 8 | 6.88 | 5 | 10 | 5 | 50 | 20 | 36 | 12 | 12 | 20 | 12 | 5.13 | 85 Ohms | TOP=L2:L3=L2/L4:L6=L5/L7:BOTTOM=L7 |
| PE_TX3_DR1_N | PE_TX3_DR1-DIFF1 | PAIR | 1 | 6.88 | 5 | 10 | 5 | 50 | 20 | 36 | 12 | 12 | 20 | 12 | 5.13 | 85 Ohms | TOP=L2:L3=L2/L4:L6=L5/L7:BOTTOM=L7 |
| PE_TX3_DR1_N | PE_TX3_DR1-DIFF1 | PAIR | 2 | 6.5 | 5 | 10 | 5 | 50 | 20 | 25 | 12 | 12 | 20 | 12 | 7.5 | 85 Ohms | TOP=L2:L3=L2/L4:L6=L5/L7:BOTTOM=L7 |
| PE_TX3_DR1_N | PE_TX3_DR1-DIFF1 | PAIR | 3 | 6.5 | 5 | 10 | 5 | 50 | 20 | 25 | 12 | 12 | 20 | 12 | 7.5 | 85 Ohms | TOP=L2:L3=L2/L4:L6=L5/L7:BOTTOM=L7 |
| PE_TX3_DR1_N | PE_TX3_DR1-DIFF1 | PAIR | 4 | 6.5 | 5 | 10 | 5 | 50 | 20 | 25 | 12 | 12 | 20 | 12 | 7.5 | 85 Ohms | TOP=L2:L3=L2/L4:L6=L5/L7:BOTTOM=L7 |
| PE_TX3_DR1_N | PE_TX3_DR1-DIFF1 | PAIR | 5 | 6.5 | 5 | 10 | 5 | 50 | 20 | 25 | 12 | 12 | 20 | 12 | 7.5 | 85 Ohms | TOP=L2:L3=L2/L4:L6=L5/L7:BOTTOM=L7 |
| PE_TX3_DR1_N | PE_TX3_DR1-DIFF1 | PAIR | 6 | 6.5 | 5 | 10 | 5 | 50 | 20 | 25 | 12 | 12 | 20 | 12 | 7.5 | 85 Ohms | TOP=L2:L3=L2/L4:L6=L5/L7:BOTTOM=L7 |
| PE_TX3_DR1_N | PE_TX3_DR1-DIFF1 | PAIR | 7 | 6.5 | 5 | 10 | 5 | 50 | 20 | 25 | 12 | 12 | 20 | 12 | 7.5 | 85 Ohms | TOP=L2:L3=L2/L4:L6=L5/L7:BOTTOM=L7 |
| PE_TX3_DR1_N | PE_TX3_DR1-DIFF1 | PAIR | 8 | 6.88 | 5 | 10 | 5 | 50 | 20 | 36 | 12 | 12 | 20 | 12 | 5.13 | 85 Ohms | TOP=L2:L3=L2/L4:L6=L5/L7:BOTTOM=L7 |
| PE_TX3_DR1_P | PE_TX3_DR1-DIFF1 | PAIR | 1 | 6.88 | 5 | 10 | 5 | 50 | 20 | 36 | 12 | 12 | 20 | 12 | 5.13 | 85 Ohms | TOP=L2:L3=L2/L4:L6=L5/L7:BOTTOM=L7 |
| PE_TX3_DR1_P | PE_TX3_DR1-DIFF1 | PAIR | 2 | 6.5 | 5 | 10 | 5 | 50 | 20 | 25 | 12 | 12 | 20 | 12 | 7.5 | 85 Ohms | TOP=L2:L3=L2/L4:L6=L5/L7:BOTTOM=L7 |
| PE_TX3_DR1_P | PE_TX3_DR1-DIFF1 | PAIR | 3 | 6.5 | 5 | 10 | 5 | 50 | 20 | 25 | 12 | 12 | 20 | 12 | 7.5 | 85 Ohms | TOP=L2:L3=L2/L4:L6=L5/L7:BOTTOM=L7 |
| PE_TX3_DR1_P | PE_TX3_DR1-DIFF1 | PAIR | 4 | 6.5 | 5 | 10 | 5 | 50 | 20 | 25 | 12 | 12 | 20 | 12 | 7.5 | 85 Ohms | TOP=L2:L3=L2/L4:L6=L5/L7:BOTTOM=L7 |
| PE_TX3_DR1_P | PE_TX3_DR1-DIFF1 | PAIR | 5 | 6.5 | 5 | 10 | 5 | 50 | 20 | 25 | 12 | 12 | 20 | 12 | 7.5 | 85 Ohms | TOP=L2:L3=L2/L4:L6=L5/L7:BOTTOM=L7 |
| PE_TX3_DR1_P | PE_TX3_DR1-DIFF1 | PAIR | 6 | 6.5 | 5 | 10 | 5 | 50 | 20 | 25 | 12 | 12 | 20 | 12 | 7.5 | 85 Ohms | TOP=L2:L3=L2/L4:L6=L5/L7:BOTTOM=L7 |
| PE_TX3_DR1_P | PE_TX3_DR1-DIFF1 | PAIR | 7 | 6.5 | 5 | 10 | 5 | 50 | 20 | 25 | 12 | 12 | 20 | 12 | 7.5 | 85 Ohms | TOP=L2:L3=L2/L4:L6=L5/L7:BOTTOM=L7 |
| PE_TX3_DR1_P | PE_TX3_DR1-DIFF1 | PAIR | 8 | 6.88 | 5 | 10 | 5 | 50 | 20 | 36 | 12 | 12 | 20 | 12 | 5.13 | 85 Ohms | TOP=L2:L3=L2/L4:L6=L5/L7:BOTTOM=L7 |
| PE_TX3_DR2_N | PE_TX3_DR2-DIFF1 | PAIR | 1 | 6.88 | 5 | 10 | 5 | 50 | 20 | 36 | 12 | 12 | 20 | 12 | 5.13 | 85 Ohms | TOP=L2:L3=L2/L4:L6=L5/L7:BOTTOM=L7 |
| PE_TX3_DR2_N | PE_TX3_DR2-DIFF1 | PAIR | 2 | 6.5 | 5 | 10 | 5 | 50 | 20 | 25 | 12 | 12 | 20 | 12 | 7.5 | 85 Ohms | TOP=L2:L3=L2/L4:L6=L5/L7:BOTTOM=L7 |
| PE_TX3_DR2_N | PE_TX3_DR2-DIFF1 | PAIR | 3 | 6.5 | 5 | 10 | 5 | 50 | 20 | 25 | 12 | 12 | 20 | 12 | 7.5 | 85 Ohms | TOP=L2:L3=L2/L4:L6=L5/L7:BOTTOM=L7 |
| PE_TX3_DR2_N | PE_TX3_DR2-DIFF1 | PAIR | 4 | 6.5 | 5 | 10 | 5 | 50 | 20 | 25 | 12 | 12 | 20 | 12 | 7.5 | 85 Ohms | TOP=L2:L3=L2/L4:L6=L5/L7:BOTTOM=L7 |
| PE_TX3_DR2_N | PE_TX3_DR2-DIFF1 | PAIR | 5 | 6.5 | 5 | 10 | 5 | 50 | 20 | 25 | 12 | 12 | 20 | 12 | 7.5 | 85 Ohms | TOP=L2:L3=L2/L4:L6=L5/L7:BOTTOM=L7 |
| PE_TX3_DR2_N | PE_TX3_DR2-DIFF1 | PAIR | 6 | 6.5 | 5 | 10 | 5 | 50 | 20 | 25 | 12 | 12 | 20 | 12 | 7.5 | 85 Ohms | TOP=L2:L3=L2/L4:L6=L5/L7:BOTTOM=L7 |
| PE_TX3_DR2_N | PE_TX3_DR2-DIFF1 | PAIR | 7 | 6.5 | 5 | 10 | 5 | 50 | 20 | 25 | 12 | 12 | 20 | 12 | 7.5 | 85 Ohms | TOP=L2:L3=L2/L4:L6=L5/L7:BOTTOM=L7 |
| PE_TX3_DR2_N | PE_TX3_DR2-DIFF1 | PAIR | 8 | 6.88 | 5 | 10 | 5 | 50 | 20 | 36 | 12 | 12 | 20 | 12 | 5.13 | 85 Ohms | TOP=L2:L3=L2/L4:L6=L5/L7:BOTTOM=L7 |
| PE_TX3_DR2_P | PE_TX3_DR2-DIFF1 | PAIR | 1 | 6.88 | 5 | 10 | 5 | 50 | 20 | 36 | 12 | 12 | 20 | 12 | 5.13 | 85 Ohms | TOP=L2:L3=L2/L4:L6=L5/L7:BOTTOM=L7 |
| PE_TX3_DR2_P | PE_TX3_DR2-DIFF1 | PAIR | 2 | 6.5 | 5 | 10 | 5 | 50 | 20 | 25 | 12 | 12 | 20 | 12 | 7.5 | 85 Ohms | TOP=L2:L3=L2/L4:L6=L5/L7:BOTTOM=L7 |
| PE_TX3_DR2_P | PE_TX3_DR2-DIFF1 | PAIR | 3 | 6.5 | 5 | 10 | 5 | 50 | 20 | 25 | 12 | 12 | 20 | 12 | 7.5 | 85 Ohms | TOP=L2:L3=L2/L4:L6=L5/L7:BOTTOM=L7 |
| PE_TX3_DR2_P | PE_TX3_DR2-DIFF1 | PAIR | 4 | 6.5 | 5 | 10 | 5 | 50 | 20 | 25 | 12 | 12 | 20 | 12 | 7.5 | 85 Ohms | TOP=L2:L3=L2/L4:L6=L5/L7:BOTTOM=L7 |
| PE_TX3_DR2_P | PE_TX3_DR2-DIFF1 | PAIR | 5 | 6.5 | 5 | 10 | 5 | 50 | 20 | 25 | 12 | 12 | 20 | 12 | 7.5 | 85 Ohms | TOP=L2:L3=L2/L4:L6=L5/L7:BOTTOM=L7 |
| PE_TX3_DR2_P | PE_TX3_DR2-DIFF1 | PAIR | 6 | 6.5 | 5 | 10 | 5 | 50 | 20 | 25 | 12 | 12 | 20 | 12 | 7.5 | 85 Ohms | TOP=L2:L3=L2/L4:L6=L5/L7:BOTTOM=L7 |
| PE_TX3_DR2_P | PE_TX3_DR2-DIFF1 | PAIR | 7 | 6.5 | 5 | 10 | 5 | 50 | 20 | 25 | 12 | 12 | 20 | 12 | 7.5 | 85 Ohms | TOP=L2:L3=L2/L4:L6=L5/L7:BOTTOM=L7 |
| PE_TX3_DR2_P | PE_TX3_DR2-DIFF1 | PAIR | 8 | 6.88 | 5 | 10 | 5 | 50 | 20 | 36 | 12 | 12 | 20 | 12 | 5.13 | 85 Ohms | TOP=L2:L3=L2/L4:L6=L5/L7:BOTTOM=L7 |
| PE_TX3_DR3_N | PE_TX3_DR3-DIFF1 | PAIR | 1 | 6.88 | 5 | 10 | 5 | 50 | 20 | 36 | 12 | 12 | 20 | 12 | 5.13 | 85 Ohms | TOP=L2:L3=L2/L4:L6=L5/L7:BOTTOM=L7 |
| PE_TX3_DR3_N | PE_TX3_DR3-DIFF1 | PAIR | 2 | 6.5 | 5 | 10 | 5 | 50 | 20 | 25 | 12 | 12 | 20 | 12 | 7.5 | 85 Ohms | TOP=L2:L3=L2/L4:L6=L5/L7:BOTTOM=L7 |
| PE_TX3_DR3_N | PE_TX3_DR3-DIFF1 | PAIR | 3 | 6.5 | 5 | 10 | 5 | 50 | 20 | 25 | 12 | 12 | 20 | 12 | 7.5 | 85 Ohms | TOP=L2:L3=L2/L4:L6=L5/L7:BOTTOM=L7 |
| PE_TX3_DR3_N | PE_TX3_DR3-DIFF1 | PAIR | 4 | 6.5 | 5 | 10 | 5 | 50 | 20 | 25 | 12 | 12 | 20 | 12 | 7.5 | 85 Ohms | TOP=L2:L3=L2/L4:L6=L5/L7:BOTTOM=L7 |
| PE_TX3_DR3_N | PE_TX3_DR3-DIFF1 | PAIR | 5 | 6.5 | 5 | 10 | 5 | 50 | 20 | 25 | 12 | 12 | 20 | 12 | 7.5 | 85 Ohms | TOP=L2:L3=L2/L4:L6=L5/L7:BOTTOM=L7 |
| PE_TX3_DR3_N | PE_TX3_DR3-DIFF1 | PAIR | 6 | 6.5 | 5 | 10 | 5 | 50 | 20 | 25 | 12 | 12 | 20 | 12 | 7.5 | 85 Ohms | TOP=L2:L3=L2/L4:L6=L5/L7:BOTTOM=L7 |
| PE_TX3_DR3_N | PE_TX3_DR3-DIFF1 | PAIR | 7 | 6.5 | 5 | 10 | 5 | 50 | 20 | 25 | 12 | 12 | 20 | 12 | 7.5 | 85 Ohms | TOP=L2:L3=L2/L4:L6=L5/L7:BOTTOM=L7 |
| PE_TX3_DR3_N | PE_TX3_DR3-DIFF1 | PAIR | 8 | 6.88 | 5 | 10 | 5 | 50 | 20 | 36 | 12 | 12 | 20 | 12 | 5.13 | 85 Ohms | TOP=L2:L3=L2/L4:L6=L5/L7:BOTTOM=L7 |
| PE_TX3_DR3_P | PE_TX3_DR3-DIFF1 | PAIR | 1 | 6.88 | 5 | 10 | 5 | 50 | 20 | 36 | 12 | 12 | 20 | 12 | 5.13 | 85 Ohms | TOP=L2:L3=L2/L4:L6=L5/L7:BOTTOM=L7 |
| PE_TX3_DR3_P | PE_TX3_DR3-DIFF1 | PAIR | 2 | 6.5 | 5 | 10 | 5 | 50 | 20 | 25 | 12 | 12 | 20 | 12 | 7.5 | 85 Ohms | TOP=L2:L3=L2/L4:L6=L5/L7:BOTTOM=L7 |
| PE_TX3_DR3_P | PE_TX3_DR3-DIFF1 | PAIR | 3 | 6.5 | 5 | 10 | 5 | 50 | 20 | 25 | 12 | 12 | 20 | 12 | 7.5 | 85 Ohms | TOP=L2:L3=L2/L4:L6=L5/L7:BOTTOM=L7 |
| PE_TX3_DR3_P | PE_TX3_DR3-DIFF1 | PAIR | 4 | 6.5 | 5 | 10 | 5 | 50 | 20 | 25 | 12 | 12 | 20 | 12 | 7.5 | 85 Ohms | TOP=L2:L3=L2/L4:L6=L5/L7:BOTTOM=L7 |
| PE_TX3_DR3_P | PE_TX3_DR3-DIFF1 | PAIR | 5 | 6.5 | 5 | 10 | 5 | 50 | 20 | 25 | 12 | 12 | 20 | 12 | 7.5 | 85 Ohms | TOP=L2:L3=L2/L4:L6=L5/L7:BOTTOM=L7 |
| PE_TX3_DR3_P | PE_TX3_DR3-DIFF1 | PAIR | 6 | 6.5 | 5 | 10 | 5 | 50 | 20 | 25 | 12 | 12 | 20 | 12 | 7.5 | 85 Ohms | TOP=L2:L3=L2/L4:L6=L5/L7:BOTTOM=L7 |
| PE_TX3_DR3_P | PE_TX3_DR3-DIFF1 | PAIR | 7 | 6.5 | 5 | 10 | 5 | 50 | 20 | 25 | 12 | 12 | 20 | 12 | 7.5 | 85 Ohms | TOP=L2:L3=L2/L4:L6=L5/L7:BOTTOM=L7 |
| PE_TX3_DR3_P | PE_TX3_DR3-DIFF1 | PAIR | 8 | 6.88 | 5 | 10 | 5 | 50 | 20 | 36 | 12 | 12 | 20 | 12 | 5.13 | 85 Ohms | TOP=L2:L3=L2/L4:L6=L5/L7:BOTTOM=L7 |
| PE_TX3_DR4_N | PE_TX3_DR4-DIFF1 | PAIR | 1 | 6.88 | 5 | 10 | 5 | 50 | 20 | 36 | 12 | 12 | 20 | 12 | 5.13 | 85 Ohms | TOP=L2:L3=L2/L4:L6=L5/L7:BOTTOM=L7 |
| PE_TX3_DR4_N | PE_TX3_DR4-DIFF1 | PAIR | 2 | 6.5 | 5 | 10 | 5 | 50 | 20 | 25 | 12 | 12 | 20 | 12 | 7.5 | 85 Ohms | TOP=L2:L3=L2/L4:L6=L5/L7:BOTTOM=L7 |
| PE_TX3_DR4_N | PE_TX3_DR4-DIFF1 | PAIR | 3 | 6.5 | 5 | 10 | 5 | 50 | 20 | 25 | 12 | 12 | 20 | 12 | 7.5 | 85 Ohms | TOP=L2:L3=L2/L4:L6=L5/L7:BOTTOM=L7 |
| PE_TX3_DR4_N | PE_TX3_DR4-DIFF1 | PAIR | 4 | 6.5 | 5 | 10 | 5 | 50 | 20 | 25 | 12 | 12 | 20 | 12 | 7.5 | 85 Ohms | TOP=L2:L3=L2/L4:L6=L5/L7:BOTTOM=L7 |
| PE_TX3_DR4_N | PE_TX3_DR4-DIFF1 | PAIR | 5 | 6.5 | 5 | 10 | 5 | 50 | 20 | 25 | 12 | 12 | 20 | 12 | 7.5 | 85 Ohms | TOP=L2:L3=L2/L4:L6=L5/L7:BOTTOM=L7 |
| PE_TX3_DR4_N | PE_TX3_DR4-DIFF1 | PAIR | 6 | 6.5 | 5 | 10 | 5 | 50 | 20 | 25 | 12 | 12 | 20 | 12 | 7.5 | 85 Ohms | TOP=L2:L3=L2/L4:L6=L5/L7:BOTTOM=L7 |
| PE_TX3_DR4_N | PE_TX3_DR4-DIFF1 | PAIR | 7 | 6.5 | 5 | 10 | 5 | 50 | 20 | 25 | 12 | 12 | 20 | 12 | 7.5 | 85 Ohms | TOP=L2:L3=L2/L4:L6=L5/L7:BOTTOM=L7 |
| PE_TX3_DR4_N | PE_TX3_DR4-DIFF1 | PAIR | 8 | 6.88 | 5 | 10 | 5 | 50 | 20 | 36 | 12 | 12 | 20 | 12 | 5.13 | 85 Ohms | TOP=L2:L3=L2/L4:L6=L5/L7:BOTTOM=L7 |
| PE_TX3_DR4_P | PE_TX3_DR4-DIFF1 | PAIR | 1 | 6.88 | 5 | 10 | 5 | 50 | 20 | 36 | 12 | 12 | 20 | 12 | 5.13 | 85 Ohms | TOP=L2:L3=L2/L4:L6=L5/L7:BOTTOM=L7 |
| PE_TX3_DR4_P | PE_TX3_DR4-DIFF1 | PAIR | 2 | 6.5 | 5 | 10 | 5 | 50 | 20 | 25 | 12 | 12 | 20 | 12 | 7.5 | 85 Ohms | TOP=L2:L3=L2/L4:L6=L5/L7:BOTTOM=L7 |
| PE_TX3_DR4_P | PE_TX3_DR4-DIFF1 | PAIR | 3 | 6.5 | 5 | 10 | 5 | 50 | 20 | 25 | 12 | 12 | 20 | 12 | 7.5 | 85 Ohms | TOP=L2:L3=L2/L4:L6=L5/L7:BOTTOM=L7 |
| PE_TX3_DR4_P | PE_TX3_DR4-DIFF1 | PAIR | 4 | 6.5 | 5 | 10 | 5 | 50 | 20 | 25 | 12 | 12 | 20 | 12 | 7.5 | 85 Ohms | TOP=L2:L3=L2/L4:L6=L5/L7:BOTTOM=L7 |
| PE_TX3_DR4_P | PE_TX3_DR4-DIFF1 | PAIR | 5 | 6.5 | 5 | 10 | 5 | 50 | 20 | 25 | 12 | 12 | 20 | 12 | 7.5 | 85 Ohms | TOP=L2:L3=L2/L4:L6=L5/L7:BOTTOM=L7 |
| PE_TX3_DR4_P | PE_TX3_DR4-DIFF1 | PAIR | 6 | 6.5 | 5 | 10 | 5 | 50 | 20 | 25 | 12 | 12 | 20 | 12 | 7.5 | 85 Ohms | TOP=L2:L3=L2/L4:L6=L5/L7:BOTTOM=L7 |
| PE_TX3_DR4_P | PE_TX3_DR4-DIFF1 | PAIR | 7 | 6.5 | 5 | 10 | 5 | 50 | 20 | 25 | 12 | 12 | 20 | 12 | 7.5 | 85 Ohms | TOP=L2:L3=L2/L4:L6=L5/L7:BOTTOM=L7 |
| PE_TX3_DR4_P | PE_TX3_DR4-DIFF1 | PAIR | 8 | 6.88 | 5 | 10 | 5 | 50 | 20 | 36 | 12 | 12 | 20 | 12 | 5.13 | 85 Ohms | TOP=L2:L3=L2/L4:L6=L5/L7:BOTTOM=L7 |
| PE_TX3_DR5_N | PE_TX3_DR5-DIFF1 | PAIR | 1 | 6.88 | 5 | 10 | 5 | 50 | 20 | 36 | 12 | 12 | 20 | 12 | 5.13 | 85 Ohms | TOP=L2:L3=L2/L4:L6=L5/L7:BOTTOM=L7 |
| PE_TX3_DR5_N | PE_TX3_DR5-DIFF1 | PAIR | 2 | 6.5 | 5 | 10 | 5 | 50 | 20 | 25 | 12 | 12 | 20 | 12 | 7.5 | 85 Ohms | TOP=L2:L3=L2/L4:L6=L5/L7:BOTTOM=L7 |
| PE_TX3_DR5_N | PE_TX3_DR5-DIFF1 | PAIR | 3 | 6.5 | 5 | 10 | 5 | 50 | 20 | 25 | 12 | 12 | 20 | 12 | 7.5 | 85 Ohms | TOP=L2:L3=L2/L4:L6=L5/L7:BOTTOM=L7 |
| PE_TX3_DR5_N | PE_TX3_DR5-DIFF1 | PAIR | 4 | 6.5 | 5 | 10 | 5 | 50 | 20 | 25 | 12 | 12 | 20 | 12 | 7.5 | 85 Ohms | TOP=L2:L3=L2/L4:L6=L5/L7:BOTTOM=L7 |
| PE_TX3_DR5_N | PE_TX3_DR5-DIFF1 | PAIR | 5 | 6.5 | 5 | 10 | 5 | 50 | 20 | 25 | 12 | 12 | 20 | 12 | 7.5 | 85 Ohms | TOP=L2:L3=L2/L4:L6=L5/L7:BOTTOM=L7 |
| PE_TX3_DR5_N | PE_TX3_DR5-DIFF1 | PAIR | 6 | 6.5 | 5 | 10 | 5 | 50 | 20 | 25 | 12 | 12 | 20 | 12 | 7.5 | 85 Ohms | TOP=L2:L3=L2/L4:L6=L5/L7:BOTTOM=L7 |
| PE_TX3_DR5_N | PE_TX3_DR5-DIFF1 | PAIR | 7 | 6.5 | 5 | 10 | 5 | 50 | 20 | 25 | 12 | 12 | 20 | 12 | 7.5 | 85 Ohms | TOP=L2:L3=L2/L4:L6=L5/L7:BOTTOM=L7 |
| PE_TX3_DR5_N | PE_TX3_DR5-DIFF1 | PAIR | 8 | 6.88 | 5 | 10 | 5 | 50 | 20 | 36 | 12 | 12 | 20 | 12 | 5.13 | 85 Ohms | TOP=L2:L3=L2/L4:L6=L5/L7:BOTTOM=L7 |
| PE_TX3_DR5_P | PE_TX3_DR5-DIFF1 | PAIR | 1 | 6.88 | 5 | 10 | 5 | 50 | 20 | 36 | 12 | 12 | 20 | 12 | 5.13 | 85 Ohms | TOP=L2:L3=L2/L4:L6=L5/L7:BOTTOM=L7 |
| PE_TX3_DR5_P | PE_TX3_DR5-DIFF1 | PAIR | 2 | 6.5 | 5 | 10 | 5 | 50 | 20 | 25 | 12 | 12 | 20 | 12 | 7.5 | 85 Ohms | TOP=L2:L3=L2/L4:L6=L5/L7:BOTTOM=L7 |
| PE_TX3_DR5_P | PE_TX3_DR5-DIFF1 | PAIR | 3 | 6.5 | 5 | 10 | 5 | 50 | 20 | 25 | 12 | 12 | 20 | 12 | 7.5 | 85 Ohms | TOP=L2:L3=L2/L4:L6=L5/L7:BOTTOM=L7 |
| PE_TX3_DR5_P | PE_TX3_DR5-DIFF1 | PAIR | 4 | 6.5 | 5 | 10 | 5 | 50 | 20 | 25 | 12 | 12 | 20 | 12 | 7.5 | 85 Ohms | TOP=L2:L3=L2/L4:L6=L5/L7:BOTTOM=L7 |
| PE_TX3_DR5_P | PE_TX3_DR5-DIFF1 | PAIR | 5 | 6.5 | 5 | 10 | 5 | 50 | 20 | 25 | 12 | 12 | 20 | 12 | 7.5 | 85 Ohms | TOP=L2:L3=L2/L4:L6=L5/L7:BOTTOM=L7 |
| PE_TX3_DR5_P | PE_TX3_DR5-DIFF1 | PAIR | 6 | 6.5 | 5 | 10 | 5 | 50 | 20 | 25 | 12 | 12 | 20 | 12 | 7.5 | 85 Ohms | TOP=L2:L3=L2/L4:L6=L5/L7:BOTTOM=L7 |
| PE_TX3_DR5_P | PE_TX3_DR5-DIFF1 | PAIR | 7 | 6.5 | 5 | 10 | 5 | 50 | 20 | 25 | 12 | 12 | 20 | 12 | 7.5 | 85 Ohms | TOP=L2:L3=L2/L4:L6=L5/L7:BOTTOM=L7 |
| PE_TX3_DR5_P | PE_TX3_DR5-DIFF1 | PAIR | 8 | 6.88 | 5 | 10 | 5 | 50 | 20 | 36 | 12 | 12 | 20 | 12 | 5.13 | 85 Ohms | TOP=L2:L3=L2/L4:L6=L5/L7:BOTTOM=L7 |
| PE_TX3_DR6_N | PE_TX3_DR6-DIFF1 | PAIR | 1 | 6.88 | 5 | 10 | 5 | 50 | 20 | 36 | 12 | 12 | 20 | 12 | 5.13 | 85 Ohms | TOP=L2:L3=L2/L4:L6=L5/L7:BOTTOM=L7 |
| PE_TX3_DR6_N | PE_TX3_DR6-DIFF1 | PAIR | 2 | 6.5 | 5 | 10 | 5 | 50 | 20 | 25 | 12 | 12 | 20 | 12 | 7.5 | 85 Ohms | TOP=L2:L3=L2/L4:L6=L5/L7:BOTTOM=L7 |
| PE_TX3_DR6_N | PE_TX3_DR6-DIFF1 | PAIR | 3 | 6.5 | 5 | 10 | 5 | 50 | 20 | 25 | 12 | 12 | 20 | 12 | 7.5 | 85 Ohms | TOP=L2:L3=L2/L4:L6=L5/L7:BOTTOM=L7 |
| PE_TX3_DR6_N | PE_TX3_DR6-DIFF1 | PAIR | 4 | 6.5 | 5 | 10 | 5 | 50 | 20 | 25 | 12 | 12 | 20 | 12 | 7.5 | 85 Ohms | TOP=L2:L3=L2/L4:L6=L5/L7:BOTTOM=L7 |
| PE_TX3_DR6_N | PE_TX3_DR6-DIFF1 | PAIR | 5 | 6.5 | 5 | 10 | 5 | 50 | 20 | 25 | 12 | 12 | 20 | 12 | 7.5 | 85 Ohms | TOP=L2:L3=L2/L4:L6=L5/L7:BOTTOM=L7 |
| PE_TX3_DR6_N | PE_TX3_DR6-DIFF1 | PAIR | 6 | 6.5 | 5 | 10 | 5 | 50 | 20 | 25 | 12 | 12 | 20 | 12 | 7.5 | 85 Ohms | TOP=L2:L3=L2/L4:L6=L5/L7:BOTTOM=L7 |
| PE_TX3_DR6_N | PE_TX3_DR6-DIFF1 | PAIR | 7 | 6.5 | 5 | 10 | 5 | 50 | 20 | 25 | 12 | 12 | 20 | 12 | 7.5 | 85 Ohms | TOP=L2:L3=L2/L4:L6=L5/L7:BOTTOM=L7 |
| PE_TX3_DR6_N | PE_TX3_DR6-DIFF1 | PAIR | 8 | 6.88 | 5 | 10 | 5 | 50 | 20 | 36 | 12 | 12 | 20 | 12 | 5.13 | 85 Ohms | TOP=L2:L3=L2/L4:L6=L5/L7:BOTTOM=L7 |
| PE_TX3_DR6_P | PE_TX3_DR6-DIFF1 | PAIR | 1 | 6.88 | 5 | 10 | 5 | 50 | 20 | 36 | 12 | 12 | 20 | 12 | 5.13 | 85 Ohms | TOP=L2:L3=L2/L4:L6=L5/L7:BOTTOM=L7 |
| PE_TX3_DR6_P | PE_TX3_DR6-DIFF1 | PAIR | 2 | 6.5 | 5 | 10 | 5 | 50 | 20 | 25 | 12 | 12 | 20 | 12 | 7.5 | 85 Ohms | TOP=L2:L3=L2/L4:L6=L5/L7:BOTTOM=L7 |
| PE_TX3_DR6_P | PE_TX3_DR6-DIFF1 | PAIR | 3 | 6.5 | 5 | 10 | 5 | 50 | 20 | 25 | 12 | 12 | 20 | 12 | 7.5 | 85 Ohms | TOP=L2:L3=L2/L4:L6=L5/L7:BOTTOM=L7 |
| PE_TX3_DR6_P | PE_TX3_DR6-DIFF1 | PAIR | 4 | 6.5 | 5 | 10 | 5 | 50 | 20 | 25 | 12 | 12 | 20 | 12 | 7.5 | 85 Ohms | TOP=L2:L3=L2/L4:L6=L5/L7:BOTTOM=L7 |
| PE_TX3_DR6_P | PE_TX3_DR6-DIFF1 | PAIR | 5 | 6.5 | 5 | 10 | 5 | 50 | 20 | 25 | 12 | 12 | 20 | 12 | 7.5 | 85 Ohms | TOP=L2:L3=L2/L4:L6=L5/L7:BOTTOM=L7 |
| PE_TX3_DR6_P | PE_TX3_DR6-DIFF1 | PAIR | 6 | 6.5 | 5 | 10 | 5 | 50 | 20 | 25 | 12 | 12 | 20 | 12 | 7.5 | 85 Ohms | TOP=L2:L3=L2/L4:L6=L5/L7:BOTTOM=L7 |
| PE_TX3_DR6_P | PE_TX3_DR6-DIFF1 | PAIR | 7 | 6.5 | 5 | 10 | 5 | 50 | 20 | 25 | 12 | 12 | 20 | 12 | 7.5 | 85 Ohms | TOP=L2:L3=L2/L4:L6=L5/L7:BOTTOM=L7 |
| PE_TX3_DR6_P | PE_TX3_DR6-DIFF1 | PAIR | 8 | 6.88 | 5 | 10 | 5 | 50 | 20 | 36 | 12 | 12 | 20 | 12 | 5.13 | 85 Ohms | TOP=L2:L3=L2/L4:L6=L5/L7:BOTTOM=L7 |
| PE_TX3_DR7_N | PE_TX3_DR7-DIFF1 | PAIR | 1 | 6.88 | 5 | 10 | 5 | 50 | 20 | 36 | 12 | 12 | 20 | 12 | 5.13 | 85 Ohms | TOP=L2:L3=L2/L4:L6=L5/L7:BOTTOM=L7 |
| PE_TX3_DR7_N | PE_TX3_DR7-DIFF1 | PAIR | 2 | 6.5 | 5 | 10 | 5 | 50 | 20 | 25 | 12 | 12 | 20 | 12 | 7.5 | 85 Ohms | TOP=L2:L3=L2/L4:L6=L5/L7:BOTTOM=L7 |
| PE_TX3_DR7_N | PE_TX3_DR7-DIFF1 | PAIR | 3 | 6.5 | 5 | 10 | 5 | 50 | 20 | 25 | 12 | 12 | 20 | 12 | 7.5 | 85 Ohms | TOP=L2:L3=L2/L4:L6=L5/L7:BOTTOM=L7 |
| PE_TX3_DR7_N | PE_TX3_DR7-DIFF1 | PAIR | 4 | 6.5 | 5 | 10 | 5 | 50 | 20 | 25 | 12 | 12 | 20 | 12 | 7.5 | 85 Ohms | TOP=L2:L3=L2/L4:L6=L5/L7:BOTTOM=L7 |
| PE_TX3_DR7_N | PE_TX3_DR7-DIFF1 | PAIR | 5 | 6.5 | 5 | 10 | 5 | 50 | 20 | 25 | 12 | 12 | 20 | 12 | 7.5 | 85 Ohms | TOP=L2:L3=L2/L4:L6=L5/L7:BOTTOM=L7 |
| PE_TX3_DR7_N | PE_TX3_DR7-DIFF1 | PAIR | 6 | 6.5 | 5 | 10 | 5 | 50 | 20 | 25 | 12 | 12 | 20 | 12 | 7.5 | 85 Ohms | TOP=L2:L3=L2/L4:L6=L5/L7:BOTTOM=L7 |
| PE_TX3_DR7_N | PE_TX3_DR7-DIFF1 | PAIR | 7 | 6.5 | 5 | 10 | 5 | 50 | 20 | 25 | 12 | 12 | 20 | 12 | 7.5 | 85 Ohms | TOP=L2:L3=L2/L4:L6=L5/L7:BOTTOM=L7 |
| PE_TX3_DR7_N | PE_TX3_DR7-DIFF1 | PAIR | 8 | 6.88 | 5 | 10 | 5 | 50 | 20 | 36 | 12 | 12 | 20 | 12 | 5.13 | 85 Ohms | TOP=L2:L3=L2/L4:L6=L5/L7:BOTTOM=L7 |
| PE_TX3_DR7_P | PE_TX3_DR7-DIFF1 | PAIR | 1 | 6.88 | 5 | 10 | 5 | 50 | 20 | 36 | 12 | 12 | 20 | 12 | 5.13 | 85 Ohms | TOP=L2:L3=L2/L4:L6=L5/L7:BOTTOM=L7 |
| PE_TX3_DR7_P | PE_TX3_DR7-DIFF1 | PAIR | 2 | 6.5 | 5 | 10 | 5 | 50 | 20 | 25 | 12 | 12 | 20 | 12 | 7.5 | 85 Ohms | TOP=L2:L3=L2/L4:L6=L5/L7:BOTTOM=L7 |
| PE_TX3_DR7_P | PE_TX3_DR7-DIFF1 | PAIR | 3 | 6.5 | 5 | 10 | 5 | 50 | 20 | 25 | 12 | 12 | 20 | 12 | 7.5 | 85 Ohms | TOP=L2:L3=L2/L4:L6=L5/L7:BOTTOM=L7 |
| PE_TX3_DR7_P | PE_TX3_DR7-DIFF1 | PAIR | 4 | 6.5 | 5 | 10 | 5 | 50 | 20 | 25 | 12 | 12 | 20 | 12 | 7.5 | 85 Ohms | TOP=L2:L3=L2/L4:L6=L5/L7:BOTTOM=L7 |
| PE_TX3_DR7_P | PE_TX3_DR7-DIFF1 | PAIR | 5 | 6.5 | 5 | 10 | 5 | 50 | 20 | 25 | 12 | 12 | 20 | 12 | 7.5 | 85 Ohms | TOP=L2:L3=L2/L4:L6=L5/L7:BOTTOM=L7 |
| PE_TX3_DR7_P | PE_TX3_DR7-DIFF1 | PAIR | 6 | 6.5 | 5 | 10 | 5 | 50 | 20 | 25 | 12 | 12 | 20 | 12 | 7.5 | 85 Ohms | TOP=L2:L3=L2/L4:L6=L5/L7:BOTTOM=L7 |
| PE_TX3_DR7_P | PE_TX3_DR7-DIFF1 | PAIR | 7 | 6.5 | 5 | 10 | 5 | 50 | 20 | 25 | 12 | 12 | 20 | 12 | 7.5 | 85 Ohms | TOP=L2:L3=L2/L4:L6=L5/L7:BOTTOM=L7 |
| PE_TX3_DR7_P | PE_TX3_DR7-DIFF1 | PAIR | 8 | 6.88 | 5 | 10 | 5 | 50 | 20 | 36 | 12 | 12 | 20 | 12 | 5.13 | 85 Ohms | TOP=L2:L3=L2/L4:L6=L5/L7:BOTTOM=L7 |
| PE_TX3_DR8_N | PE_TX3_DR8-DIFF1 | PAIR | 1 | 6.88 | 5 | 10 | 5 | 50 | 20 | 36 | 12 | 12 | 20 | 12 | 5.13 | 85 Ohms | TOP=L2:L3=L2/L4:L6=L5/L7:BOTTOM=L7 |
| PE_TX3_DR8_N | PE_TX3_DR8-DIFF1 | PAIR | 2 | 6.5 | 5 | 10 | 5 | 50 | 20 | 25 | 12 | 12 | 20 | 12 | 7.5 | 85 Ohms | TOP=L2:L3=L2/L4:L6=L5/L7:BOTTOM=L7 |
| PE_TX3_DR8_N | PE_TX3_DR8-DIFF1 | PAIR | 3 | 6.5 | 5 | 10 | 5 | 50 | 20 | 25 | 12 | 12 | 20 | 12 | 7.5 | 85 Ohms | TOP=L2:L3=L2/L4:L6=L5/L7:BOTTOM=L7 |
| PE_TX3_DR8_N | PE_TX3_DR8-DIFF1 | PAIR | 4 | 6.5 | 5 | 10 | 5 | 50 | 20 | 25 | 12 | 12 | 20 | 12 | 7.5 | 85 Ohms | TOP=L2:L3=L2/L4:L6=L5/L7:BOTTOM=L7 |
| PE_TX3_DR8_N | PE_TX3_DR8-DIFF1 | PAIR | 5 | 6.5 | 5 | 10 | 5 | 50 | 20 | 25 | 12 | 12 | 20 | 12 | 7.5 | 85 Ohms | TOP=L2:L3=L2/L4:L6=L5/L7:BOTTOM=L7 |
| PE_TX3_DR8_N | PE_TX3_DR8-DIFF1 | PAIR | 6 | 6.5 | 5 | 10 | 5 | 50 | 20 | 25 | 12 | 12 | 20 | 12 | 7.5 | 85 Ohms | TOP=L2:L3=L2/L4:L6=L5/L7:BOTTOM=L7 |
| PE_TX3_DR8_N | PE_TX3_DR8-DIFF1 | PAIR | 7 | 6.5 | 5 | 10 | 5 | 50 | 20 | 25 | 12 | 12 | 20 | 12 | 7.5 | 85 Ohms | TOP=L2:L3=L2/L4:L6=L5/L7:BOTTOM=L7 |
| PE_TX3_DR8_N | PE_TX3_DR8-DIFF1 | PAIR | 8 | 6.88 | 5 | 10 | 5 | 50 | 20 | 36 | 12 | 12 | 20 | 12 | 5.13 | 85 Ohms | TOP=L2:L3=L2/L4:L6=L5/L7:BOTTOM=L7 |
| PE_TX3_DR8_P | PE_TX3_DR8-DIFF1 | PAIR | 1 | 6.88 | 5 | 10 | 5 | 50 | 20 | 36 | 12 | 12 | 20 | 12 | 5.13 | 85 Ohms | TOP=L2:L3=L2/L4:L6=L5/L7:BOTTOM=L7 |
| PE_TX3_DR8_P | PE_TX3_DR8-DIFF1 | PAIR | 2 | 6.5 | 5 | 10 | 5 | 50 | 20 | 25 | 12 | 12 | 20 | 12 | 7.5 | 85 Ohms | TOP=L2:L3=L2/L4:L6=L5/L7:BOTTOM=L7 |
| PE_TX3_DR8_P | PE_TX3_DR8-DIFF1 | PAIR | 3 | 6.5 | 5 | 10 | 5 | 50 | 20 | 25 | 12 | 12 | 20 | 12 | 7.5 | 85 Ohms | TOP=L2:L3=L2/L4:L6=L5/L7:BOTTOM=L7 |
| PE_TX3_DR8_P | PE_TX3_DR8-DIFF1 | PAIR | 4 | 6.5 | 5 | 10 | 5 | 50 | 20 | 25 | 12 | 12 | 20 | 12 | 7.5 | 85 Ohms | TOP=L2:L3=L2/L4:L6=L5/L7:BOTTOM=L7 |
| PE_TX3_DR8_P | PE_TX3_DR8-DIFF1 | PAIR | 5 | 6.5 | 5 | 10 | 5 | 50 | 20 | 25 | 12 | 12 | 20 | 12 | 7.5 | 85 Ohms | TOP=L2:L3=L2/L4:L6=L5/L7:BOTTOM=L7 |
| PE_TX3_DR8_P | PE_TX3_DR8-DIFF1 | PAIR | 6 | 6.5 | 5 | 10 | 5 | 50 | 20 | 25 | 12 | 12 | 20 | 12 | 7.5 | 85 Ohms | TOP=L2:L3=L2/L4:L6=L5/L7:BOTTOM=L7 |
| PE_TX3_DR8_P | PE_TX3_DR8-DIFF1 | PAIR | 7 | 6.5 | 5 | 10 | 5 | 50 | 20 | 25 | 12 | 12 | 20 | 12 | 7.5 | 85 Ohms | TOP=L2:L3=L2/L4:L6=L5/L7:BOTTOM=L7 |
| PE_TX3_DR8_P | PE_TX3_DR8-DIFF1 | PAIR | 8 | 6.88 | 5 | 10 | 5 | 50 | 20 | 36 | 12 | 12 | 20 | 12 | 5.13 | 85 Ohms | TOP=L2:L3=L2/L4:L6=L5/L7:BOTTOM=L7 |
| PE_TX3_DR9_N | PE_TX3_DR9-DIFF1 | PAIR | 1 | 6.88 | 5 | 10 | 5 | 50 | 20 | 36 | 12 | 12 | 20 | 12 | 5.13 | 85 Ohms | TOP=L2:L3=L2/L4:L6=L5/L7:BOTTOM=L7 |
| PE_TX3_DR9_N | PE_TX3_DR9-DIFF1 | PAIR | 2 | 6.5 | 5 | 10 | 5 | 50 | 20 | 25 | 12 | 12 | 20 | 12 | 7.5 | 85 Ohms | TOP=L2:L3=L2/L4:L6=L5/L7:BOTTOM=L7 |
| PE_TX3_DR9_N | PE_TX3_DR9-DIFF1 | PAIR | 3 | 6.5 | 5 | 10 | 5 | 50 | 20 | 25 | 12 | 12 | 20 | 12 | 7.5 | 85 Ohms | TOP=L2:L3=L2/L4:L6=L5/L7:BOTTOM=L7 |
| PE_TX3_DR9_N | PE_TX3_DR9-DIFF1 | PAIR | 4 | 6.5 | 5 | 10 | 5 | 50 | 20 | 25 | 12 | 12 | 20 | 12 | 7.5 | 85 Ohms | TOP=L2:L3=L2/L4:L6=L5/L7:BOTTOM=L7 |
| PE_TX3_DR9_N | PE_TX3_DR9-DIFF1 | PAIR | 5 | 6.5 | 5 | 10 | 5 | 50 | 20 | 25 | 12 | 12 | 20 | 12 | 7.5 | 85 Ohms | TOP=L2:L3=L2/L4:L6=L5/L7:BOTTOM=L7 |
| PE_TX3_DR9_N | PE_TX3_DR9-DIFF1 | PAIR | 6 | 6.5 | 5 | 10 | 5 | 50 | 20 | 25 | 12 | 12 | 20 | 12 | 7.5 | 85 Ohms | TOP=L2:L3=L2/L4:L6=L5/L7:BOTTOM=L7 |
| PE_TX3_DR9_N | PE_TX3_DR9-DIFF1 | PAIR | 7 | 6.5 | 5 | 10 | 5 | 50 | 20 | 25 | 12 | 12 | 20 | 12 | 7.5 | 85 Ohms | TOP=L2:L3=L2/L4:L6=L5/L7:BOTTOM=L7 |
| PE_TX3_DR9_N | PE_TX3_DR9-DIFF1 | PAIR | 8 | 6.88 | 5 | 10 | 5 | 50 | 20 | 36 | 12 | 12 | 20 | 12 | 5.13 | 85 Ohms | TOP=L2:L3=L2/L4:L6=L5/L7:BOTTOM=L7 |
| PE_TX3_DR9_P | PE_TX3_DR9-DIFF1 | PAIR | 1 | 6.88 | 5 | 10 | 5 | 50 | 20 | 36 | 12 | 12 | 20 | 12 | 5.13 | 85 Ohms | TOP=L2:L3=L2/L4:L6=L5/L7:BOTTOM=L7 |
| PE_TX3_DR9_P | PE_TX3_DR9-DIFF1 | PAIR | 2 | 6.5 | 5 | 10 | 5 | 50 | 20 | 25 | 12 | 12 | 20 | 12 | 7.5 | 85 Ohms | TOP=L2:L3=L2/L4:L6=L5/L7:BOTTOM=L7 |
| PE_TX3_DR9_P | PE_TX3_DR9-DIFF1 | PAIR | 3 | 6.5 | 5 | 10 | 5 | 50 | 20 | 25 | 12 | 12 | 20 | 12 | 7.5 | 85 Ohms | TOP=L2:L3=L2/L4:L6=L5/L7:BOTTOM=L7 |
| PE_TX3_DR9_P | PE_TX3_DR9-DIFF1 | PAIR | 4 | 6.5 | 5 | 10 | 5 | 50 | 20 | 25 | 12 | 12 | 20 | 12 | 7.5 | 85 Ohms | TOP=L2:L3=L2/L4:L6=L5/L7:BOTTOM=L7 |
| PE_TX3_DR9_P | PE_TX3_DR9-DIFF1 | PAIR | 5 | 6.5 | 5 | 10 | 5 | 50 | 20 | 25 | 12 | 12 | 20 | 12 | 7.5 | 85 Ohms | TOP=L2:L3=L2/L4:L6=L5/L7:BOTTOM=L7 |
| PE_TX3_DR9_P | PE_TX3_DR9-DIFF1 | PAIR | 6 | 6.5 | 5 | 10 | 5 | 50 | 20 | 25 | 12 | 12 | 20 | 12 | 7.5 | 85 Ohms | TOP=L2:L3=L2/L4:L6=L5/L7:BOTTOM=L7 |
| PE_TX3_DR9_P | PE_TX3_DR9-DIFF1 | PAIR | 7 | 6.5 | 5 | 10 | 5 | 50 | 20 | 25 | 12 | 12 | 20 | 12 | 7.5 | 85 Ohms | TOP=L2:L3=L2/L4:L6=L5/L7:BOTTOM=L7 |
| PE_TX3_DR9_P | PE_TX3_DR9-DIFF1 | PAIR | 8 | 6.88 | 5 | 10 | 5 | 50 | 20 | 36 | 12 | 12 | 20 | 12 | 5.13 | 85 Ohms | TOP=L2:L3=L2/L4:L6=L5/L7:BOTTOM=L7 |
| PE_TX4_DR0_N | PE_TX4_DR0-DIFF1 | PAIR | 1 | 6.88 | 5 | 10 | 5 | 50 | 20 | 36 | 12 | 12 | 20 | 12 | 5.13 | 85 Ohms | TOP=L2:L3=L2/L4:L6=L5/L7:BOTTOM=L7 |
| PE_TX4_DR0_N | PE_TX4_DR0-DIFF1 | PAIR | 2 | 6.5 | 5 | 10 | 5 | 50 | 20 | 25 | 12 | 12 | 20 | 12 | 7.5 | 85 Ohms | TOP=L2:L3=L2/L4:L6=L5/L7:BOTTOM=L7 |
| PE_TX4_DR0_N | PE_TX4_DR0-DIFF1 | PAIR | 3 | 6.5 | 5 | 10 | 5 | 50 | 20 | 25 | 12 | 12 | 20 | 12 | 7.5 | 85 Ohms | TOP=L2:L3=L2/L4:L6=L5/L7:BOTTOM=L7 |
| PE_TX4_DR0_N | PE_TX4_DR0-DIFF1 | PAIR | 4 | 6.5 | 5 | 10 | 5 | 50 | 20 | 25 | 12 | 12 | 20 | 12 | 7.5 | 85 Ohms | TOP=L2:L3=L2/L4:L6=L5/L7:BOTTOM=L7 |
| PE_TX4_DR0_N | PE_TX4_DR0-DIFF1 | PAIR | 5 | 6.5 | 5 | 10 | 5 | 50 | 20 | 25 | 12 | 12 | 20 | 12 | 7.5 | 85 Ohms | TOP=L2:L3=L2/L4:L6=L5/L7:BOTTOM=L7 |
| PE_TX4_DR0_N | PE_TX4_DR0-DIFF1 | PAIR | 6 | 6.5 | 5 | 10 | 5 | 50 | 20 | 25 | 12 | 12 | 20 | 12 | 7.5 | 85 Ohms | TOP=L2:L3=L2/L4:L6=L5/L7:BOTTOM=L7 |
| PE_TX4_DR0_N | PE_TX4_DR0-DIFF1 | PAIR | 7 | 6.5 | 5 | 10 | 5 | 50 | 20 | 25 | 12 | 12 | 20 | 12 | 7.5 | 85 Ohms | TOP=L2:L3=L2/L4:L6=L5/L7:BOTTOM=L7 |
| PE_TX4_DR0_N | PE_TX4_DR0-DIFF1 | PAIR | 8 | 6.88 | 5 | 10 | 5 | 50 | 20 | 36 | 12 | 12 | 20 | 12 | 5.13 | 85 Ohms | TOP=L2:L3=L2/L4:L6=L5/L7:BOTTOM=L7 |
| PE_TX4_DR0_P | PE_TX4_DR0-DIFF1 | PAIR | 1 | 6.88 | 5 | 10 | 5 | 50 | 20 | 36 | 12 | 12 | 20 | 12 | 5.13 | 85 Ohms | TOP=L2:L3=L2/L4:L6=L5/L7:BOTTOM=L7 |
| PE_TX4_DR0_P | PE_TX4_DR0-DIFF1 | PAIR | 2 | 6.5 | 5 | 10 | 5 | 50 | 20 | 25 | 12 | 12 | 20 | 12 | 7.5 | 85 Ohms | TOP=L2:L3=L2/L4:L6=L5/L7:BOTTOM=L7 |
| PE_TX4_DR0_P | PE_TX4_DR0-DIFF1 | PAIR | 3 | 6.5 | 5 | 10 | 5 | 50 | 20 | 25 | 12 | 12 | 20 | 12 | 7.5 | 85 Ohms | TOP=L2:L3=L2/L4:L6=L5/L7:BOTTOM=L7 |
| PE_TX4_DR0_P | PE_TX4_DR0-DIFF1 | PAIR | 4 | 6.5 | 5 | 10 | 5 | 50 | 20 | 25 | 12 | 12 | 20 | 12 | 7.5 | 85 Ohms | TOP=L2:L3=L2/L4:L6=L5/L7:BOTTOM=L7 |
| PE_TX4_DR0_P | PE_TX4_DR0-DIFF1 | PAIR | 5 | 6.5 | 5 | 10 | 5 | 50 | 20 | 25 | 12 | 12 | 20 | 12 | 7.5 | 85 Ohms | TOP=L2:L3=L2/L4:L6=L5/L7:BOTTOM=L7 |
| PE_TX4_DR0_P | PE_TX4_DR0-DIFF1 | PAIR | 6 | 6.5 | 5 | 10 | 5 | 50 | 20 | 25 | 12 | 12 | 20 | 12 | 7.5 | 85 Ohms | TOP=L2:L3=L2/L4:L6=L5/L7:BOTTOM=L7 |
| PE_TX4_DR0_P | PE_TX4_DR0-DIFF1 | PAIR | 7 | 6.5 | 5 | 10 | 5 | 50 | 20 | 25 | 12 | 12 | 20 | 12 | 7.5 | 85 Ohms | TOP=L2:L3=L2/L4:L6=L5/L7:BOTTOM=L7 |
| PE_TX4_DR0_P | PE_TX4_DR0-DIFF1 | PAIR | 8 | 6.88 | 5 | 10 | 5 | 50 | 20 | 36 | 12 | 12 | 20 | 12 | 5.13 | 85 Ohms | TOP=L2:L3=L2/L4:L6=L5/L7:BOTTOM=L7 |
| PE_TX4_DR10_N | PE_TX4_DR10-DIFF1 | PAIR | 1 | 6.88 | 5 | 10 | 5 | 50 | 20 | 36 | 12 | 12 | 20 | 12 | 5.13 | 85 Ohms | TOP=L2:L3=L2/L4:L6=L5/L7:BOTTOM=L7 |
| PE_TX4_DR10_N | PE_TX4_DR10-DIFF1 | PAIR | 2 | 6.5 | 5 | 10 | 5 | 50 | 20 | 25 | 12 | 12 | 20 | 12 | 7.5 | 85 Ohms | TOP=L2:L3=L2/L4:L6=L5/L7:BOTTOM=L7 |
| PE_TX4_DR10_N | PE_TX4_DR10-DIFF1 | PAIR | 3 | 6.5 | 5 | 10 | 5 | 50 | 20 | 25 | 12 | 12 | 20 | 12 | 7.5 | 85 Ohms | TOP=L2:L3=L2/L4:L6=L5/L7:BOTTOM=L7 |
| PE_TX4_DR10_N | PE_TX4_DR10-DIFF1 | PAIR | 4 | 6.5 | 5 | 10 | 5 | 50 | 20 | 25 | 12 | 12 | 20 | 12 | 7.5 | 85 Ohms | TOP=L2:L3=L2/L4:L6=L5/L7:BOTTOM=L7 |
| PE_TX4_DR10_N | PE_TX4_DR10-DIFF1 | PAIR | 5 | 6.5 | 5 | 10 | 5 | 50 | 20 | 25 | 12 | 12 | 20 | 12 | 7.5 | 85 Ohms | TOP=L2:L3=L2/L4:L6=L5/L7:BOTTOM=L7 |
| PE_TX4_DR10_N | PE_TX4_DR10-DIFF1 | PAIR | 6 | 6.5 | 5 | 10 | 5 | 50 | 20 | 25 | 12 | 12 | 20 | 12 | 7.5 | 85 Ohms | TOP=L2:L3=L2/L4:L6=L5/L7:BOTTOM=L7 |
| PE_TX4_DR10_N | PE_TX4_DR10-DIFF1 | PAIR | 7 | 6.5 | 5 | 10 | 5 | 50 | 20 | 25 | 12 | 12 | 20 | 12 | 7.5 | 85 Ohms | TOP=L2:L3=L2/L4:L6=L5/L7:BOTTOM=L7 |
| PE_TX4_DR10_N | PE_TX4_DR10-DIFF1 | PAIR | 8 | 6.88 | 5 | 10 | 5 | 50 | 20 | 36 | 12 | 12 | 20 | 12 | 5.13 | 85 Ohms | TOP=L2:L3=L2/L4:L6=L5/L7:BOTTOM=L7 |
| PE_TX4_DR10_P | PE_TX4_DR10-DIFF1 | PAIR | 1 | 6.88 | 5 | 10 | 5 | 50 | 20 | 36 | 12 | 12 | 20 | 12 | 5.13 | 85 Ohms | TOP=L2:L3=L2/L4:L6=L5/L7:BOTTOM=L7 |
| PE_TX4_DR10_P | PE_TX4_DR10-DIFF1 | PAIR | 2 | 6.5 | 5 | 10 | 5 | 50 | 20 | 25 | 12 | 12 | 20 | 12 | 7.5 | 85 Ohms | TOP=L2:L3=L2/L4:L6=L5/L7:BOTTOM=L7 |
| PE_TX4_DR10_P | PE_TX4_DR10-DIFF1 | PAIR | 3 | 6.5 | 5 | 10 | 5 | 50 | 20 | 25 | 12 | 12 | 20 | 12 | 7.5 | 85 Ohms | TOP=L2:L3=L2/L4:L6=L5/L7:BOTTOM=L7 |
| PE_TX4_DR10_P | PE_TX4_DR10-DIFF1 | PAIR | 4 | 6.5 | 5 | 10 | 5 | 50 | 20 | 25 | 12 | 12 | 20 | 12 | 7.5 | 85 Ohms | TOP=L2:L3=L2/L4:L6=L5/L7:BOTTOM=L7 |
| PE_TX4_DR10_P | PE_TX4_DR10-DIFF1 | PAIR | 5 | 6.5 | 5 | 10 | 5 | 50 | 20 | 25 | 12 | 12 | 20 | 12 | 7.5 | 85 Ohms | TOP=L2:L3=L2/L4:L6=L5/L7:BOTTOM=L7 |
| PE_TX4_DR10_P | PE_TX4_DR10-DIFF1 | PAIR | 6 | 6.5 | 5 | 10 | 5 | 50 | 20 | 25 | 12 | 12 | 20 | 12 | 7.5 | 85 Ohms | TOP=L2:L3=L2/L4:L6=L5/L7:BOTTOM=L7 |
| PE_TX4_DR10_P | PE_TX4_DR10-DIFF1 | PAIR | 7 | 6.5 | 5 | 10 | 5 | 50 | 20 | 25 | 12 | 12 | 20 | 12 | 7.5 | 85 Ohms | TOP=L2:L3=L2/L4:L6=L5/L7:BOTTOM=L7 |
| PE_TX4_DR10_P | PE_TX4_DR10-DIFF1 | PAIR | 8 | 6.88 | 5 | 10 | 5 | 50 | 20 | 36 | 12 | 12 | 20 | 12 | 5.13 | 85 Ohms | TOP=L2:L3=L2/L4:L6=L5/L7:BOTTOM=L7 |
| PE_TX4_DR11_N | PE_TX4_DR11-DIFF1 | PAIR | 1 | 6.88 | 5 | 10 | 5 | 50 | 20 | 36 | 12 | 12 | 20 | 12 | 5.13 | 85 Ohms | TOP=L2:L3=L2/L4:L6=L5/L7:BOTTOM=L7 |
| PE_TX4_DR11_N | PE_TX4_DR11-DIFF1 | PAIR | 2 | 6.5 | 5 | 10 | 5 | 50 | 20 | 25 | 12 | 12 | 20 | 12 | 7.5 | 85 Ohms | TOP=L2:L3=L2/L4:L6=L5/L7:BOTTOM=L7 |
| PE_TX4_DR11_N | PE_TX4_DR11-DIFF1 | PAIR | 3 | 6.5 | 5 | 10 | 5 | 50 | 20 | 25 | 12 | 12 | 20 | 12 | 7.5 | 85 Ohms | TOP=L2:L3=L2/L4:L6=L5/L7:BOTTOM=L7 |
| PE_TX4_DR11_N | PE_TX4_DR11-DIFF1 | PAIR | 4 | 6.5 | 5 | 10 | 5 | 50 | 20 | 25 | 12 | 12 | 20 | 12 | 7.5 | 85 Ohms | TOP=L2:L3=L2/L4:L6=L5/L7:BOTTOM=L7 |
| PE_TX4_DR11_N | PE_TX4_DR11-DIFF1 | PAIR | 5 | 6.5 | 5 | 10 | 5 | 50 | 20 | 25 | 12 | 12 | 20 | 12 | 7.5 | 85 Ohms | TOP=L2:L3=L2/L4:L6=L5/L7:BOTTOM=L7 |
| PE_TX4_DR11_N | PE_TX4_DR11-DIFF1 | PAIR | 6 | 6.5 | 5 | 10 | 5 | 50 | 20 | 25 | 12 | 12 | 20 | 12 | 7.5 | 85 Ohms | TOP=L2:L3=L2/L4:L6=L5/L7:BOTTOM=L7 |
| PE_TX4_DR11_N | PE_TX4_DR11-DIFF1 | PAIR | 7 | 6.5 | 5 | 10 | 5 | 50 | 20 | 25 | 12 | 12 | 20 | 12 | 7.5 | 85 Ohms | TOP=L2:L3=L2/L4:L6=L5/L7:BOTTOM=L7 |
| PE_TX4_DR11_N | PE_TX4_DR11-DIFF1 | PAIR | 8 | 6.88 | 5 | 10 | 5 | 50 | 20 | 36 | 12 | 12 | 20 | 12 | 5.13 | 85 Ohms | TOP=L2:L3=L2/L4:L6=L5/L7:BOTTOM=L7 |
| PE_TX4_DR11_P | PE_TX4_DR11-DIFF1 | PAIR | 1 | 6.88 | 5 | 10 | 5 | 50 | 20 | 36 | 12 | 12 | 20 | 12 | 5.13 | 85 Ohms | TOP=L2:L3=L2/L4:L6=L5/L7:BOTTOM=L7 |
| PE_TX4_DR11_P | PE_TX4_DR11-DIFF1 | PAIR | 2 | 6.5 | 5 | 10 | 5 | 50 | 20 | 25 | 12 | 12 | 20 | 12 | 7.5 | 85 Ohms | TOP=L2:L3=L2/L4:L6=L5/L7:BOTTOM=L7 |
| PE_TX4_DR11_P | PE_TX4_DR11-DIFF1 | PAIR | 3 | 6.5 | 5 | 10 | 5 | 50 | 20 | 25 | 12 | 12 | 20 | 12 | 7.5 | 85 Ohms | TOP=L2:L3=L2/L4:L6=L5/L7:BOTTOM=L7 |
| PE_TX4_DR11_P | PE_TX4_DR11-DIFF1 | PAIR | 4 | 6.5 | 5 | 10 | 5 | 50 | 20 | 25 | 12 | 12 | 20 | 12 | 7.5 | 85 Ohms | TOP=L2:L3=L2/L4:L6=L5/L7:BOTTOM=L7 |
| PE_TX4_DR11_P | PE_TX4_DR11-DIFF1 | PAIR | 5 | 6.5 | 5 | 10 | 5 | 50 | 20 | 25 | 12 | 12 | 20 | 12 | 7.5 | 85 Ohms | TOP=L2:L3=L2/L4:L6=L5/L7:BOTTOM=L7 |
| PE_TX4_DR11_P | PE_TX4_DR11-DIFF1 | PAIR | 6 | 6.5 | 5 | 10 | 5 | 50 | 20 | 25 | 12 | 12 | 20 | 12 | 7.5 | 85 Ohms | TOP=L2:L3=L2/L4:L6=L5/L7:BOTTOM=L7 |
| PE_TX4_DR11_P | PE_TX4_DR11-DIFF1 | PAIR | 7 | 6.5 | 5 | 10 | 5 | 50 | 20 | 25 | 12 | 12 | 20 | 12 | 7.5 | 85 Ohms | TOP=L2:L3=L2/L4:L6=L5/L7:BOTTOM=L7 |
| PE_TX4_DR11_P | PE_TX4_DR11-DIFF1 | PAIR | 8 | 6.88 | 5 | 10 | 5 | 50 | 20 | 36 | 12 | 12 | 20 | 12 | 5.13 | 85 Ohms | TOP=L2:L3=L2/L4:L6=L5/L7:BOTTOM=L7 |
| PE_TX4_DR12_N | PE_TX4_DR12-DIFF1 | PAIR | 1 | 6.88 | 5 | 10 | 5 | 50 | 20 | 36 | 12 | 12 | 20 | 12 | 5.13 | 85 Ohms | TOP=L2:L3=L2/L4:L6=L5/L7:BOTTOM=L7 |
| PE_TX4_DR12_N | PE_TX4_DR12-DIFF1 | PAIR | 2 | 6.5 | 5 | 10 | 5 | 50 | 20 | 25 | 12 | 12 | 20 | 12 | 7.5 | 85 Ohms | TOP=L2:L3=L2/L4:L6=L5/L7:BOTTOM=L7 |
| PE_TX4_DR12_N | PE_TX4_DR12-DIFF1 | PAIR | 3 | 6.5 | 5 | 10 | 5 | 50 | 20 | 25 | 12 | 12 | 20 | 12 | 7.5 | 85 Ohms | TOP=L2:L3=L2/L4:L6=L5/L7:BOTTOM=L7 |
| PE_TX4_DR12_N | PE_TX4_DR12-DIFF1 | PAIR | 4 | 6.5 | 5 | 10 | 5 | 50 | 20 | 25 | 12 | 12 | 20 | 12 | 7.5 | 85 Ohms | TOP=L2:L3=L2/L4:L6=L5/L7:BOTTOM=L7 |
| PE_TX4_DR12_N | PE_TX4_DR12-DIFF1 | PAIR | 5 | 6.5 | 5 | 10 | 5 | 50 | 20 | 25 | 12 | 12 | 20 | 12 | 7.5 | 85 Ohms | TOP=L2:L3=L2/L4:L6=L5/L7:BOTTOM=L7 |
| PE_TX4_DR12_N | PE_TX4_DR12-DIFF1 | PAIR | 6 | 6.5 | 5 | 10 | 5 | 50 | 20 | 25 | 12 | 12 | 20 | 12 | 7.5 | 85 Ohms | TOP=L2:L3=L2/L4:L6=L5/L7:BOTTOM=L7 |
| PE_TX4_DR12_N | PE_TX4_DR12-DIFF1 | PAIR | 7 | 6.5 | 5 | 10 | 5 | 50 | 20 | 25 | 12 | 12 | 20 | 12 | 7.5 | 85 Ohms | TOP=L2:L3=L2/L4:L6=L5/L7:BOTTOM=L7 |
| PE_TX4_DR12_N | PE_TX4_DR12-DIFF1 | PAIR | 8 | 6.88 | 5 | 10 | 5 | 50 | 20 | 36 | 12 | 12 | 20 | 12 | 5.13 | 85 Ohms | TOP=L2:L3=L2/L4:L6=L5/L7:BOTTOM=L7 |
| PE_TX4_DR12_P | PE_TX4_DR12-DIFF1 | PAIR | 1 | 6.88 | 5 | 10 | 5 | 50 | 20 | 36 | 12 | 12 | 20 | 12 | 5.13 | 85 Ohms | TOP=L2:L3=L2/L4:L6=L5/L7:BOTTOM=L7 |
| PE_TX4_DR12_P | PE_TX4_DR12-DIFF1 | PAIR | 2 | 6.5 | 5 | 10 | 5 | 50 | 20 | 25 | 12 | 12 | 20 | 12 | 7.5 | 85 Ohms | TOP=L2:L3=L2/L4:L6=L5/L7:BOTTOM=L7 |
| PE_TX4_DR12_P | PE_TX4_DR12-DIFF1 | PAIR | 3 | 6.5 | 5 | 10 | 5 | 50 | 20 | 25 | 12 | 12 | 20 | 12 | 7.5 | 85 Ohms | TOP=L2:L3=L2/L4:L6=L5/L7:BOTTOM=L7 |
| PE_TX4_DR12_P | PE_TX4_DR12-DIFF1 | PAIR | 4 | 6.5 | 5 | 10 | 5 | 50 | 20 | 25 | 12 | 12 | 20 | 12 | 7.5 | 85 Ohms | TOP=L2:L3=L2/L4:L6=L5/L7:BOTTOM=L7 |
| PE_TX4_DR12_P | PE_TX4_DR12-DIFF1 | PAIR | 5 | 6.5 | 5 | 10 | 5 | 50 | 20 | 25 | 12 | 12 | 20 | 12 | 7.5 | 85 Ohms | TOP=L2:L3=L2/L4:L6=L5/L7:BOTTOM=L7 |
| PE_TX4_DR12_P | PE_TX4_DR12-DIFF1 | PAIR | 6 | 6.5 | 5 | 10 | 5 | 50 | 20 | 25 | 12 | 12 | 20 | 12 | 7.5 | 85 Ohms | TOP=L2:L3=L2/L4:L6=L5/L7:BOTTOM=L7 |
| PE_TX4_DR12_P | PE_TX4_DR12-DIFF1 | PAIR | 7 | 6.5 | 5 | 10 | 5 | 50 | 20 | 25 | 12 | 12 | 20 | 12 | 7.5 | 85 Ohms | TOP=L2:L3=L2/L4:L6=L5/L7:BOTTOM=L7 |
| PE_TX4_DR12_P | PE_TX4_DR12-DIFF1 | PAIR | 8 | 6.88 | 5 | 10 | 5 | 50 | 20 | 36 | 12 | 12 | 20 | 12 | 5.13 | 85 Ohms | TOP=L2:L3=L2/L4:L6=L5/L7:BOTTOM=L7 |
| PE_TX4_DR13_N | PE_TX4_DR13-DIFF1 | PAIR | 1 | 6.88 | 5 | 10 | 5 | 50 | 20 | 36 | 12 | 12 | 20 | 12 | 5.13 | 85 Ohms | TOP=L2:L3=L2/L4:L6=L5/L7:BOTTOM=L7 |
| PE_TX4_DR13_N | PE_TX4_DR13-DIFF1 | PAIR | 2 | 6.5 | 5 | 10 | 5 | 50 | 20 | 25 | 12 | 12 | 20 | 12 | 7.5 | 85 Ohms | TOP=L2:L3=L2/L4:L6=L5/L7:BOTTOM=L7 |
| PE_TX4_DR13_N | PE_TX4_DR13-DIFF1 | PAIR | 3 | 6.5 | 5 | 10 | 5 | 50 | 20 | 25 | 12 | 12 | 20 | 12 | 7.5 | 85 Ohms | TOP=L2:L3=L2/L4:L6=L5/L7:BOTTOM=L7 |
| PE_TX4_DR13_N | PE_TX4_DR13-DIFF1 | PAIR | 4 | 6.5 | 5 | 10 | 5 | 50 | 20 | 25 | 12 | 12 | 20 | 12 | 7.5 | 85 Ohms | TOP=L2:L3=L2/L4:L6=L5/L7:BOTTOM=L7 |
| PE_TX4_DR13_N | PE_TX4_DR13-DIFF1 | PAIR | 5 | 6.5 | 5 | 10 | 5 | 50 | 20 | 25 | 12 | 12 | 20 | 12 | 7.5 | 85 Ohms | TOP=L2:L3=L2/L4:L6=L5/L7:BOTTOM=L7 |
| PE_TX4_DR13_N | PE_TX4_DR13-DIFF1 | PAIR | 6 | 6.5 | 5 | 10 | 5 | 50 | 20 | 25 | 12 | 12 | 20 | 12 | 7.5 | 85 Ohms | TOP=L2:L3=L2/L4:L6=L5/L7:BOTTOM=L7 |
| PE_TX4_DR13_N | PE_TX4_DR13-DIFF1 | PAIR | 7 | 6.5 | 5 | 10 | 5 | 50 | 20 | 25 | 12 | 12 | 20 | 12 | 7.5 | 85 Ohms | TOP=L2:L3=L2/L4:L6=L5/L7:BOTTOM=L7 |
| PE_TX4_DR13_N | PE_TX4_DR13-DIFF1 | PAIR | 8 | 6.88 | 5 | 10 | 5 | 50 | 20 | 36 | 12 | 12 | 20 | 12 | 5.13 | 85 Ohms | TOP=L2:L3=L2/L4:L6=L5/L7:BOTTOM=L7 |
| PE_TX4_DR13_P | PE_TX4_DR13-DIFF1 | PAIR | 1 | 6.88 | 5 | 10 | 5 | 50 | 20 | 36 | 12 | 12 | 20 | 12 | 5.13 | 85 Ohms | TOP=L2:L3=L2/L4:L6=L5/L7:BOTTOM=L7 |
| PE_TX4_DR13_P | PE_TX4_DR13-DIFF1 | PAIR | 2 | 6.5 | 5 | 10 | 5 | 50 | 20 | 25 | 12 | 12 | 20 | 12 | 7.5 | 85 Ohms | TOP=L2:L3=L2/L4:L6=L5/L7:BOTTOM=L7 |
| PE_TX4_DR13_P | PE_TX4_DR13-DIFF1 | PAIR | 3 | 6.5 | 5 | 10 | 5 | 50 | 20 | 25 | 12 | 12 | 20 | 12 | 7.5 | 85 Ohms | TOP=L2:L3=L2/L4:L6=L5/L7:BOTTOM=L7 |
| PE_TX4_DR13_P | PE_TX4_DR13-DIFF1 | PAIR | 4 | 6.5 | 5 | 10 | 5 | 50 | 20 | 25 | 12 | 12 | 20 | 12 | 7.5 | 85 Ohms | TOP=L2:L3=L2/L4:L6=L5/L7:BOTTOM=L7 |
| PE_TX4_DR13_P | PE_TX4_DR13-DIFF1 | PAIR | 5 | 6.5 | 5 | 10 | 5 | 50 | 20 | 25 | 12 | 12 | 20 | 12 | 7.5 | 85 Ohms | TOP=L2:L3=L2/L4:L6=L5/L7:BOTTOM=L7 |
| PE_TX4_DR13_P | PE_TX4_DR13-DIFF1 | PAIR | 6 | 6.5 | 5 | 10 | 5 | 50 | 20 | 25 | 12 | 12 | 20 | 12 | 7.5 | 85 Ohms | TOP=L2:L3=L2/L4:L6=L5/L7:BOTTOM=L7 |
| PE_TX4_DR13_P | PE_TX4_DR13-DIFF1 | PAIR | 7 | 6.5 | 5 | 10 | 5 | 50 | 20 | 25 | 12 | 12 | 20 | 12 | 7.5 | 85 Ohms | TOP=L2:L3=L2/L4:L6=L5/L7:BOTTOM=L7 |
| PE_TX4_DR13_P | PE_TX4_DR13-DIFF1 | PAIR | 8 | 6.88 | 5 | 10 | 5 | 50 | 20 | 36 | 12 | 12 | 20 | 12 | 5.13 | 85 Ohms | TOP=L2:L3=L2/L4:L6=L5/L7:BOTTOM=L7 |
| PE_TX4_DR14_N | PE_TX4_DR14-DIFF1 | PAIR | 1 | 6.88 | 5 | 10 | 5 | 50 | 20 | 36 | 12 | 12 | 20 | 12 | 5.13 | 85 Ohms | TOP=L2:L3=L2/L4:L6=L5/L7:BOTTOM=L7 |
| PE_TX4_DR14_N | PE_TX4_DR14-DIFF1 | PAIR | 2 | 6.5 | 5 | 10 | 5 | 50 | 20 | 25 | 12 | 12 | 20 | 12 | 7.5 | 85 Ohms | TOP=L2:L3=L2/L4:L6=L5/L7:BOTTOM=L7 |
| PE_TX4_DR14_N | PE_TX4_DR14-DIFF1 | PAIR | 3 | 6.5 | 5 | 10 | 5 | 50 | 20 | 25 | 12 | 12 | 20 | 12 | 7.5 | 85 Ohms | TOP=L2:L3=L2/L4:L6=L5/L7:BOTTOM=L7 |
| PE_TX4_DR14_N | PE_TX4_DR14-DIFF1 | PAIR | 4 | 6.5 | 5 | 10 | 5 | 50 | 20 | 25 | 12 | 12 | 20 | 12 | 7.5 | 85 Ohms | TOP=L2:L3=L2/L4:L6=L5/L7:BOTTOM=L7 |
| PE_TX4_DR14_N | PE_TX4_DR14-DIFF1 | PAIR | 5 | 6.5 | 5 | 10 | 5 | 50 | 20 | 25 | 12 | 12 | 20 | 12 | 7.5 | 85 Ohms | TOP=L2:L3=L2/L4:L6=L5/L7:BOTTOM=L7 |
| PE_TX4_DR14_N | PE_TX4_DR14-DIFF1 | PAIR | 6 | 6.5 | 5 | 10 | 5 | 50 | 20 | 25 | 12 | 12 | 20 | 12 | 7.5 | 85 Ohms | TOP=L2:L3=L2/L4:L6=L5/L7:BOTTOM=L7 |
| PE_TX4_DR14_N | PE_TX4_DR14-DIFF1 | PAIR | 7 | 6.5 | 5 | 10 | 5 | 50 | 20 | 25 | 12 | 12 | 20 | 12 | 7.5 | 85 Ohms | TOP=L2:L3=L2/L4:L6=L5/L7:BOTTOM=L7 |
| PE_TX4_DR14_N | PE_TX4_DR14-DIFF1 | PAIR | 8 | 6.88 | 5 | 10 | 5 | 50 | 20 | 36 | 12 | 12 | 20 | 12 | 5.13 | 85 Ohms | TOP=L2:L3=L2/L4:L6=L5/L7:BOTTOM=L7 |
| PE_TX4_DR14_P | PE_TX4_DR14-DIFF1 | PAIR | 1 | 6.88 | 5 | 10 | 5 | 50 | 20 | 36 | 12 | 12 | 20 | 12 | 5.13 | 85 Ohms | TOP=L2:L3=L2/L4:L6=L5/L7:BOTTOM=L7 |
| PE_TX4_DR14_P | PE_TX4_DR14-DIFF1 | PAIR | 2 | 6.5 | 5 | 10 | 5 | 50 | 20 | 25 | 12 | 12 | 20 | 12 | 7.5 | 85 Ohms | TOP=L2:L3=L2/L4:L6=L5/L7:BOTTOM=L7 |
| PE_TX4_DR14_P | PE_TX4_DR14-DIFF1 | PAIR | 3 | 6.5 | 5 | 10 | 5 | 50 | 20 | 25 | 12 | 12 | 20 | 12 | 7.5 | 85 Ohms | TOP=L2:L3=L2/L4:L6=L5/L7:BOTTOM=L7 |
| PE_TX4_DR14_P | PE_TX4_DR14-DIFF1 | PAIR | 4 | 6.5 | 5 | 10 | 5 | 50 | 20 | 25 | 12 | 12 | 20 | 12 | 7.5 | 85 Ohms | TOP=L2:L3=L2/L4:L6=L5/L7:BOTTOM=L7 |
| PE_TX4_DR14_P | PE_TX4_DR14-DIFF1 | PAIR | 5 | 6.5 | 5 | 10 | 5 | 50 | 20 | 25 | 12 | 12 | 20 | 12 | 7.5 | 85 Ohms | TOP=L2:L3=L2/L4:L6=L5/L7:BOTTOM=L7 |
| PE_TX4_DR14_P | PE_TX4_DR14-DIFF1 | PAIR | 6 | 6.5 | 5 | 10 | 5 | 50 | 20 | 25 | 12 | 12 | 20 | 12 | 7.5 | 85 Ohms | TOP=L2:L3=L2/L4:L6=L5/L7:BOTTOM=L7 |
| PE_TX4_DR14_P | PE_TX4_DR14-DIFF1 | PAIR | 7 | 6.5 | 5 | 10 | 5 | 50 | 20 | 25 | 12 | 12 | 20 | 12 | 7.5 | 85 Ohms | TOP=L2:L3=L2/L4:L6=L5/L7:BOTTOM=L7 |
| PE_TX4_DR14_P | PE_TX4_DR14-DIFF1 | PAIR | 8 | 6.88 | 5 | 10 | 5 | 50 | 20 | 36 | 12 | 12 | 20 | 12 | 5.13 | 85 Ohms | TOP=L2:L3=L2/L4:L6=L5/L7:BOTTOM=L7 |
| PE_TX4_DR1_N | PE_TX4_DR1-DIFF1 | PAIR | 1 | 6.88 | 5 | 10 | 5 | 50 | 20 | 36 | 12 | 12 | 20 | 12 | 5.13 | 85 Ohms | TOP=L2:L3=L2/L4:L6=L5/L7:BOTTOM=L7 |
| PE_TX4_DR1_N | PE_TX4_DR1-DIFF1 | PAIR | 2 | 6.5 | 5 | 10 | 5 | 50 | 20 | 25 | 12 | 12 | 20 | 12 | 7.5 | 85 Ohms | TOP=L2:L3=L2/L4:L6=L5/L7:BOTTOM=L7 |
| PE_TX4_DR1_N | PE_TX4_DR1-DIFF1 | PAIR | 3 | 6.5 | 5 | 10 | 5 | 50 | 20 | 25 | 12 | 12 | 20 | 12 | 7.5 | 85 Ohms | TOP=L2:L3=L2/L4:L6=L5/L7:BOTTOM=L7 |
| PE_TX4_DR1_N | PE_TX4_DR1-DIFF1 | PAIR | 4 | 6.5 | 5 | 10 | 5 | 50 | 20 | 25 | 12 | 12 | 20 | 12 | 7.5 | 85 Ohms | TOP=L2:L3=L2/L4:L6=L5/L7:BOTTOM=L7 |
| PE_TX4_DR1_N | PE_TX4_DR1-DIFF1 | PAIR | 5 | 6.5 | 5 | 10 | 5 | 50 | 20 | 25 | 12 | 12 | 20 | 12 | 7.5 | 85 Ohms | TOP=L2:L3=L2/L4:L6=L5/L7:BOTTOM=L7 |
| PE_TX4_DR1_N | PE_TX4_DR1-DIFF1 | PAIR | 6 | 6.5 | 5 | 10 | 5 | 50 | 20 | 25 | 12 | 12 | 20 | 12 | 7.5 | 85 Ohms | TOP=L2:L3=L2/L4:L6=L5/L7:BOTTOM=L7 |
| PE_TX4_DR1_N | PE_TX4_DR1-DIFF1 | PAIR | 7 | 6.5 | 5 | 10 | 5 | 50 | 20 | 25 | 12 | 12 | 20 | 12 | 7.5 | 85 Ohms | TOP=L2:L3=L2/L4:L6=L5/L7:BOTTOM=L7 |
| PE_TX4_DR1_N | PE_TX4_DR1-DIFF1 | PAIR | 8 | 6.88 | 5 | 10 | 5 | 50 | 20 | 36 | 12 | 12 | 20 | 12 | 5.13 | 85 Ohms | TOP=L2:L3=L2/L4:L6=L5/L7:BOTTOM=L7 |
| PE_TX4_DR1_P | PE_TX4_DR1-DIFF1 | PAIR | 1 | 6.88 | 5 | 10 | 5 | 50 | 20 | 36 | 12 | 12 | 20 | 12 | 5.13 | 85 Ohms | TOP=L2:L3=L2/L4:L6=L5/L7:BOTTOM=L7 |
| PE_TX4_DR1_P | PE_TX4_DR1-DIFF1 | PAIR | 2 | 6.5 | 5 | 10 | 5 | 50 | 20 | 25 | 12 | 12 | 20 | 12 | 7.5 | 85 Ohms | TOP=L2:L3=L2/L4:L6=L5/L7:BOTTOM=L7 |
| PE_TX4_DR1_P | PE_TX4_DR1-DIFF1 | PAIR | 3 | 6.5 | 5 | 10 | 5 | 50 | 20 | 25 | 12 | 12 | 20 | 12 | 7.5 | 85 Ohms | TOP=L2:L3=L2/L4:L6=L5/L7:BOTTOM=L7 |
| PE_TX4_DR1_P | PE_TX4_DR1-DIFF1 | PAIR | 4 | 6.5 | 5 | 10 | 5 | 50 | 20 | 25 | 12 | 12 | 20 | 12 | 7.5 | 85 Ohms | TOP=L2:L3=L2/L4:L6=L5/L7:BOTTOM=L7 |
| PE_TX4_DR1_P | PE_TX4_DR1-DIFF1 | PAIR | 5 | 6.5 | 5 | 10 | 5 | 50 | 20 | 25 | 12 | 12 | 20 | 12 | 7.5 | 85 Ohms | TOP=L2:L3=L2/L4:L6=L5/L7:BOTTOM=L7 |
| PE_TX4_DR1_P | PE_TX4_DR1-DIFF1 | PAIR | 6 | 6.5 | 5 | 10 | 5 | 50 | 20 | 25 | 12 | 12 | 20 | 12 | 7.5 | 85 Ohms | TOP=L2:L3=L2/L4:L6=L5/L7:BOTTOM=L7 |
| PE_TX4_DR1_P | PE_TX4_DR1-DIFF1 | PAIR | 7 | 6.5 | 5 | 10 | 5 | 50 | 20 | 25 | 12 | 12 | 20 | 12 | 7.5 | 85 Ohms | TOP=L2:L3=L2/L4:L6=L5/L7:BOTTOM=L7 |
| PE_TX4_DR1_P | PE_TX4_DR1-DIFF1 | PAIR | 8 | 6.88 | 5 | 10 | 5 | 50 | 20 | 36 | 12 | 12 | 20 | 12 | 5.13 | 85 Ohms | TOP=L2:L3=L2/L4:L6=L5/L7:BOTTOM=L7 |
| PE_TX4_DR2_N | PE_TX4_DR2-DIFF1 | PAIR | 1 | 6.88 | 5 | 10 | 5 | 50 | 20 | 36 | 12 | 12 | 20 | 12 | 5.13 | 85 Ohms | TOP=L2:L3=L2/L4:L6=L5/L7:BOTTOM=L7 |
| PE_TX4_DR2_N | PE_TX4_DR2-DIFF1 | PAIR | 2 | 6.5 | 5 | 10 | 5 | 50 | 20 | 25 | 12 | 12 | 20 | 12 | 7.5 | 85 Ohms | TOP=L2:L3=L2/L4:L6=L5/L7:BOTTOM=L7 |
| PE_TX4_DR2_N | PE_TX4_DR2-DIFF1 | PAIR | 3 | 6.5 | 5 | 10 | 5 | 50 | 20 | 25 | 12 | 12 | 20 | 12 | 7.5 | 85 Ohms | TOP=L2:L3=L2/L4:L6=L5/L7:BOTTOM=L7 |
| PE_TX4_DR2_N | PE_TX4_DR2-DIFF1 | PAIR | 4 | 6.5 | 5 | 10 | 5 | 50 | 20 | 25 | 12 | 12 | 20 | 12 | 7.5 | 85 Ohms | TOP=L2:L3=L2/L4:L6=L5/L7:BOTTOM=L7 |
| PE_TX4_DR2_N | PE_TX4_DR2-DIFF1 | PAIR | 5 | 6.5 | 5 | 10 | 5 | 50 | 20 | 25 | 12 | 12 | 20 | 12 | 7.5 | 85 Ohms | TOP=L2:L3=L2/L4:L6=L5/L7:BOTTOM=L7 |
| PE_TX4_DR2_N | PE_TX4_DR2-DIFF1 | PAIR | 6 | 6.5 | 5 | 10 | 5 | 50 | 20 | 25 | 12 | 12 | 20 | 12 | 7.5 | 85 Ohms | TOP=L2:L3=L2/L4:L6=L5/L7:BOTTOM=L7 |
| PE_TX4_DR2_N | PE_TX4_DR2-DIFF1 | PAIR | 7 | 6.5 | 5 | 10 | 5 | 50 | 20 | 25 | 12 | 12 | 20 | 12 | 7.5 | 85 Ohms | TOP=L2:L3=L2/L4:L6=L5/L7:BOTTOM=L7 |
| PE_TX4_DR2_N | PE_TX4_DR2-DIFF1 | PAIR | 8 | 6.88 | 5 | 10 | 5 | 50 | 20 | 36 | 12 | 12 | 20 | 12 | 5.13 | 85 Ohms | TOP=L2:L3=L2/L4:L6=L5/L7:BOTTOM=L7 |
| PE_TX4_DR2_P | PE_TX4_DR2-DIFF1 | PAIR | 1 | 6.88 | 5 | 10 | 5 | 50 | 20 | 36 | 12 | 12 | 20 | 12 | 5.13 | 85 Ohms | TOP=L2:L3=L2/L4:L6=L5/L7:BOTTOM=L7 |
| PE_TX4_DR2_P | PE_TX4_DR2-DIFF1 | PAIR | 2 | 6.5 | 5 | 10 | 5 | 50 | 20 | 25 | 12 | 12 | 20 | 12 | 7.5 | 85 Ohms | TOP=L2:L3=L2/L4:L6=L5/L7:BOTTOM=L7 |
| PE_TX4_DR2_P | PE_TX4_DR2-DIFF1 | PAIR | 3 | 6.5 | 5 | 10 | 5 | 50 | 20 | 25 | 12 | 12 | 20 | 12 | 7.5 | 85 Ohms | TOP=L2:L3=L2/L4:L6=L5/L7:BOTTOM=L7 |
| PE_TX4_DR2_P | PE_TX4_DR2-DIFF1 | PAIR | 4 | 6.5 | 5 | 10 | 5 | 50 | 20 | 25 | 12 | 12 | 20 | 12 | 7.5 | 85 Ohms | TOP=L2:L3=L2/L4:L6=L5/L7:BOTTOM=L7 |
| PE_TX4_DR2_P | PE_TX4_DR2-DIFF1 | PAIR | 5 | 6.5 | 5 | 10 | 5 | 50 | 20 | 25 | 12 | 12 | 20 | 12 | 7.5 | 85 Ohms | TOP=L2:L3=L2/L4:L6=L5/L7:BOTTOM=L7 |
| PE_TX4_DR2_P | PE_TX4_DR2-DIFF1 | PAIR | 6 | 6.5 | 5 | 10 | 5 | 50 | 20 | 25 | 12 | 12 | 20 | 12 | 7.5 | 85 Ohms | TOP=L2:L3=L2/L4:L6=L5/L7:BOTTOM=L7 |
| PE_TX4_DR2_P | PE_TX4_DR2-DIFF1 | PAIR | 7 | 6.5 | 5 | 10 | 5 | 50 | 20 | 25 | 12 | 12 | 20 | 12 | 7.5 | 85 Ohms | TOP=L2:L3=L2/L4:L6=L5/L7:BOTTOM=L7 |
| PE_TX4_DR2_P | PE_TX4_DR2-DIFF1 | PAIR | 8 | 6.88 | 5 | 10 | 5 | 50 | 20 | 36 | 12 | 12 | 20 | 12 | 5.13 | 85 Ohms | TOP=L2:L3=L2/L4:L6=L5/L7:BOTTOM=L7 |
| PE_TX4_DR3_N | PE_TX4_DR3-DIFF1 | PAIR | 1 | 6.88 | 5 | 10 | 5 | 50 | 20 | 36 | 12 | 12 | 20 | 12 | 5.13 | 85 Ohms | TOP=L2:L3=L2/L4:L6=L5/L7:BOTTOM=L7 |
| PE_TX4_DR3_N | PE_TX4_DR3-DIFF1 | PAIR | 2 | 6.5 | 5 | 10 | 5 | 50 | 20 | 25 | 12 | 12 | 20 | 12 | 7.5 | 85 Ohms | TOP=L2:L3=L2/L4:L6=L5/L7:BOTTOM=L7 |
| PE_TX4_DR3_N | PE_TX4_DR3-DIFF1 | PAIR | 3 | 6.5 | 5 | 10 | 5 | 50 | 20 | 25 | 12 | 12 | 20 | 12 | 7.5 | 85 Ohms | TOP=L2:L3=L2/L4:L6=L5/L7:BOTTOM=L7 |
| PE_TX4_DR3_N | PE_TX4_DR3-DIFF1 | PAIR | 4 | 6.5 | 5 | 10 | 5 | 50 | 20 | 25 | 12 | 12 | 20 | 12 | 7.5 | 85 Ohms | TOP=L2:L3=L2/L4:L6=L5/L7:BOTTOM=L7 |
| PE_TX4_DR3_N | PE_TX4_DR3-DIFF1 | PAIR | 5 | 6.5 | 5 | 10 | 5 | 50 | 20 | 25 | 12 | 12 | 20 | 12 | 7.5 | 85 Ohms | TOP=L2:L3=L2/L4:L6=L5/L7:BOTTOM=L7 |
| PE_TX4_DR3_N | PE_TX4_DR3-DIFF1 | PAIR | 6 | 6.5 | 5 | 10 | 5 | 50 | 20 | 25 | 12 | 12 | 20 | 12 | 7.5 | 85 Ohms | TOP=L2:L3=L2/L4:L6=L5/L7:BOTTOM=L7 |
| PE_TX4_DR3_N | PE_TX4_DR3-DIFF1 | PAIR | 7 | 6.5 | 5 | 10 | 5 | 50 | 20 | 25 | 12 | 12 | 20 | 12 | 7.5 | 85 Ohms | TOP=L2:L3=L2/L4:L6=L5/L7:BOTTOM=L7 |
| PE_TX4_DR3_N | PE_TX4_DR3-DIFF1 | PAIR | 8 | 6.88 | 5 | 10 | 5 | 50 | 20 | 36 | 12 | 12 | 20 | 12 | 5.13 | 85 Ohms | TOP=L2:L3=L2/L4:L6=L5/L7:BOTTOM=L7 |
| PE_TX4_DR3_P | PE_TX4_DR3-DIFF1 | PAIR | 1 | 6.88 | 5 | 10 | 5 | 50 | 20 | 36 | 12 | 12 | 20 | 12 | 5.13 | 85 Ohms | TOP=L2:L3=L2/L4:L6=L5/L7:BOTTOM=L7 |
| PE_TX4_DR3_P | PE_TX4_DR3-DIFF1 | PAIR | 2 | 6.5 | 5 | 10 | 5 | 50 | 20 | 25 | 12 | 12 | 20 | 12 | 7.5 | 85 Ohms | TOP=L2:L3=L2/L4:L6=L5/L7:BOTTOM=L7 |
| PE_TX4_DR3_P | PE_TX4_DR3-DIFF1 | PAIR | 3 | 6.5 | 5 | 10 | 5 | 50 | 20 | 25 | 12 | 12 | 20 | 12 | 7.5 | 85 Ohms | TOP=L2:L3=L2/L4:L6=L5/L7:BOTTOM=L7 |
| PE_TX4_DR3_P | PE_TX4_DR3-DIFF1 | PAIR | 4 | 6.5 | 5 | 10 | 5 | 50 | 20 | 25 | 12 | 12 | 20 | 12 | 7.5 | 85 Ohms | TOP=L2:L3=L2/L4:L6=L5/L7:BOTTOM=L7 |
| PE_TX4_DR3_P | PE_TX4_DR3-DIFF1 | PAIR | 5 | 6.5 | 5 | 10 | 5 | 50 | 20 | 25 | 12 | 12 | 20 | 12 | 7.5 | 85 Ohms | TOP=L2:L3=L2/L4:L6=L5/L7:BOTTOM=L7 |
| PE_TX4_DR3_P | PE_TX4_DR3-DIFF1 | PAIR | 6 | 6.5 | 5 | 10 | 5 | 50 | 20 | 25 | 12 | 12 | 20 | 12 | 7.5 | 85 Ohms | TOP=L2:L3=L2/L4:L6=L5/L7:BOTTOM=L7 |
| PE_TX4_DR3_P | PE_TX4_DR3-DIFF1 | PAIR | 7 | 6.5 | 5 | 10 | 5 | 50 | 20 | 25 | 12 | 12 | 20 | 12 | 7.5 | 85 Ohms | TOP=L2:L3=L2/L4:L6=L5/L7:BOTTOM=L7 |
| PE_TX4_DR3_P | PE_TX4_DR3-DIFF1 | PAIR | 8 | 6.88 | 5 | 10 | 5 | 50 | 20 | 36 | 12 | 12 | 20 | 12 | 5.13 | 85 Ohms | TOP=L2:L3=L2/L4:L6=L5/L7:BOTTOM=L7 |
| PE_TX4_DR4_N | PE_TX4_DR4-DIFF1 | PAIR | 1 | 6.88 | 5 | 10 | 5 | 50 | 20 | 36 | 12 | 12 | 20 | 12 | 5.13 | 85 Ohms | TOP=L2:L3=L2/L4:L6=L5/L7:BOTTOM=L7 |
| PE_TX4_DR4_N | PE_TX4_DR4-DIFF1 | PAIR | 2 | 6.5 | 5 | 10 | 5 | 50 | 20 | 25 | 12 | 12 | 20 | 12 | 7.5 | 85 Ohms | TOP=L2:L3=L2/L4:L6=L5/L7:BOTTOM=L7 |
| PE_TX4_DR4_N | PE_TX4_DR4-DIFF1 | PAIR | 3 | 6.5 | 5 | 10 | 5 | 50 | 20 | 25 | 12 | 12 | 20 | 12 | 7.5 | 85 Ohms | TOP=L2:L3=L2/L4:L6=L5/L7:BOTTOM=L7 |
| PE_TX4_DR4_N | PE_TX4_DR4-DIFF1 | PAIR | 4 | 6.5 | 5 | 10 | 5 | 50 | 20 | 25 | 12 | 12 | 20 | 12 | 7.5 | 85 Ohms | TOP=L2:L3=L2/L4:L6=L5/L7:BOTTOM=L7 |
| PE_TX4_DR4_N | PE_TX4_DR4-DIFF1 | PAIR | 5 | 6.5 | 5 | 10 | 5 | 50 | 20 | 25 | 12 | 12 | 20 | 12 | 7.5 | 85 Ohms | TOP=L2:L3=L2/L4:L6=L5/L7:BOTTOM=L7 |
| PE_TX4_DR4_N | PE_TX4_DR4-DIFF1 | PAIR | 6 | 6.5 | 5 | 10 | 5 | 50 | 20 | 25 | 12 | 12 | 20 | 12 | 7.5 | 85 Ohms | TOP=L2:L3=L2/L4:L6=L5/L7:BOTTOM=L7 |
| PE_TX4_DR4_N | PE_TX4_DR4-DIFF1 | PAIR | 7 | 6.5 | 5 | 10 | 5 | 50 | 20 | 25 | 12 | 12 | 20 | 12 | 7.5 | 85 Ohms | TOP=L2:L3=L2/L4:L6=L5/L7:BOTTOM=L7 |
| PE_TX4_DR4_N | PE_TX4_DR4-DIFF1 | PAIR | 8 | 6.88 | 5 | 10 | 5 | 50 | 20 | 36 | 12 | 12 | 20 | 12 | 5.13 | 85 Ohms | TOP=L2:L3=L2/L4:L6=L5/L7:BOTTOM=L7 |
| PE_TX4_DR4_P | PE_TX4_DR4-DIFF1 | PAIR | 1 | 6.88 | 5 | 10 | 5 | 50 | 20 | 36 | 12 | 12 | 20 | 12 | 5.13 | 85 Ohms | TOP=L2:L3=L2/L4:L6=L5/L7:BOTTOM=L7 |
| PE_TX4_DR4_P | PE_TX4_DR4-DIFF1 | PAIR | 2 | 6.5 | 5 | 10 | 5 | 50 | 20 | 25 | 12 | 12 | 20 | 12 | 7.5 | 85 Ohms | TOP=L2:L3=L2/L4:L6=L5/L7:BOTTOM=L7 |
| PE_TX4_DR4_P | PE_TX4_DR4-DIFF1 | PAIR | 3 | 6.5 | 5 | 10 | 5 | 50 | 20 | 25 | 12 | 12 | 20 | 12 | 7.5 | 85 Ohms | TOP=L2:L3=L2/L4:L6=L5/L7:BOTTOM=L7 |
| PE_TX4_DR4_P | PE_TX4_DR4-DIFF1 | PAIR | 4 | 6.5 | 5 | 10 | 5 | 50 | 20 | 25 | 12 | 12 | 20 | 12 | 7.5 | 85 Ohms | TOP=L2:L3=L2/L4:L6=L5/L7:BOTTOM=L7 |
| PE_TX4_DR4_P | PE_TX4_DR4-DIFF1 | PAIR | 5 | 6.5 | 5 | 10 | 5 | 50 | 20 | 25 | 12 | 12 | 20 | 12 | 7.5 | 85 Ohms | TOP=L2:L3=L2/L4:L6=L5/L7:BOTTOM=L7 |
| PE_TX4_DR4_P | PE_TX4_DR4-DIFF1 | PAIR | 6 | 6.5 | 5 | 10 | 5 | 50 | 20 | 25 | 12 | 12 | 20 | 12 | 7.5 | 85 Ohms | TOP=L2:L3=L2/L4:L6=L5/L7:BOTTOM=L7 |
| PE_TX4_DR4_P | PE_TX4_DR4-DIFF1 | PAIR | 7 | 6.5 | 5 | 10 | 5 | 50 | 20 | 25 | 12 | 12 | 20 | 12 | 7.5 | 85 Ohms | TOP=L2:L3=L2/L4:L6=L5/L7:BOTTOM=L7 |
| PE_TX4_DR4_P | PE_TX4_DR4-DIFF1 | PAIR | 8 | 6.88 | 5 | 10 | 5 | 50 | 20 | 36 | 12 | 12 | 20 | 12 | 5.13 | 85 Ohms | TOP=L2:L3=L2/L4:L6=L5/L7:BOTTOM=L7 |
| PE_TX4_DR5_N | PE_TX4_DR5-DIFF1 | PAIR | 1 | 6.88 | 5 | 10 | 5 | 50 | 20 | 36 | 12 | 12 | 20 | 12 | 5.13 | 85 Ohms | TOP=L2:L3=L2/L4:L6=L5/L7:BOTTOM=L7 |
| PE_TX4_DR5_N | PE_TX4_DR5-DIFF1 | PAIR | 2 | 6.5 | 5 | 10 | 5 | 50 | 20 | 25 | 12 | 12 | 20 | 12 | 7.5 | 85 Ohms | TOP=L2:L3=L2/L4:L6=L5/L7:BOTTOM=L7 |
| PE_TX4_DR5_N | PE_TX4_DR5-DIFF1 | PAIR | 3 | 6.5 | 5 | 10 | 5 | 50 | 20 | 25 | 12 | 12 | 20 | 12 | 7.5 | 85 Ohms | TOP=L2:L3=L2/L4:L6=L5/L7:BOTTOM=L7 |
| PE_TX4_DR5_N | PE_TX4_DR5-DIFF1 | PAIR | 4 | 6.5 | 5 | 10 | 5 | 50 | 20 | 25 | 12 | 12 | 20 | 12 | 7.5 | 85 Ohms | TOP=L2:L3=L2/L4:L6=L5/L7:BOTTOM=L7 |
| PE_TX4_DR5_N | PE_TX4_DR5-DIFF1 | PAIR | 5 | 6.5 | 5 | 10 | 5 | 50 | 20 | 25 | 12 | 12 | 20 | 12 | 7.5 | 85 Ohms | TOP=L2:L3=L2/L4:L6=L5/L7:BOTTOM=L7 |
| PE_TX4_DR5_N | PE_TX4_DR5-DIFF1 | PAIR | 6 | 6.5 | 5 | 10 | 5 | 50 | 20 | 25 | 12 | 12 | 20 | 12 | 7.5 | 85 Ohms | TOP=L2:L3=L2/L4:L6=L5/L7:BOTTOM=L7 |
| PE_TX4_DR5_N | PE_TX4_DR5-DIFF1 | PAIR | 7 | 6.5 | 5 | 10 | 5 | 50 | 20 | 25 | 12 | 12 | 20 | 12 | 7.5 | 85 Ohms | TOP=L2:L3=L2/L4:L6=L5/L7:BOTTOM=L7 |
| PE_TX4_DR5_N | PE_TX4_DR5-DIFF1 | PAIR | 8 | 6.88 | 5 | 10 | 5 | 50 | 20 | 36 | 12 | 12 | 20 | 12 | 5.13 | 85 Ohms | TOP=L2:L3=L2/L4:L6=L5/L7:BOTTOM=L7 |
| PE_TX4_DR5_P | PE_TX4_DR5-DIFF1 | PAIR | 1 | 6.88 | 5 | 10 | 5 | 50 | 20 | 36 | 12 | 12 | 20 | 12 | 5.13 | 85 Ohms | TOP=L2:L3=L2/L4:L6=L5/L7:BOTTOM=L7 |
| PE_TX4_DR5_P | PE_TX4_DR5-DIFF1 | PAIR | 2 | 6.5 | 5 | 10 | 5 | 50 | 20 | 25 | 12 | 12 | 20 | 12 | 7.5 | 85 Ohms | TOP=L2:L3=L2/L4:L6=L5/L7:BOTTOM=L7 |
| PE_TX4_DR5_P | PE_TX4_DR5-DIFF1 | PAIR | 3 | 6.5 | 5 | 10 | 5 | 50 | 20 | 25 | 12 | 12 | 20 | 12 | 7.5 | 85 Ohms | TOP=L2:L3=L2/L4:L6=L5/L7:BOTTOM=L7 |
| PE_TX4_DR5_P | PE_TX4_DR5-DIFF1 | PAIR | 4 | 6.5 | 5 | 10 | 5 | 50 | 20 | 25 | 12 | 12 | 20 | 12 | 7.5 | 85 Ohms | TOP=L2:L3=L2/L4:L6=L5/L7:BOTTOM=L7 |
| PE_TX4_DR5_P | PE_TX4_DR5-DIFF1 | PAIR | 5 | 6.5 | 5 | 10 | 5 | 50 | 20 | 25 | 12 | 12 | 20 | 12 | 7.5 | 85 Ohms | TOP=L2:L3=L2/L4:L6=L5/L7:BOTTOM=L7 |
| PE_TX4_DR5_P | PE_TX4_DR5-DIFF1 | PAIR | 6 | 6.5 | 5 | 10 | 5 | 50 | 20 | 25 | 12 | 12 | 20 | 12 | 7.5 | 85 Ohms | TOP=L2:L3=L2/L4:L6=L5/L7:BOTTOM=L7 |
| PE_TX4_DR5_P | PE_TX4_DR5-DIFF1 | PAIR | 7 | 6.5 | 5 | 10 | 5 | 50 | 20 | 25 | 12 | 12 | 20 | 12 | 7.5 | 85 Ohms | TOP=L2:L3=L2/L4:L6=L5/L7:BOTTOM=L7 |
| PE_TX4_DR5_P | PE_TX4_DR5-DIFF1 | PAIR | 8 | 6.88 | 5 | 10 | 5 | 50 | 20 | 36 | 12 | 12 | 20 | 12 | 5.13 | 85 Ohms | TOP=L2:L3=L2/L4:L6=L5/L7:BOTTOM=L7 |
| PE_TX4_DR6_N | PE_TX4_DR6-DIFF1 | PAIR | 1 | 6.88 | 5 | 10 | 5 | 50 | 20 | 36 | 12 | 12 | 20 | 12 | 5.13 | 85 Ohms | TOP=L2:L3=L2/L4:L6=L5/L7:BOTTOM=L7 |
| PE_TX4_DR6_N | PE_TX4_DR6-DIFF1 | PAIR | 2 | 6.5 | 5 | 10 | 5 | 50 | 20 | 25 | 12 | 12 | 20 | 12 | 7.5 | 85 Ohms | TOP=L2:L3=L2/L4:L6=L5/L7:BOTTOM=L7 |
| PE_TX4_DR6_N | PE_TX4_DR6-DIFF1 | PAIR | 3 | 6.5 | 5 | 10 | 5 | 50 | 20 | 25 | 12 | 12 | 20 | 12 | 7.5 | 85 Ohms | TOP=L2:L3=L2/L4:L6=L5/L7:BOTTOM=L7 |
| PE_TX4_DR6_N | PE_TX4_DR6-DIFF1 | PAIR | 4 | 6.5 | 5 | 10 | 5 | 50 | 20 | 25 | 12 | 12 | 20 | 12 | 7.5 | 85 Ohms | TOP=L2:L3=L2/L4:L6=L5/L7:BOTTOM=L7 |
| PE_TX4_DR6_N | PE_TX4_DR6-DIFF1 | PAIR | 5 | 6.5 | 5 | 10 | 5 | 50 | 20 | 25 | 12 | 12 | 20 | 12 | 7.5 | 85 Ohms | TOP=L2:L3=L2/L4:L6=L5/L7:BOTTOM=L7 |
| PE_TX4_DR6_N | PE_TX4_DR6-DIFF1 | PAIR | 6 | 6.5 | 5 | 10 | 5 | 50 | 20 | 25 | 12 | 12 | 20 | 12 | 7.5 | 85 Ohms | TOP=L2:L3=L2/L4:L6=L5/L7:BOTTOM=L7 |
| PE_TX4_DR6_N | PE_TX4_DR6-DIFF1 | PAIR | 7 | 6.5 | 5 | 10 | 5 | 50 | 20 | 25 | 12 | 12 | 20 | 12 | 7.5 | 85 Ohms | TOP=L2:L3=L2/L4:L6=L5/L7:BOTTOM=L7 |
| PE_TX4_DR6_N | PE_TX4_DR6-DIFF1 | PAIR | 8 | 6.88 | 5 | 10 | 5 | 50 | 20 | 36 | 12 | 12 | 20 | 12 | 5.13 | 85 Ohms | TOP=L2:L3=L2/L4:L6=L5/L7:BOTTOM=L7 |
| PE_TX4_DR6_P | PE_TX4_DR6-DIFF1 | PAIR | 1 | 6.88 | 5 | 10 | 5 | 50 | 20 | 36 | 12 | 12 | 20 | 12 | 5.13 | 85 Ohms | TOP=L2:L3=L2/L4:L6=L5/L7:BOTTOM=L7 |
| PE_TX4_DR6_P | PE_TX4_DR6-DIFF1 | PAIR | 2 | 6.5 | 5 | 10 | 5 | 50 | 20 | 25 | 12 | 12 | 20 | 12 | 7.5 | 85 Ohms | TOP=L2:L3=L2/L4:L6=L5/L7:BOTTOM=L7 |
| PE_TX4_DR6_P | PE_TX4_DR6-DIFF1 | PAIR | 3 | 6.5 | 5 | 10 | 5 | 50 | 20 | 25 | 12 | 12 | 20 | 12 | 7.5 | 85 Ohms | TOP=L2:L3=L2/L4:L6=L5/L7:BOTTOM=L7 |
| PE_TX4_DR6_P | PE_TX4_DR6-DIFF1 | PAIR | 4 | 6.5 | 5 | 10 | 5 | 50 | 20 | 25 | 12 | 12 | 20 | 12 | 7.5 | 85 Ohms | TOP=L2:L3=L2/L4:L6=L5/L7:BOTTOM=L7 |
| PE_TX4_DR6_P | PE_TX4_DR6-DIFF1 | PAIR | 5 | 6.5 | 5 | 10 | 5 | 50 | 20 | 25 | 12 | 12 | 20 | 12 | 7.5 | 85 Ohms | TOP=L2:L3=L2/L4:L6=L5/L7:BOTTOM=L7 |
| PE_TX4_DR6_P | PE_TX4_DR6-DIFF1 | PAIR | 6 | 6.5 | 5 | 10 | 5 | 50 | 20 | 25 | 12 | 12 | 20 | 12 | 7.5 | 85 Ohms | TOP=L2:L3=L2/L4:L6=L5/L7:BOTTOM=L7 |
| PE_TX4_DR6_P | PE_TX4_DR6-DIFF1 | PAIR | 7 | 6.5 | 5 | 10 | 5 | 50 | 20 | 25 | 12 | 12 | 20 | 12 | 7.5 | 85 Ohms | TOP=L2:L3=L2/L4:L6=L5/L7:BOTTOM=L7 |
| PE_TX4_DR6_P | PE_TX4_DR6-DIFF1 | PAIR | 8 | 6.88 | 5 | 10 | 5 | 50 | 20 | 36 | 12 | 12 | 20 | 12 | 5.13 | 85 Ohms | TOP=L2:L3=L2/L4:L6=L5/L7:BOTTOM=L7 |
| PE_TX4_DR7_N | PE_TX4_DR7-DIFF1 | PAIR | 1 | 6.88 | 5 | 10 | 5 | 50 | 20 | 36 | 12 | 12 | 20 | 12 | 5.13 | 85 Ohms | TOP=L2:L3=L2/L4:L6=L5/L7:BOTTOM=L7 |
| PE_TX4_DR7_N | PE_TX4_DR7-DIFF1 | PAIR | 2 | 6.5 | 5 | 10 | 5 | 50 | 20 | 25 | 12 | 12 | 20 | 12 | 7.5 | 85 Ohms | TOP=L2:L3=L2/L4:L6=L5/L7:BOTTOM=L7 |
| PE_TX4_DR7_N | PE_TX4_DR7-DIFF1 | PAIR | 3 | 6.5 | 5 | 10 | 5 | 50 | 20 | 25 | 12 | 12 | 20 | 12 | 7.5 | 85 Ohms | TOP=L2:L3=L2/L4:L6=L5/L7:BOTTOM=L7 |
| PE_TX4_DR7_N | PE_TX4_DR7-DIFF1 | PAIR | 4 | 6.5 | 5 | 10 | 5 | 50 | 20 | 25 | 12 | 12 | 20 | 12 | 7.5 | 85 Ohms | TOP=L2:L3=L2/L4:L6=L5/L7:BOTTOM=L7 |
| PE_TX4_DR7_N | PE_TX4_DR7-DIFF1 | PAIR | 5 | 6.5 | 5 | 10 | 5 | 50 | 20 | 25 | 12 | 12 | 20 | 12 | 7.5 | 85 Ohms | TOP=L2:L3=L2/L4:L6=L5/L7:BOTTOM=L7 |
| PE_TX4_DR7_N | PE_TX4_DR7-DIFF1 | PAIR | 6 | 6.5 | 5 | 10 | 5 | 50 | 20 | 25 | 12 | 12 | 20 | 12 | 7.5 | 85 Ohms | TOP=L2:L3=L2/L4:L6=L5/L7:BOTTOM=L7 |
| PE_TX4_DR7_N | PE_TX4_DR7-DIFF1 | PAIR | 7 | 6.5 | 5 | 10 | 5 | 50 | 20 | 25 | 12 | 12 | 20 | 12 | 7.5 | 85 Ohms | TOP=L2:L3=L2/L4:L6=L5/L7:BOTTOM=L7 |
| PE_TX4_DR7_N | PE_TX4_DR7-DIFF1 | PAIR | 8 | 6.88 | 5 | 10 | 5 | 50 | 20 | 36 | 12 | 12 | 20 | 12 | 5.13 | 85 Ohms | TOP=L2:L3=L2/L4:L6=L5/L7:BOTTOM=L7 |
| PE_TX4_DR7_P | PE_TX4_DR7-DIFF1 | PAIR | 1 | 6.88 | 5 | 10 | 5 | 50 | 20 | 36 | 12 | 12 | 20 | 12 | 5.13 | 85 Ohms | TOP=L2:L3=L2/L4:L6=L5/L7:BOTTOM=L7 |
| PE_TX4_DR7_P | PE_TX4_DR7-DIFF1 | PAIR | 2 | 6.5 | 5 | 10 | 5 | 50 | 20 | 25 | 12 | 12 | 20 | 12 | 7.5 | 85 Ohms | TOP=L2:L3=L2/L4:L6=L5/L7:BOTTOM=L7 |
| PE_TX4_DR7_P | PE_TX4_DR7-DIFF1 | PAIR | 3 | 6.5 | 5 | 10 | 5 | 50 | 20 | 25 | 12 | 12 | 20 | 12 | 7.5 | 85 Ohms | TOP=L2:L3=L2/L4:L6=L5/L7:BOTTOM=L7 |
| PE_TX4_DR7_P | PE_TX4_DR7-DIFF1 | PAIR | 4 | 6.5 | 5 | 10 | 5 | 50 | 20 | 25 | 12 | 12 | 20 | 12 | 7.5 | 85 Ohms | TOP=L2:L3=L2/L4:L6=L5/L7:BOTTOM=L7 |
| PE_TX4_DR7_P | PE_TX4_DR7-DIFF1 | PAIR | 5 | 6.5 | 5 | 10 | 5 | 50 | 20 | 25 | 12 | 12 | 20 | 12 | 7.5 | 85 Ohms | TOP=L2:L3=L2/L4:L6=L5/L7:BOTTOM=L7 |
| PE_TX4_DR7_P | PE_TX4_DR7-DIFF1 | PAIR | 6 | 6.5 | 5 | 10 | 5 | 50 | 20 | 25 | 12 | 12 | 20 | 12 | 7.5 | 85 Ohms | TOP=L2:L3=L2/L4:L6=L5/L7:BOTTOM=L7 |
| PE_TX4_DR7_P | PE_TX4_DR7-DIFF1 | PAIR | 7 | 6.5 | 5 | 10 | 5 | 50 | 20 | 25 | 12 | 12 | 20 | 12 | 7.5 | 85 Ohms | TOP=L2:L3=L2/L4:L6=L5/L7:BOTTOM=L7 |
| PE_TX4_DR7_P | PE_TX4_DR7-DIFF1 | PAIR | 8 | 6.88 | 5 | 10 | 5 | 50 | 20 | 36 | 12 | 12 | 20 | 12 | 5.13 | 85 Ohms | TOP=L2:L3=L2/L4:L6=L5/L7:BOTTOM=L7 |
| PE_TX4_DR8_N | PE_TX4_DR8-DIFF1 | PAIR | 1 | 6.88 | 5 | 10 | 5 | 50 | 20 | 36 | 12 | 12 | 20 | 12 | 5.13 | 85 Ohms | TOP=L2:L3=L2/L4:L6=L5/L7:BOTTOM=L7 |
| PE_TX4_DR8_N | PE_TX4_DR8-DIFF1 | PAIR | 2 | 6.5 | 5 | 10 | 5 | 50 | 20 | 25 | 12 | 12 | 20 | 12 | 7.5 | 85 Ohms | TOP=L2:L3=L2/L4:L6=L5/L7:BOTTOM=L7 |
| PE_TX4_DR8_N | PE_TX4_DR8-DIFF1 | PAIR | 3 | 6.5 | 5 | 10 | 5 | 50 | 20 | 25 | 12 | 12 | 20 | 12 | 7.5 | 85 Ohms | TOP=L2:L3=L2/L4:L6=L5/L7:BOTTOM=L7 |
| PE_TX4_DR8_N | PE_TX4_DR8-DIFF1 | PAIR | 4 | 6.5 | 5 | 10 | 5 | 50 | 20 | 25 | 12 | 12 | 20 | 12 | 7.5 | 85 Ohms | TOP=L2:L3=L2/L4:L6=L5/L7:BOTTOM=L7 |
| PE_TX4_DR8_N | PE_TX4_DR8-DIFF1 | PAIR | 5 | 6.5 | 5 | 10 | 5 | 50 | 20 | 25 | 12 | 12 | 20 | 12 | 7.5 | 85 Ohms | TOP=L2:L3=L2/L4:L6=L5/L7:BOTTOM=L7 |
| PE_TX4_DR8_N | PE_TX4_DR8-DIFF1 | PAIR | 6 | 6.5 | 5 | 10 | 5 | 50 | 20 | 25 | 12 | 12 | 20 | 12 | 7.5 | 85 Ohms | TOP=L2:L3=L2/L4:L6=L5/L7:BOTTOM=L7 |
| PE_TX4_DR8_N | PE_TX4_DR8-DIFF1 | PAIR | 7 | 6.5 | 5 | 10 | 5 | 50 | 20 | 25 | 12 | 12 | 20 | 12 | 7.5 | 85 Ohms | TOP=L2:L3=L2/L4:L6=L5/L7:BOTTOM=L7 |
| PE_TX4_DR8_N | PE_TX4_DR8-DIFF1 | PAIR | 8 | 6.88 | 5 | 10 | 5 | 50 | 20 | 36 | 12 | 12 | 20 | 12 | 5.13 | 85 Ohms | TOP=L2:L3=L2/L4:L6=L5/L7:BOTTOM=L7 |
| PE_TX4_DR8_P | PE_TX4_DR8-DIFF1 | PAIR | 1 | 6.88 | 5 | 10 | 5 | 50 | 20 | 36 | 12 | 12 | 20 | 12 | 5.13 | 85 Ohms | TOP=L2:L3=L2/L4:L6=L5/L7:BOTTOM=L7 |
| PE_TX4_DR8_P | PE_TX4_DR8-DIFF1 | PAIR | 2 | 6.5 | 5 | 10 | 5 | 50 | 20 | 25 | 12 | 12 | 20 | 12 | 7.5 | 85 Ohms | TOP=L2:L3=L2/L4:L6=L5/L7:BOTTOM=L7 |
| PE_TX4_DR8_P | PE_TX4_DR8-DIFF1 | PAIR | 3 | 6.5 | 5 | 10 | 5 | 50 | 20 | 25 | 12 | 12 | 20 | 12 | 7.5 | 85 Ohms | TOP=L2:L3=L2/L4:L6=L5/L7:BOTTOM=L7 |
| PE_TX4_DR8_P | PE_TX4_DR8-DIFF1 | PAIR | 4 | 6.5 | 5 | 10 | 5 | 50 | 20 | 25 | 12 | 12 | 20 | 12 | 7.5 | 85 Ohms | TOP=L2:L3=L2/L4:L6=L5/L7:BOTTOM=L7 |
| PE_TX4_DR8_P | PE_TX4_DR8-DIFF1 | PAIR | 5 | 6.5 | 5 | 10 | 5 | 50 | 20 | 25 | 12 | 12 | 20 | 12 | 7.5 | 85 Ohms | TOP=L2:L3=L2/L4:L6=L5/L7:BOTTOM=L7 |
| PE_TX4_DR8_P | PE_TX4_DR8-DIFF1 | PAIR | 6 | 6.5 | 5 | 10 | 5 | 50 | 20 | 25 | 12 | 12 | 20 | 12 | 7.5 | 85 Ohms | TOP=L2:L3=L2/L4:L6=L5/L7:BOTTOM=L7 |
| PE_TX4_DR8_P | PE_TX4_DR8-DIFF1 | PAIR | 7 | 6.5 | 5 | 10 | 5 | 50 | 20 | 25 | 12 | 12 | 20 | 12 | 7.5 | 85 Ohms | TOP=L2:L3=L2/L4:L6=L5/L7:BOTTOM=L7 |
| PE_TX4_DR8_P | PE_TX4_DR8-DIFF1 | PAIR | 8 | 6.88 | 5 | 10 | 5 | 50 | 20 | 36 | 12 | 12 | 20 | 12 | 5.13 | 85 Ohms | TOP=L2:L3=L2/L4:L6=L5/L7:BOTTOM=L7 |
| PE_TX4_DR9_N | PE_TX4_DR9-DIFF1 | PAIR | 1 | 6.88 | 5 | 10 | 5 | 50 | 20 | 36 | 12 | 12 | 20 | 12 | 5.13 | 85 Ohms | TOP=L2:L3=L2/L4:L6=L5/L7:BOTTOM=L7 |
| PE_TX4_DR9_N | PE_TX4_DR9-DIFF1 | PAIR | 2 | 6.5 | 5 | 10 | 5 | 50 | 20 | 25 | 12 | 12 | 20 | 12 | 7.5 | 85 Ohms | TOP=L2:L3=L2/L4:L6=L5/L7:BOTTOM=L7 |
| PE_TX4_DR9_N | PE_TX4_DR9-DIFF1 | PAIR | 3 | 6.5 | 5 | 10 | 5 | 50 | 20 | 25 | 12 | 12 | 20 | 12 | 7.5 | 85 Ohms | TOP=L2:L3=L2/L4:L6=L5/L7:BOTTOM=L7 |
| PE_TX4_DR9_N | PE_TX4_DR9-DIFF1 | PAIR | 4 | 6.5 | 5 | 10 | 5 | 50 | 20 | 25 | 12 | 12 | 20 | 12 | 7.5 | 85 Ohms | TOP=L2:L3=L2/L4:L6=L5/L7:BOTTOM=L7 |
| PE_TX4_DR9_N | PE_TX4_DR9-DIFF1 | PAIR | 5 | 6.5 | 5 | 10 | 5 | 50 | 20 | 25 | 12 | 12 | 20 | 12 | 7.5 | 85 Ohms | TOP=L2:L3=L2/L4:L6=L5/L7:BOTTOM=L7 |
| PE_TX4_DR9_N | PE_TX4_DR9-DIFF1 | PAIR | 6 | 6.5 | 5 | 10 | 5 | 50 | 20 | 25 | 12 | 12 | 20 | 12 | 7.5 | 85 Ohms | TOP=L2:L3=L2/L4:L6=L5/L7:BOTTOM=L7 |
| PE_TX4_DR9_N | PE_TX4_DR9-DIFF1 | PAIR | 7 | 6.5 | 5 | 10 | 5 | 50 | 20 | 25 | 12 | 12 | 20 | 12 | 7.5 | 85 Ohms | TOP=L2:L3=L2/L4:L6=L5/L7:BOTTOM=L7 |
| PE_TX4_DR9_N | PE_TX4_DR9-DIFF1 | PAIR | 8 | 6.88 | 5 | 10 | 5 | 50 | 20 | 36 | 12 | 12 | 20 | 12 | 5.13 | 85 Ohms | TOP=L2:L3=L2/L4:L6=L5/L7:BOTTOM=L7 |
| PE_TX4_DR9_P | PE_TX4_DR9-DIFF1 | PAIR | 1 | 6.88 | 5 | 10 | 5 | 50 | 20 | 36 | 12 | 12 | 20 | 12 | 5.13 | 85 Ohms | TOP=L2:L3=L2/L4:L6=L5/L7:BOTTOM=L7 |
| PE_TX4_DR9_P | PE_TX4_DR9-DIFF1 | PAIR | 2 | 6.5 | 5 | 10 | 5 | 50 | 20 | 25 | 12 | 12 | 20 | 12 | 7.5 | 85 Ohms | TOP=L2:L3=L2/L4:L6=L5/L7:BOTTOM=L7 |
| PE_TX4_DR9_P | PE_TX4_DR9-DIFF1 | PAIR | 3 | 6.5 | 5 | 10 | 5 | 50 | 20 | 25 | 12 | 12 | 20 | 12 | 7.5 | 85 Ohms | TOP=L2:L3=L2/L4:L6=L5/L7:BOTTOM=L7 |
| PE_TX4_DR9_P | PE_TX4_DR9-DIFF1 | PAIR | 4 | 6.5 | 5 | 10 | 5 | 50 | 20 | 25 | 12 | 12 | 20 | 12 | 7.5 | 85 Ohms | TOP=L2:L3=L2/L4:L6=L5/L7:BOTTOM=L7 |
| PE_TX4_DR9_P | PE_TX4_DR9-DIFF1 | PAIR | 5 | 6.5 | 5 | 10 | 5 | 50 | 20 | 25 | 12 | 12 | 20 | 12 | 7.5 | 85 Ohms | TOP=L2:L3=L2/L4:L6=L5/L7:BOTTOM=L7 |
| PE_TX4_DR9_P | PE_TX4_DR9-DIFF1 | PAIR | 6 | 6.5 | 5 | 10 | 5 | 50 | 20 | 25 | 12 | 12 | 20 | 12 | 7.5 | 85 Ohms | TOP=L2:L3=L2/L4:L6=L5/L7:BOTTOM=L7 |
| PE_TX4_DR9_P | PE_TX4_DR9-DIFF1 | PAIR | 7 | 6.5 | 5 | 10 | 5 | 50 | 20 | 25 | 12 | 12 | 20 | 12 | 7.5 | 85 Ohms | TOP=L2:L3=L2/L4:L6=L5/L7:BOTTOM=L7 |
| PE_TX4_DR9_P | PE_TX4_DR9-DIFF1 | PAIR | 8 | 6.88 | 5 | 10 | 5 | 50 | 20 | 36 | 12 | 12 | 20 | 12 | 5.13 | 85 Ohms | TOP=L2:L3=L2/L4:L6=L5/L7:BOTTOM=L7 |
| SAS_I2C_B_BUF_SCL_R | SAS_I2C_B_BUS_R-DIFF1 | PAIR | 1 | 6.75 | 5 | 10 | 5 | 14 | 6 | 15 | 12 | 12 | 12 | 12 | 15 |  |  |
| SAS_I2C_B_BUF_SCL_R | SAS_I2C_B_BUS_R-DIFF1 | PAIR | 2 | 6 | 5 | 10 | 5 | 14 | 6 | 15 | 12 | 12 | 12 | 12 | 15 |  |  |
| SAS_I2C_B_BUF_SCL_R | SAS_I2C_B_BUS_R-DIFF1 | PAIR | 3 | 6 | 5 | 10 | 5 | 14 | 6 | 15 | 12 | 12 | 12 | 12 | 15 |  |  |
| SAS_I2C_B_BUF_SCL_R | SAS_I2C_B_BUS_R-DIFF1 | PAIR | 4 | 6 | 5 | 10 | 5 | 14 | 6 | 15 | 12 | 12 | 12 | 12 | 15 |  |  |
| SAS_I2C_B_BUF_SCL_R | SAS_I2C_B_BUS_R-DIFF1 | PAIR | 5 | 6 | 5 | 10 | 5 | 14 | 6 | 15 | 12 | 12 | 12 | 12 | 15 |  |  |
| SAS_I2C_B_BUF_SCL_R | SAS_I2C_B_BUS_R-DIFF1 | PAIR | 6 | 6 | 5 | 10 | 5 | 14 | 6 | 15 | 12 | 12 | 12 | 12 | 15 |  |  |
| SAS_I2C_B_BUF_SCL_R | SAS_I2C_B_BUS_R-DIFF1 | PAIR | 7 | 6 | 5 | 10 | 5 | 14 | 6 | 15 | 12 | 12 | 12 | 12 | 15 |  |  |
| SAS_I2C_B_BUF_SCL_R | SAS_I2C_B_BUS_R-DIFF1 | PAIR | 8 | 6.75 | 5 | 10 | 5 | 14 | 6 | 15 | 12 | 12 | 12 | 12 | 15 |  |  |
| SAS_I2C_B_BUF_SDA_R | SAS_I2C_B_BUS_R-DIFF1 | PAIR | 1 | 6.75 | 5 | 10 | 5 | 14 | 6 | 15 | 12 | 12 | 12 | 12 | 15 |  |  |
| SAS_I2C_B_BUF_SDA_R | SAS_I2C_B_BUS_R-DIFF1 | PAIR | 2 | 6 | 5 | 10 | 5 | 14 | 6 | 15 | 12 | 12 | 12 | 12 | 15 |  |  |
| SAS_I2C_B_BUF_SDA_R | SAS_I2C_B_BUS_R-DIFF1 | PAIR | 3 | 6 | 5 | 10 | 5 | 14 | 6 | 15 | 12 | 12 | 12 | 12 | 15 |  |  |
| SAS_I2C_B_BUF_SDA_R | SAS_I2C_B_BUS_R-DIFF1 | PAIR | 4 | 6 | 5 | 10 | 5 | 14 | 6 | 15 | 12 | 12 | 12 | 12 | 15 |  |  |
| SAS_I2C_B_BUF_SDA_R | SAS_I2C_B_BUS_R-DIFF1 | PAIR | 5 | 6 | 5 | 10 | 5 | 14 | 6 | 15 | 12 | 12 | 12 | 12 | 15 |  |  |
| SAS_I2C_B_BUF_SDA_R | SAS_I2C_B_BUS_R-DIFF1 | PAIR | 6 | 6 | 5 | 10 | 5 | 14 | 6 | 15 | 12 | 12 | 12 | 12 | 15 |  |  |
| SAS_I2C_B_BUF_SDA_R | SAS_I2C_B_BUS_R-DIFF1 | PAIR | 7 | 6 | 5 | 10 | 5 | 14 | 6 | 15 | 12 | 12 | 12 | 12 | 15 |  |  |
| SAS_I2C_B_BUF_SDA_R | SAS_I2C_B_BUS_R-DIFF1 | PAIR | 8 | 6.75 | 5 | 10 | 5 | 14 | 6 | 15 | 12 | 12 | 12 | 12 | 15 |  |  |
| SAS_I2C_C_BUF_SCL_R | SAS_I2C_C_BUF_R-DIFF1 | PAIR | 1 | 6.75 | 5 | 10 | 5 | 14 | 6 | 15 | 12 | 12 | 12 | 12 | 15 |  |  |
| SAS_I2C_C_BUF_SCL_R | SAS_I2C_C_BUF_R-DIFF1 | PAIR | 2 | 6 | 5 | 10 | 5 | 14 | 6 | 15 | 12 | 12 | 12 | 12 | 15 |  |  |
| SAS_I2C_C_BUF_SCL_R | SAS_I2C_C_BUF_R-DIFF1 | PAIR | 3 | 6 | 5 | 10 | 5 | 14 | 6 | 15 | 12 | 12 | 12 | 12 | 15 |  |  |
| SAS_I2C_C_BUF_SCL_R | SAS_I2C_C_BUF_R-DIFF1 | PAIR | 4 | 6 | 5 | 10 | 5 | 14 | 6 | 15 | 12 | 12 | 12 | 12 | 15 |  |  |
| SAS_I2C_C_BUF_SCL_R | SAS_I2C_C_BUF_R-DIFF1 | PAIR | 5 | 6 | 5 | 10 | 5 | 14 | 6 | 15 | 12 | 12 | 12 | 12 | 15 |  |  |
| SAS_I2C_C_BUF_SCL_R | SAS_I2C_C_BUF_R-DIFF1 | PAIR | 6 | 6 | 5 | 10 | 5 | 14 | 6 | 15 | 12 | 12 | 12 | 12 | 15 |  |  |
| SAS_I2C_C_BUF_SCL_R | SAS_I2C_C_BUF_R-DIFF1 | PAIR | 7 | 6 | 5 | 10 | 5 | 14 | 6 | 15 | 12 | 12 | 12 | 12 | 15 |  |  |
| SAS_I2C_C_BUF_SCL_R | SAS_I2C_C_BUF_R-DIFF1 | PAIR | 8 | 6.75 | 5 | 10 | 5 | 14 | 6 | 15 | 12 | 12 | 12 | 12 | 15 |  |  |
| SAS_I2C_C_BUF_SDA_R | SAS_I2C_C_BUF_R-DIFF1 | PAIR | 1 | 6.75 | 5 | 10 | 5 | 14 | 6 | 15 | 12 | 12 | 12 | 12 | 15 |  |  |
| SAS_I2C_C_BUF_SDA_R | SAS_I2C_C_BUF_R-DIFF1 | PAIR | 2 | 6 | 5 | 10 | 5 | 14 | 6 | 15 | 12 | 12 | 12 | 12 | 15 |  |  |
| SAS_I2C_C_BUF_SDA_R | SAS_I2C_C_BUF_R-DIFF1 | PAIR | 3 | 6 | 5 | 10 | 5 | 14 | 6 | 15 | 12 | 12 | 12 | 12 | 15 |  |  |
| SAS_I2C_C_BUF_SDA_R | SAS_I2C_C_BUF_R-DIFF1 | PAIR | 4 | 6 | 5 | 10 | 5 | 14 | 6 | 15 | 12 | 12 | 12 | 12 | 15 |  |  |
| SAS_I2C_C_BUF_SDA_R | SAS_I2C_C_BUF_R-DIFF1 | PAIR | 5 | 6 | 5 | 10 | 5 | 14 | 6 | 15 | 12 | 12 | 12 | 12 | 15 |  |  |
| SAS_I2C_C_BUF_SDA_R | SAS_I2C_C_BUF_R-DIFF1 | PAIR | 6 | 6 | 5 | 10 | 5 | 14 | 6 | 15 | 12 | 12 | 12 | 12 | 15 |  |  |
| SAS_I2C_C_BUF_SDA_R | SAS_I2C_C_BUF_R-DIFF1 | PAIR | 7 | 6 | 5 | 10 | 5 | 14 | 6 | 15 | 12 | 12 | 12 | 12 | 15 |  |  |
| SAS_I2C_C_BUF_SDA_R | SAS_I2C_C_BUF_R-DIFF1 | PAIR | 8 | 6.75 | 5 | 10 | 5 | 14 | 6 | 15 | 12 | 12 | 12 | 12 | 15 |  |  |
| P12V_SSD0 | 50OHM_X100MIL_POWER | PWR/GND | 1 | 100 | 5 | 10 | 5 | 14 | 6 | 6 | 12 | 12 | 12 | 12 |  |  |  |
| P12V_SSD1 | 50OHM_X100MIL_POWER | PWR/GND | 1 | 100 | 5 | 10 | 5 | 14 | 6 | 6 | 12 | 12 | 12 | 12 |  |  |  |
| P12V_SSD10 | 50OHM_X100MIL_POWER | PWR/GND | 1 | 100 | 5 | 10 | 5 | 14 | 6 | 6 | 12 | 12 | 12 | 12 |  |  |  |
| P12V_SSD11 | 50OHM_X100MIL_POWER | PWR/GND | 1 | 100 | 5 | 10 | 5 | 14 | 6 | 6 | 12 | 12 | 12 | 12 |  |  |  |
| P12V_SSD12 | 50OHM_X100MIL_POWER | PWR/GND | 1 | 100 | 5 | 10 | 5 | 14 | 6 | 6 | 12 | 12 | 12 | 12 |  |  |  |
| P12V_SSD13 | 50OHM_X100MIL_POWER | PWR/GND | 1 | 100 | 5 | 10 | 5 | 14 | 6 | 6 | 12 | 12 | 12 | 12 |  |  |  |
| P12V_SSD14 | 50OHM_X100MIL_POWER | PWR/GND | 1 | 100 | 5 | 10 | 5 | 14 | 6 | 6 | 12 | 12 | 12 | 12 |  |  |  |
| P12V_SSD2 | 50OHM_X100MIL_POWER | PWR/GND | 1 | 100 | 5 | 10 | 5 | 14 | 6 | 6 | 12 | 12 | 12 | 12 |  |  |  |
| P12V_SSD3 | 50OHM_X100MIL_POWER | PWR/GND | 1 | 100 | 5 | 10 | 5 | 14 | 6 | 6 | 12 | 12 | 12 | 12 |  |  |  |
| P12V_SSD4 | 50OHM_X100MIL_POWER | PWR/GND | 1 | 100 | 5 | 10 | 5 | 14 | 6 | 6 | 12 | 12 | 12 | 12 |  |  |  |
| P12V_SSD5 | 50OHM_X100MIL_POWER | PWR/GND | 1 | 100 | 5 | 10 | 5 | 14 | 6 | 6 | 12 | 12 | 12 | 12 |  |  |  |
| P12V_SSD6 | 50OHM_X100MIL_POWER | PWR/GND | 1 | 100 | 5 | 10 | 5 | 14 | 6 | 6 | 12 | 12 | 12 | 12 |  |  |  |
| P12V_SSD7 | 50OHM_X100MIL_POWER | PWR/GND | 1 | 100 | 5 | 10 | 5 | 14 | 6 | 6 | 12 | 12 | 12 | 12 |  |  |  |
| P12V_SSD8 | 50OHM_X100MIL_POWER | PWR/GND | 1 | 100 | 5 | 10 | 5 | 14 | 6 | 6 | 12 | 12 | 12 | 12 |  |  |  |
| P12V_SSD9 | 50OHM_X100MIL_POWER | PWR/GND | 1 | 100 | 5 | 10 | 5 | 14 | 6 | 6 | 12 | 12 | 12 | 12 |  |  |  |
| P3V3_OUT | 50OHM_X10-160MIL_P2V5-P3V3_OUT | PWR/GND | 1 | 10 | 5 | 10 | 5 | 14 | 6 | 6 | 12 | 12 | 12 | 12 |  |  |  |
| P3V3_SW | 50OHM_X10-160Y20TF20MIL_P2V5-P3V3_SW | PWR/GND | 1 | 10 | 5 | 10 | 5 | 14 | 6 | 20 | 12 | 12 | 20 | 12 |  |  |  |
| AGND_P3V3 | 50OHM_X10MIL_POWER | PWR/GND | 1 | 10 | 5 | 10 | 5 | 14 | 6 | 6 | 12 | 12 | 12 | 12 |  |  |  |
| P3V3_CC | 50OHM_X10MIL_POWER | PWR/GND | 1 | 10 | 5 | 10 | 5 | 14 | 6 | 6 | 12 | 12 | 12 | 12 |  |  |  |
| P3V3_CC_R | 50OHM_X10MIL_POWER | PWR/GND | 1 | 10 | 5 | 10 | 5 | 14 | 6 | 6 | 12 | 12 | 12 | 12 |  |  |  |
| P3V3_EN_R | 50OHM_X10MIL_POWER | PWR/GND | 1 | 10 | 5 | 10 | 5 | 14 | 6 | 6 | 12 | 12 | 12 | 12 |  |  |  |
| P3V3_PG | 50OHM_X10MIL_POWER | PWR/GND | 1 | 10 | 5 | 10 | 5 | 14 | 6 | 6 | 12 | 12 | 12 | 12 |  |  |  |
| P3V3_SS | 50OHM_X10MIL_POWER | PWR/GND | 1 | 10 | 5 | 10 | 5 | 14 | 6 | 6 | 12 | 12 | 12 | 12 |  |  |  |
| P3V3_VFB | 50OHM_X10MIL_POWER | PWR/GND | 1 | 10 | 5 | 10 | 5 | 14 | 6 | 6 | 12 | 12 | 12 | 12 |  |  |  |
| P3V3_VFB_R | 50OHM_X10MIL_POWER | PWR/GND | 1 | 10 | 5 | 10 | 5 | 14 | 6 | 6 | 12 | 12 | 12 | 12 |  |  |  |
| P3V3_VO | 50OHM_X10MIL_POWER | PWR/GND | 1 | 10 | 5 | 10 | 5 | 14 | 6 | 6 | 12 | 12 | 12 | 12 |  |  |  |
| 12V_PRECH_SSD0 | 50OHM_X20MIL_POWER | PWR/GND | 1 | 20 | 5 | 10 | 5 | 14 | 6 | 6 | 12 | 12 | 12 | 12 |  |  |  |
| 12V_PRECH_SSD1 | 50OHM_X20MIL_POWER | PWR/GND | 1 | 20 | 5 | 10 | 5 | 14 | 6 | 6 | 12 | 12 | 12 | 12 |  |  |  |
| 12V_PRECH_SSD10 | 50OHM_X20MIL_POWER | PWR/GND | 1 | 20 | 5 | 10 | 5 | 14 | 6 | 6 | 12 | 12 | 12 | 12 |  |  |  |
| 12V_PRECH_SSD11 | 50OHM_X20MIL_POWER | PWR/GND | 1 | 20 | 5 | 10 | 5 | 14 | 6 | 6 | 12 | 12 | 12 | 12 |  |  |  |
| 12V_PRECH_SSD12 | 50OHM_X20MIL_POWER | PWR/GND | 1 | 20 | 5 | 10 | 5 | 14 | 6 | 6 | 12 | 12 | 12 | 12 |  |  |  |
| 12V_PRECH_SSD13 | 50OHM_X20MIL_POWER | PWR/GND | 1 | 20 | 5 | 10 | 5 | 14 | 6 | 6 | 12 | 12 | 12 | 12 |  |  |  |
| 12V_PRECH_SSD14 | 50OHM_X20MIL_POWER | PWR/GND | 1 | 20 | 5 | 10 | 5 | 14 | 6 | 6 | 12 | 12 | 12 | 12 |  |  |  |
| 12V_PRECH_SSD2 | 50OHM_X20MIL_POWER | PWR/GND | 1 | 20 | 5 | 10 | 5 | 14 | 6 | 6 | 12 | 12 | 12 | 12 |  |  |  |
| 12V_PRECH_SSD3 | 50OHM_X20MIL_POWER | PWR/GND | 1 | 20 | 5 | 10 | 5 | 14 | 6 | 6 | 12 | 12 | 12 | 12 |  |  |  |
| 12V_PRECH_SSD4 | 50OHM_X20MIL_POWER | PWR/GND | 1 | 20 | 5 | 10 | 5 | 14 | 6 | 6 | 12 | 12 | 12 | 12 |  |  |  |
| 12V_PRECH_SSD5 | 50OHM_X20MIL_POWER | PWR/GND | 1 | 20 | 5 | 10 | 5 | 14 | 6 | 6 | 12 | 12 | 12 | 12 |  |  |  |
| 12V_PRECH_SSD6 | 50OHM_X20MIL_POWER | PWR/GND | 1 | 20 | 5 | 10 | 5 | 14 | 6 | 6 | 12 | 12 | 12 | 12 |  |  |  |
| 12V_PRECH_SSD7 | 50OHM_X20MIL_POWER | PWR/GND | 1 | 20 | 5 | 10 | 5 | 14 | 6 | 6 | 12 | 12 | 12 | 12 |  |  |  |
| 12V_PRECH_SSD8 | 50OHM_X20MIL_POWER | PWR/GND | 1 | 20 | 5 | 10 | 5 | 14 | 6 | 6 | 12 | 12 | 12 | 12 |  |  |  |
| 12V_PRECH_SSD9 | 50OHM_X20MIL_POWER | PWR/GND | 1 | 20 | 5 | 10 | 5 | 14 | 6 | 6 | 12 | 12 | 12 | 12 |  |  |  |
| P12V_MOST0_GATE_D | 50OHM_X20MIL_POWER | PWR/GND | 1 | 20 | 5 | 10 | 5 | 14 | 6 | 6 | 12 | 12 | 12 | 12 |  |  |  |
| P12V_MOST1_GATE_D | 50OHM_X20MIL_POWER | PWR/GND | 1 | 20 | 5 | 10 | 5 | 14 | 6 | 6 | 12 | 12 | 12 | 12 |  |  |  |
| P12V_MOST10_GATE_D | 50OHM_X20MIL_POWER | PWR/GND | 1 | 20 | 5 | 10 | 5 | 14 | 6 | 6 | 12 | 12 | 12 | 12 |  |  |  |
| P12V_MOST11_GATE_D | 50OHM_X20MIL_POWER | PWR/GND | 1 | 20 | 5 | 10 | 5 | 14 | 6 | 6 | 12 | 12 | 12 | 12 |  |  |  |
| P12V_MOST12_GATE_D | 50OHM_X20MIL_POWER | PWR/GND | 1 | 20 | 5 | 10 | 5 | 14 | 6 | 6 | 12 | 12 | 12 | 12 |  |  |  |
| P12V_MOST13_GATE_D | 50OHM_X20MIL_POWER | PWR/GND | 1 | 20 | 5 | 10 | 5 | 14 | 6 | 6 | 12 | 12 | 12 | 12 |  |  |  |
| P12V_MOST14_GATE_D | 50OHM_X20MIL_POWER | PWR/GND | 1 | 20 | 5 | 10 | 5 | 14 | 6 | 6 | 12 | 12 | 12 | 12 |  |  |  |
| P12V_MOST2_GATE_D | 50OHM_X20MIL_POWER | PWR/GND | 1 | 20 | 5 | 10 | 5 | 14 | 6 | 6 | 12 | 12 | 12 | 12 |  |  |  |
| P12V_MOST3_GATE_D | 50OHM_X20MIL_POWER | PWR/GND | 1 | 20 | 5 | 10 | 5 | 14 | 6 | 6 | 12 | 12 | 12 | 12 |  |  |  |
| P12V_MOST4_GATE_D | 50OHM_X20MIL_POWER | PWR/GND | 1 | 20 | 5 | 10 | 5 | 14 | 6 | 6 | 12 | 12 | 12 | 12 |  |  |  |
| P12V_MOST5_GATE_D | 50OHM_X20MIL_POWER | PWR/GND | 1 | 20 | 5 | 10 | 5 | 14 | 6 | 6 | 12 | 12 | 12 | 12 |  |  |  |
| P12V_MOST6_GATE_D | 50OHM_X20MIL_POWER | PWR/GND | 1 | 20 | 5 | 10 | 5 | 14 | 6 | 6 | 12 | 12 | 12 | 12 |  |  |  |
| P12V_MOST7_GATE_D | 50OHM_X20MIL_POWER | PWR/GND | 1 | 20 | 5 | 10 | 5 | 14 | 6 | 6 | 12 | 12 | 12 | 12 |  |  |  |
| P12V_MOST8_GATE_D | 50OHM_X20MIL_POWER | PWR/GND | 1 | 20 | 5 | 10 | 5 | 14 | 6 | 6 | 12 | 12 | 12 | 12 |  |  |  |
| P12V_MOST9_GATE_D | 50OHM_X20MIL_POWER | PWR/GND | 1 | 20 | 5 | 10 | 5 | 14 | 6 | 6 | 12 | 12 | 12 | 12 |  |  |  |
| P12V_SENSE | 50OHM_X20MIL_POWER | PWR/GND | 1 | 20 | 5 | 10 | 5 | 14 | 6 | 6 | 12 | 12 | 12 | 12 |  |  |  |
| P12V_SSD14_SENSE | 50OHM_X20MIL_POWER | PWR/GND | 1 | 20 | 5 | 10 | 5 | 14 | 6 | 6 | 12 | 12 | 12 | 12 |  |  |  |
| P3V3_SENSE | 50OHM_X20MIL_POWER | PWR/GND | 1 | 20 | 5 | 10 | 5 | 14 | 6 | 6 | 12 | 12 | 12 | 12 |  |  |  |
| P3V3_VCC | 50OHM_X20MIL_POWER | PWR/GND | 1 | 20 | 5 | 10 | 5 | 14 | 6 | 6 | 12 | 12 | 12 | 12 |  |  |  |
| P3V3_VRG5 | 50OHM_X20MIL_POWER | PWR/GND | 1 | 20 | 5 | 10 | 5 | 14 | 6 | 6 | 12 | 12 | 12 | 12 |  |  |  |
| TPS53312_P3V3_PG | 50OHM_X20MIL_POWER | PWR/GND | 1 | 20 | 5 | 10 | 5 | 14 | 6 | 6 | 12 | 12 | 12 | 12 |  |  |  |
| VDDA_1 | 50OHM_X20MIL_POWER | PWR/GND | 1 | 20 | 5 | 10 | 5 | 14 | 6 | 6 | 12 | 12 | 12 | 12 |  |  |  |
| VDDA_2 | 50OHM_X20MIL_POWER | PWR/GND | 1 | 20 | 5 | 10 | 5 | 14 | 6 | 6 | 12 | 12 | 12 | 12 |  |  |  |
| VDDA_3 | 50OHM_X20MIL_POWER | PWR/GND | 1 | 20 | 5 | 10 | 5 | 14 | 6 | 6 | 12 | 12 | 12 | 12 |  |  |  |
| VDDA_4 | 50OHM_X20MIL_POWER | PWR/GND | 1 | 20 | 5 | 10 | 5 | 14 | 6 | 6 | 12 | 12 | 12 | 12 |  |  |  |
| VDDR_1 | 50OHM_X20MIL_POWER | PWR/GND | 1 | 20 | 5 | 10 | 5 | 14 | 6 | 6 | 12 | 12 | 12 | 12 |  |  |  |
| VDDR_2 | 50OHM_X20MIL_POWER | PWR/GND | 1 | 20 | 5 | 10 | 5 | 14 | 6 | 6 | 12 | 12 | 12 | 12 |  |  |  |
| VDDR_3 | 50OHM_X20MIL_POWER | PWR/GND | 1 | 20 | 5 | 10 | 5 | 14 | 6 | 6 | 12 | 12 | 12 | 12 |  |  |  |
| VDDR_4 | 50OHM_X20MIL_POWER | PWR/GND | 1 | 20 | 5 | 10 | 5 | 14 | 6 | 6 | 12 | 12 | 12 | 12 |  |  |  |
| P3V3_SNB | 50OHM_X20Y20TF20MIL_POWER | PWR/GND | 1 | 20 | 5 | 10 | 5 | 14 | 6 | 20 | 12 | 12 | 20 | 12 |  |  |  |
| P3V3_VBST | 50OHM_X20Y20TF20MIL_POWER | PWR/GND | 1 | 20 | 5 | 10 | 5 | 14 | 6 | 20 | 12 | 12 | 20 | 12 |  |  |  |
| P3V3_VBST_RR | 50OHM_X20Y20TF20MIL_POWER | PWR/GND | 1 | 20 | 5 | 10 | 5 | 14 | 6 | 20 | 12 | 12 | 20 | 12 |  |  |  |
| VDD_DIFF_1 | 50OHM_X40MIL_POWER | PWR/GND | 1 | 40 | 5 | 10 | 5 | 14 | 6 | 6 | 12 | 12 | 12 | 12 |  |  |  |
| VDD_DIFF_2 | 50OHM_X40MIL_POWER | PWR/GND | 1 | 40 | 5 | 10 | 5 | 14 | 6 | 6 | 12 | 12 | 12 | 12 |  |  |  |
| VDD_DIFF_3 | 50OHM_X40MIL_POWER | PWR/GND | 1 | 40 | 5 | 10 | 5 | 14 | 6 | 6 | 12 | 12 | 12 | 12 |  |  |  |
| VDD_DIFF_4 | 50OHM_X40MIL_POWER | PWR/GND | 1 | 40 | 5 | 10 | 5 | 14 | 6 | 6 | 12 | 12 | 12 | 12 |  |  |  |
| VDD_IO_1 | 50OHM_X40MIL_POWER | PWR/GND | 1 | 40 | 5 | 10 | 5 | 14 | 6 | 6 | 12 | 12 | 12 | 12 |  |  |  |
| VDD_IO_2 | 50OHM_X40MIL_POWER | PWR/GND | 1 | 40 | 5 | 10 | 5 | 14 | 6 | 6 | 12 | 12 | 12 | 12 |  |  |  |
| VDD_IO_3 | 50OHM_X40MIL_POWER | PWR/GND | 1 | 40 | 5 | 10 | 5 | 14 | 6 | 6 | 12 | 12 | 12 | 12 |  |  |  |
| VDD_IO_4 | 50OHM_X40MIL_POWER | PWR/GND | 1 | 40 | 5 | 10 | 5 | 14 | 6 | 6 | 12 | 12 | 12 | 12 |  |  |  |
| P3V3 | 50OHM_X40VT6MIL_P3V3-POWER | PWR/GND | 1 | 40 | 5 | 10 | 5 | 14 | 6 | 6 | 12 | 12 | 12 | 12 |  |  |  |
| P12V | 50OHM_X800MIL_POWER | PWR/GND | 1 | 100 | 5 | 10 | 5 | 14 | 6 | 6 | 12 | 12 | 12 | 12 |  |  |  |
| P3V3_VIN | 50OHM_X80MIL_POWER | PWR/GND | 1 | 80 | 5 | 10 | 5 | 14 | 6 | 6 | 12 | 12 | 12 | 12 |  |  |  |
| GND | GND_X1000MIL | PWR/GND | 1 | 1000 | 5 | 10 | 5 | 14 | 6 | 6 | 12 | 12 | 12 | 12 |  |  |  |
